( 
	(global
		("VARIANT_NAME" "MPS")
		("VARIANT_VIEW" "schmps_1")
		("VARIANT_DESCRIPTION" "")
	)
	(modules
		"@t6g_mb_lib.t6g(sch_1)"
	)
	(options
		("VARIANT_PROP" "VARIANT")
		("VARIANT_DNI" "DNI")
		("VARIANT_DESIGNATOR" "*")
	)
	(props
		("@t6g_mb_lib.t6g(sch_1):page100_i23@pure_quanta.ina183a1idbvr(chips)"
			("VARIANT" "*")
			("VALUE" "INA183A1IDBVR")
			("PART_TYPE" "SMLF")
			("MATERIAL" "IC")
			("PART_NUMBER" "AL000183000")
			("LOCATION" "U121")
		)
		("@t6g_mb_lib.t6g(sch_1):page100_i24@pure_quanta.ina183a1idbvr(chips)"
			("VARIANT" "*")
			("VALUE" "INA183A1IDBVR")
			("PART_TYPE" "SMLF")
			("MATERIAL" "IC")
			("PART_NUMBER" "AL000183000")
			("LOCATION" "U120")
		)
		("@t6g_mb_lib.t6g(sch_1):page313_i23@pure_quanta.q_cap(chips)"
			("VARIANT" "*")
			("VALUE" "0.1UF")
			("VOLTAGE" "25V")
			("TOLERANCE" "10%")
			("PACK_TYPE" "0402")
			("MATERIAL" "EMPTY")
			("PART_NUMBER" "CH4104K1B00")
			("LOCATION" "PC1370")
		)
		("@t6g_mb_lib.t6g(sch_1):page313_i40@pure_quanta.q_cap(chips)"
			("VARIANT" "*")
			("VALUE" "0.1UF")
			("VOLTAGE" "25V")
			("TOLERANCE" "10%")
			("PACK_TYPE" "0402")
			("MATERIAL" "EMPTY")
			("PART_NUMBER" "CH4104K1B00")
			("LOCATION" "PC1369")
		)
		("@t6g_mb_lib.t6g(sch_1):page295_i23@pure_quanta.q_cap(chips)"
			("VARIANT" "*")
			("VALUE" "0.1UF")
			("VOLTAGE" "25V")
			("TOLERANCE" "10%")
			("PACK_TYPE" "0402")
			("MATERIAL" "EMPTY")
			("PART_NUMBER" "CH4104K1B00")
			("LOCATION" "PC1352")
		)
		("@t6g_mb_lib.t6g(sch_1):page295_i39@pure_quanta.q_cap(chips)"
			("VARIANT" "*")
			("VALUE" "0.1UF")
			("VOLTAGE" "25V")
			("TOLERANCE" "10%")
			("PACK_TYPE" "0402")
			("MATERIAL" "EMPTY")
			("PART_NUMBER" "CH4104K1B00")
			("LOCATION" "PC1351")
		)
		("@t6g_mb_lib.t6g(sch_1):page302_i330@pure_quanta.q_cap(chips)"
			("VARIANT" "*")
			("VALUE" "0.1UF")
			("VOLTAGE" "25V")
			("TOLERANCE" "10%")
			("PACK_TYPE" "0402")
			("MATERIAL" "EMPTY")
			("PART_NUMBER" "CH4104K1B00")
			("LOCATION" "PC1354")
		)
		("@t6g_mb_lib.t6g(sch_1):page294_i29@pure_quanta.q_cap(chips)"
			("VARIANT" "*")
			("VALUE" "0.1UF")
			("VOLTAGE" "25V")
			("TOLERANCE" "10%")
			("PACK_TYPE" "0402")
			("MATERIAL" "EMPTY")
			("PART_NUMBER" "CH4104K1B00")
			("LOCATION" "PC1350")
		)
		("@t6g_mb_lib.t6g(sch_1):page294_i46@pure_quanta.q_cap(chips)"
			("VARIANT" "*")
			("VALUE" "0.1UF")
			("VOLTAGE" "25V")
			("TOLERANCE" "10%")
			("PACK_TYPE" "0402")
			("MATERIAL" "EMPTY")
			("PART_NUMBER" "CH4104K1B00")
			("LOCATION" "PC1349")
		)
		("@t6g_mb_lib.t6g(sch_1):page309_i23@pure_quanta.q_cap(chips)"
			("VARIANT" "*")
			("VALUE" "0.1UF")
			("VOLTAGE" "25V")
			("TOLERANCE" "10%")
			("PACK_TYPE" "0402")
			("MATERIAL" "EMPTY")
			("PART_NUMBER" "CH4104K1B00")
			("LOCATION" "PC1359")
		)
		("@t6g_mb_lib.t6g(sch_1):page309_i8@pure_quanta.q_cap(chips)"
			("VARIANT" "*")
			("VALUE" "0.1UF")
			("VOLTAGE" "25V")
			("TOLERANCE" "10%")
			("PACK_TYPE" "0402")
			("MATERIAL" "EMPTY")
			("PART_NUMBER" "CH4104K1B00")
			("LOCATION" "PC1358")
		)
		("@t6g_mb_lib.t6g(sch_1):page310_i31@pure_quanta.q_cap(chips)"
			("VARIANT" "*")
			("VALUE" "0.1UF")
			("VOLTAGE" "25V")
			("TOLERANCE" "10%")
			("PACK_TYPE" "0402")
			("MATERIAL" "EMPTY")
			("PART_NUMBER" "CH4104K1B00")
			("LOCATION" "PC1361")
		)
		("@t6g_mb_lib.t6g(sch_1):page310_i28@pure_quanta.q_cap(chips)"
			("VARIANT" "*")
			("VALUE" "0.1UF")
			("VOLTAGE" "25V")
			("TOLERANCE" "10%")
			("PACK_TYPE" "0402")
			("MATERIAL" "EMPTY")
			("PART_NUMBER" "CH4104K1B00")
			("LOCATION" "PC1360")
		)
		("@t6g_mb_lib.t6g(sch_1):page311_i31@pure_quanta.q_cap(chips)"
			("VARIANT" "*")
			("VALUE" "0.1UF")
			("VOLTAGE" "25V")
			("TOLERANCE" "10%")
			("PACK_TYPE" "0402")
			("MATERIAL" "EMPTY")
			("PART_NUMBER" "CH4104K1B00")
			("LOCATION" "PC1363")
		)
		("@t6g_mb_lib.t6g(sch_1):page311_i8@pure_quanta.q_cap(chips)"
			("VARIANT" "*")
			("VALUE" "0.1UF")
			("VOLTAGE" "25V")
			("TOLERANCE" "10%")
			("PACK_TYPE" "0402")
			("MATERIAL" "EMPTY")
			("PART_NUMBER" "CH4104K1B00")
			("LOCATION" "PC1362")
		)
		("@t6g_mb_lib.t6g(sch_1):page316_i11@pure_quanta.q_cap(chips)"
			("VARIANT" "*")
			("VALUE" "0.1UF")
			("VOLTAGE" "25V")
			("TOLERANCE" "10%")
			("PACK_TYPE" "0402")
			("MATERIAL" "EMPTY")
			("PART_NUMBER" "CH4104K1B00")
			("LOCATION" "PC1365")
		)
		("@t6g_mb_lib.t6g(sch_1):page316_i24@pure_quanta.q_cap(chips)"
			("VARIANT" "*")
			("VALUE" "0.1UF")
			("VOLTAGE" "25V")
			("TOLERANCE" "10%")
			("PACK_TYPE" "0402")
			("MATERIAL" "EMPTY")
			("PART_NUMBER" "CH4104K1B00")
			("LOCATION" "PC1364")
		)
		("@t6g_mb_lib.t6g(sch_1):page317_i8@pure_quanta.q_cap(chips)"
			("VARIANT" "*")
			("VALUE" "0.1UF")
			("VOLTAGE" "25V")
			("TOLERANCE" "10%")
			("PACK_TYPE" "0402")
			("MATERIAL" "EMPTY")
			("PART_NUMBER" "CH4104K1B00")
			("LOCATION" "PC1366")
		)
		("@t6g_mb_lib.t6g(sch_1):page312_i209@pure_quanta.q_cap(chips)"
			("VARIANT" "*")
			("VALUE" "0.1UF")
			("VOLTAGE" "25V")
			("TOLERANCE" "10%")
			("PACK_TYPE" "0402")
			("MATERIAL" "EMPTY")
			("PART_NUMBER" "CH4104K1B00")
			("LOCATION" "PC1368")
		)
		("@t6g_mb_lib.t6g(sch_1):page312_i231@pure_quanta.q_cap(chips)"
			("VARIANT" "*")
			("VALUE" "0.1UF")
			("VOLTAGE" "25V")
			("TOLERANCE" "10%")
			("PACK_TYPE" "0402")
			("MATERIAL" "EMPTY")
			("PART_NUMBER" "CH4104K1B00")
			("LOCATION" "PC1367")
		)
		("@t6g_mb_lib.t6g(sch_1):page319_i237@pure_quanta.q_cap(chips)"
			("VARIANT" "*")
			("VALUE" "0.1UF")
			("VOLTAGE" "25V")
			("TOLERANCE" "10%")
			("PACK_TYPE" "0402")
			("MATERIAL" "EMPTY")
			("PART_NUMBER" "CH4104K1B00")
			("LOCATION" "PC386")
		)
		("@t6g_mb_lib.t6g(sch_1):page320_i8@pure_quanta.q_cap(chips)"
			("VARIANT" "*")
			("VALUE" "0.1UF")
			("VOLTAGE" "25V")
			("TOLERANCE" "10%")
			("PACK_TYPE" "0402")
			("MATERIAL" "EMPTY")
			("PART_NUMBER" "CH4104K1B00")
			("LOCATION" "PC1371")
		)
		("@t6g_mb_lib.t6g(sch_1):page291_i29@pure_quanta.q_cap(chips)"
			("VARIANT" "*")
			("VALUE" "0.1UF")
			("VOLTAGE" "25V")
			("TOLERANCE" "10%")
			("PACK_TYPE" "0402")
			("MATERIAL" "EMPTY")
			("PART_NUMBER" "CH4104K1B00")
			("LOCATION" "PC1341")
		)
		("@t6g_mb_lib.t6g(sch_1):page291_i13@pure_quanta.q_cap(chips)"
			("VARIANT" "*")
			("VALUE" "0.1UF")
			("VOLTAGE" "25V")
			("TOLERANCE" "10%")
			("PACK_TYPE" "0402")
			("MATERIAL" "EMPTY")
			("PART_NUMBER" "CH4104K1B00")
			("LOCATION" "PC1340")
		)
		("@t6g_mb_lib.t6g(sch_1):page292_i27@pure_quanta.q_cap(chips)"
			("VARIANT" "*")
			("VALUE" "0.1UF")
			("VOLTAGE" "25V")
			("TOLERANCE" "10%")
			("PACK_TYPE" "0402")
			("MATERIAL" "EMPTY")
			("PART_NUMBER" "CH4104K1B00")
			("LOCATION" "PC1343")
		)
		("@t6g_mb_lib.t6g(sch_1):page292_i8@pure_quanta.q_cap(chips)"
			("VARIANT" "*")
			("VALUE" "0.1UF")
			("VOLTAGE" "25V")
			("TOLERANCE" "10%")
			("PACK_TYPE" "0402")
			("MATERIAL" "EMPTY")
			("PART_NUMBER" "CH4104K1B00")
			("LOCATION" "PC1342")
		)
		("@t6g_mb_lib.t6g(sch_1):page293_i28@pure_quanta.q_cap(chips)"
			("VARIANT" "*")
			("VALUE" "0.1UF")
			("VOLTAGE" "25V")
			("TOLERANCE" "10%")
			("PACK_TYPE" "0402")
			("MATERIAL" "EMPTY")
			("PART_NUMBER" "CH4104K1B00")
			("LOCATION" "PC1345")
		)
		("@t6g_mb_lib.t6g(sch_1):page293_i16@pure_quanta.q_cap(chips)"
			("VARIANT" "*")
			("VALUE" "0.1UF")
			("VOLTAGE" "25V")
			("TOLERANCE" "10%")
			("PACK_TYPE" "0402")
			("MATERIAL" "EMPTY")
			("PART_NUMBER" "CH4104K1B00")
			("LOCATION" "PC1344")
		)
		("@t6g_mb_lib.t6g(sch_1):page298_i163@pure_quanta.q_cap(chips)"
			("VARIANT" "*")
			("VALUE" "0.1UF")
			("VOLTAGE" "25V")
			("TOLERANCE" "10%")
			("PACK_TYPE" "0402")
			("MATERIAL" "EMPTY")
			("PART_NUMBER" "CH4104K1B00")
			("LOCATION" "PC1347")
		)
		("@t6g_mb_lib.t6g(sch_1):page298_i152@pure_quanta.q_cap(chips)"
			("VARIANT" "*")
			("VALUE" "0.1UF")
			("VOLTAGE" "25V")
			("TOLERANCE" "10%")
			("PACK_TYPE" "0402")
			("MATERIAL" "EMPTY")
			("PART_NUMBER" "CH4104K1B00")
			("LOCATION" "PC1346")
		)
		("@t6g_mb_lib.t6g(sch_1):page299_i7@pure_quanta.q_cap(chips)"
			("VARIANT" "*")
			("VALUE" "0.1UF")
			("VOLTAGE" "25V")
			("TOLERANCE" "10%")
			("PACK_TYPE" "0402")
			("MATERIAL" "EMPTY")
			("PART_NUMBER" "CH4104K1B00")
			("LOCATION" "PC1348")
		)
		("@t6g_mb_lib.t6g(sch_1):page308_i30@pure_quanta.q_cap(chips)"
			("VARIANT" "*")
			("VALUE" "0.1UF")
			("VOLTAGE" "25V")
			("TOLERANCE" "10%")
			("PACK_TYPE" "0402")
			("MATERIAL" "EMPTY")
			("PART_NUMBER" "CH4104K1B00")
			("LOCATION" "PC1339")
		)
		("@t6g_mb_lib.t6g(sch_1):page308_i10@pure_quanta.q_cap(chips)"
			("VARIANT" "*")
			("VALUE" "0.1UF")
			("VOLTAGE" "25V")
			("TOLERANCE" "10%")
			("PACK_TYPE" "0402")
			("MATERIAL" "EMPTY")
			("PART_NUMBER" "CH4104K1B00")
			("LOCATION" "PC1338")
		)
		("@t6g_mb_lib.t6g(sch_1):page290_i33@pure_quanta.q_cap(chips)"
			("VARIANT" "*")
			("VALUE" "0.1UF")
			("VOLTAGE" "25V")
			("TOLERANCE" "10%")
			("PACK_TYPE" "0402")
			("MATERIAL" "EMPTY")
			("PART_NUMBER" "CH4104K1B00")
			("LOCATION" "PC1356")
		)
		("@t6g_mb_lib.t6g(sch_1):page290_i10@pure_quanta.q_cap(chips)"
			("VARIANT" "*")
			("VALUE" "0.1UF")
			("VOLTAGE" "25V")
			("TOLERANCE" "10%")
			("PACK_TYPE" "0402")
			("MATERIAL" "EMPTY")
			("PART_NUMBER" "CH4104K1B00")
			("LOCATION" "PC1355")
		)
		("@t6g_mb_lib.t6g(sch_1):page301_i13@pure_quanta.q_cap(chips)"
			("VARIANT" "*")
			("VALUE" "0.1UF")
			("VOLTAGE" "25V")
			("TOLERANCE" "10%")
			("PACK_TYPE" "0402")
			("MATERIAL" "EMPTY")
			("PART_NUMBER" "CH4104K1B00")
			("LOCATION" "PC624")
		)
		("@t6g_mb_lib.t6g(sch_1):page315_i64@pure_quanta.q_cap(chips)"
			("VARIANT" "*")
			("VALUE" "3300PF")
			("VOLTAGE" "50V")
			("TOLERANCE" "10%")
			("PACK_TYPE" "C0402")
			("MATERIAL" "EMPTY")
			("PART_NUMBER" "CH2336K1B06")
			("LOCATION" "PC469")
		)
		("@t6g_mb_lib.t6g(sch_1):page315_i65@pure_quanta.q_cap(chips)"
			("VARIANT" "*")
			("VALUE" "3300PF")
			("VOLTAGE" "50V")
			("TOLERANCE" "10%")
			("PACK_TYPE" "C0402")
			("MATERIAL" "EMPTY")
			("PART_NUMBER" "CH2336K1B06")
			("LOCATION" "PC468")
		)
		("@t6g_mb_lib.t6g(sch_1):page307_i240@pure_quanta.q_cap(chips)"
			("VARIANT" "*")
			("VALUE" "3300PF")
			("VOLTAGE" "50V")
			("TOLERANCE" "10%")
			("PACK_TYPE" "C0402")
			("MATERIAL" "EMPTY")
			("PART_NUMBER" "CH2336K1B06")
			("LOCATION" "PC549")
		)
		("@t6g_mb_lib.t6g(sch_1):page307_i219@pure_quanta.q_cap(chips)"
			("VARIANT" "*")
			("VALUE" "3300PF")
			("VOLTAGE" "50V")
			("TOLERANCE" "10%")
			("PACK_TYPE" "C0402")
			("MATERIAL" "EMPTY")
			("PART_NUMBER" "CH2336K1B06")
			("LOCATION" "PC422")
		)
		("@t6g_mb_lib.t6g(sch_1):page319_i248@pure_quanta.q_cap(chips)"
			("VARIANT" "*")
			("VALUE" "3300PF")
			("VOLTAGE" "50V")
			("TOLERANCE" "10%")
			("PACK_TYPE" "C0402")
			("MATERIAL" "EMPTY")
			("PART_NUMBER" "CH2336K1B06")
			("LOCATION" "PC389")
		)
		("@t6g_mb_lib.t6g(sch_1):page289_i245@pure_quanta.q_cap(chips)"
			("VARIANT" "*")
			("VALUE" "3300PF")
			("VOLTAGE" "50V")
			("TOLERANCE" "10%")
			("PACK_TYPE" "C0402")
			("MATERIAL" "EMPTY")
			("PART_NUMBER" "CH2336K1B06")
			("LOCATION" "PC594")
		)
		("@t6g_mb_lib.t6g(sch_1):page289_i247@pure_quanta.q_cap(chips)"
			("VARIANT" "*")
			("VALUE" "3300PF")
			("VOLTAGE" "50V")
			("TOLERANCE" "10%")
			("PACK_TYPE" "C0402")
			("MATERIAL" "EMPTY")
			("PART_NUMBER" "CH2336K1B06")
			("LOCATION" "PC331")
		)
		("@t6g_mb_lib.t6g(sch_1):page297_i46@pure_quanta.q_cap(chips)"
			("VARIANT" "*")
			("VALUE" "3300PF")
			("VOLTAGE" "50V")
			("TOLERANCE" "10%")
			("PACK_TYPE" "C0402")
			("MATERIAL" "EMPTY")
			("PART_NUMBER" "CH2336K1B06")
			("LOCATION" "PC216")
		)
		("@t6g_mb_lib.t6g(sch_1):page297_i47@pure_quanta.q_cap(chips)"
			("VARIANT" "*")
			("VALUE" "3300PF")
			("VOLTAGE" "50V")
			("TOLERANCE" "10%")
			("PACK_TYPE" "C0402")
			("MATERIAL" "EMPTY")
			("PART_NUMBER" "CH2336K1B06")
			("LOCATION" "PC215")
		)
		("@t6g_mb_lib.t6g(sch_1):page301_i18@pure_quanta.q_cap(chips)"
			("VARIANT" "*")
			("VALUE" "3300PF")
			("VOLTAGE" "50V")
			("TOLERANCE" "10%")
			("PACK_TYPE" "C0402")
			("MATERIAL" "EMPTY")
			("PART_NUMBER" "CH2336K1B06")
			("LOCATION" "PC627")
		)
		("@t6g_mb_lib.t6g(sch_1):page315_i80@pure_quanta.q_cap(chips)"
			("VARIANT" "*")
			("VALUE" "4.7UF")
			("VOLTAGE" "6.3V")
			("TOLERANCE" "20%")
			("PACK_TYPE" "0402")
			("MATERIAL" "EMPTY")
			("PART_NUMBER" "CH5471MEB01")
			("LOCATION" "PC477")
		)
		("@t6g_mb_lib.t6g(sch_1):page307_i253@pure_quanta.q_cap(chips)"
			("VARIANT" "*")
			("VALUE" "4.7UF")
			("VOLTAGE" "6.3V")
			("TOLERANCE" "20%")
			("PACK_TYPE" "0402")
			("MATERIAL" "EMPTY")
			("PART_NUMBER" "CH5471MEB01")
			("LOCATION" "PC553")
		)
		("@t6g_mb_lib.t6g(sch_1):page319_i255@pure_quanta.q_cap(chips)"
			("VARIANT" "*")
			("VALUE" "4.7UF")
			("VOLTAGE" "6.3V")
			("TOLERANCE" "20%")
			("PACK_TYPE" "0402")
			("MATERIAL" "EMPTY")
			("PART_NUMBER" "CH5471MEB01")
			("LOCATION" "PC392")
		)
		("@t6g_mb_lib.t6g(sch_1):page289_i317@pure_quanta.q_cap(chips)"
			("VARIANT" "*")
			("VALUE" "4.7UF")
			("VOLTAGE" "6.3V")
			("TOLERANCE" "20%")
			("PACK_TYPE" "0402")
			("MATERIAL" "EMPTY")
			("PART_NUMBER" "CH5471MEB01")
			("LOCATION" "PC335")
		)
		("@t6g_mb_lib.t6g(sch_1):page297_i87@pure_quanta.q_cap(chips)"
			("VARIANT" "*")
			("VALUE" "4.7UF")
			("VOLTAGE" "6.3V")
			("TOLERANCE" "20%")
			("PACK_TYPE" "0402")
			("MATERIAL" "EMPTY")
			("PART_NUMBER" "CH5471MEB01")
			("LOCATION" "PC224")
		)
		("@t6g_mb_lib.t6g(sch_1):page301_i63@pure_quanta.q_cap(chips)"
			("VARIANT" "*")
			("VALUE" "4.7UF")
			("VOLTAGE" "6.3V")
			("TOLERANCE" "20%")
			("PACK_TYPE" "0402")
			("MATERIAL" "EMPTY")
			("PART_NUMBER" "CH5471MEB01")
			("LOCATION" "PC630")
		)
		("@t6g_mb_lib.t6g(sch_1):page315_i68@pure_quanta.q_cap(chips)"
			("VARIANT" "*")
			("VALUE" "0.01UF")
			("VOLTAGE" "25V")
			("TOLERANCE" "10%")
			("PACK_TYPE" "0402")
			("MATERIAL" "X7R")
			("PART_NUMBER" "TMP_QCH31004KB17")
			("LOCATION" "PC1292")
		)
		("@t6g_mb_lib.t6g(sch_1):page315_i67@pure_quanta.q_cap(chips)"
			("VARIANT" "*")
			("VALUE" "0.01UF")
			("VOLTAGE" "25V")
			("TOLERANCE" "10%")
			("PACK_TYPE" "0402")
			("MATERIAL" "X7R")
			("PART_NUMBER" "TMP_QCH31004KB17")
			("LOCATION" "PC475")
		)
		("@t6g_mb_lib.t6g(sch_1):page307_i221@pure_quanta.q_cap(chips)"
			("VARIANT" "*")
			("VALUE" "0.01UF")
			("VOLTAGE" "25V")
			("TOLERANCE" "10%")
			("PACK_TYPE" "0402")
			("MATERIAL" "X7R")
			("PART_NUMBER" "TMP_QCH31004KB17")
			("LOCATION" "PC554")
		)
		("@t6g_mb_lib.t6g(sch_1):page319_i251@pure_quanta.q_cap(chips)"
			("VARIANT" "*")
			("VALUE" "0.01UF")
			("VOLTAGE" "25V")
			("TOLERANCE" "10%")
			("PACK_TYPE" "0402")
			("MATERIAL" "X7R")
			("PART_NUMBER" "TMP_QCH31004KB17")
			("LOCATION" "PC393")
		)
		("@t6g_mb_lib.t6g(sch_1):page289_i286@pure_quanta.q_cap(chips)"
			("VARIANT" "*")
			("VALUE" "0.01UF")
			("VOLTAGE" "25V")
			("TOLERANCE" "10%")
			("PACK_TYPE" "0402")
			("MATERIAL" "X7R")
			("PART_NUMBER" "TMP_QCH31004KB17")
			("LOCATION" "PC336")
		)
		("@t6g_mb_lib.t6g(sch_1):page297_i56@pure_quanta.q_cap(chips)"
			("VARIANT" "*")
			("VALUE" "0.01UF")
			("VOLTAGE" "25V")
			("TOLERANCE" "10%")
			("PACK_TYPE" "0402")
			("MATERIAL" "X7R")
			("PART_NUMBER" "TMP_QCH31004KB17")
			("LOCATION" "PC1271")
		)
		("@t6g_mb_lib.t6g(sch_1):page297_i55@pure_quanta.q_cap(chips)"
			("VARIANT" "*")
			("VALUE" "0.01UF")
			("VOLTAGE" "25V")
			("TOLERANCE" "10%")
			("PACK_TYPE" "0402")
			("MATERIAL" "X7R")
			("PART_NUMBER" "TMP_QCH31004KB17")
			("LOCATION" "PC222")
		)
		("@t6g_mb_lib.t6g(sch_1):page301_i55@pure_quanta.q_cap(chips)"
			("VARIANT" "*")
			("VALUE" "0.01UF")
			("VOLTAGE" "25V")
			("TOLERANCE" "10%")
			("PACK_TYPE" "0402")
			("MATERIAL" "X7R")
			("PART_NUMBER" "TMP_QCH31004KB17")
			("LOCATION" "PC631")
		)
		("@t6g_mb_lib.t6g(sch_1):page319_i241@pure_quanta.q_cap(chips)"
			("VARIANT" "*")
			("VALUE" "1UF")
			("VOLTAGE" "16V")
			("TOLERANCE" "10%")
			("PACK_TYPE" "C0402")
			("MATERIAL" "EMPTY")
			("PART_NUMBER" "CH5103KEB01")
			("LOCATION" "PC814")
		)
		("@t6g_mb_lib.t6g(sch_1):page301_i49@pure_quanta.q_cap(chips)"
			("VARIANT" "*")
			("VALUE" "1UF")
			("VOLTAGE" "16V")
			("TOLERANCE" "10%")
			("PACK_TYPE" "C0402")
			("MATERIAL" "EMPTY")
			("PART_NUMBER" "CH5103KEB01")
			("LOCATION" "PC813")
		)
		("@t6g_mb_lib.t6g(sch_1):page315_i6@pure_quanta.q_res(chips)"
			("VARIANT" "*")
			("VALUE" "110")
			("TOLERANCE" "1%")
			("WATTAGE" "1/16W")
			("PACK_TYPE" "0402LF")
			("MATERIAL" "CHIP")
			("PART_NUMBER" "TMP_QCS11102FB18")
			("LOCATION" "PR259")
		)
		("@t6g_mb_lib.t6g(sch_1):page313_i30@pure_quanta.q_res(chips)"
			("VARIANT" "*")
			("VALUE" "0")
			("TOLERANCE" "5%")
			("WATTAGE" "1/16W")
			("PACK_TYPE" "0402LF")
			("MATERIAL" "EMPTY")
			("PART_NUMBER" "CS00002JB38")
			("LOCATION" "PR1334")
		)
		("@t6g_mb_lib.t6g(sch_1):page313_i47@pure_quanta.q_res(chips)"
			("VARIANT" "*")
			("VALUE" "0")
			("TOLERANCE" "5%")
			("WATTAGE" "1/16W")
			("PACK_TYPE" "0402LF")
			("MATERIAL" "EMPTY")
			("PART_NUMBER" "CS00002JB38")
			("LOCATION" "PR1333")
		)
		("@t6g_mb_lib.t6g(sch_1):page295_i29@pure_quanta.q_res(chips)"
			("VARIANT" "*")
			("VALUE" "0")
			("TOLERANCE" "5%")
			("WATTAGE" "1/16W")
			("PACK_TYPE" "0402LF")
			("MATERIAL" "EMPTY")
			("PART_NUMBER" "CS00002JB38")
			("LOCATION" "PR1325")
		)
		("@t6g_mb_lib.t6g(sch_1):page295_i47@pure_quanta.q_res(chips)"
			("VARIANT" "*")
			("VALUE" "0")
			("TOLERANCE" "5%")
			("WATTAGE" "1/16W")
			("PACK_TYPE" "0402LF")
			("MATERIAL" "EMPTY")
			("PART_NUMBER" "CS00002JB38")
			("LOCATION" "PR1324")
		)
		("@t6g_mb_lib.t6g(sch_1):page302_i342@pure_quanta.q_res(chips)"
			("VARIANT" "*")
			("VALUE" "0")
			("TOLERANCE" "5%")
			("WATTAGE" "1/16W")
			("PACK_TYPE" "0402LF")
			("MATERIAL" "EMPTY")
			("PART_NUMBER" "CS00002JB38")
			("LOCATION" "PR1785")
		)
		("@t6g_mb_lib.t6g(sch_1):page302_i335@pure_quanta.q_res(chips)"
			("VARIANT" "*")
			("VALUE" "0")
			("TOLERANCE" "5%")
			("WATTAGE" "1/16W")
			("PACK_TYPE" "0402LF")
			("MATERIAL" "EMPTY")
			("PART_NUMBER" "CS00002JB38")
			("LOCATION" "PR635")
		)
		("@t6g_mb_lib.t6g(sch_1):page294_i36@pure_quanta.q_res(chips)"
			("VARIANT" "*")
			("VALUE" "0")
			("TOLERANCE" "5%")
			("WATTAGE" "1/16W")
			("PACK_TYPE" "0402LF")
			("MATERIAL" "EMPTY")
			("PART_NUMBER" "CS00002JB38")
			("LOCATION" "PR1323")
		)
		("@t6g_mb_lib.t6g(sch_1):page294_i53@pure_quanta.q_res(chips)"
			("VARIANT" "*")
			("VALUE" "0")
			("TOLERANCE" "5%")
			("WATTAGE" "1/16W")
			("PACK_TYPE" "0402LF")
			("MATERIAL" "EMPTY")
			("PART_NUMBER" "CS00002JB38")
			("LOCATION" "PR1322")
		)
		("@t6g_mb_lib.t6g(sch_1):page294_i11@pure_quanta.q_res(chips)"
			("VARIANT" "*")
			("VALUE" "0")
			("TOLERANCE" "5%")
			("WATTAGE" "1/16W")
			("PACK_TYPE" "0402LF")
			("MATERIAL" "EMPTY")
			("PART_NUMBER" "CS00002JB38")
			("LOCATION" "PR447")
		)
		("@t6g_mb_lib.t6g(sch_1):page294_i24@pure_quanta.q_res(chips)"
			("VARIANT" "*")
			("VALUE" "0")
			("TOLERANCE" "5%")
			("WATTAGE" "1/16W")
			("PACK_TYPE" "0402LF")
			("MATERIAL" "EMPTY")
			("PART_NUMBER" "CS00002JB38")
			("LOCATION" "PR444")
		)
		("@t6g_mb_lib.t6g(sch_1):page315_i11@pure_quanta.q_res(chips)"
			("VARIANT" "*")
			("VALUE" "15K")
			("TOLERANCE" "1%")
			("WATTAGE" "1/16W")
			("PACK_TYPE" "0402LF")
			("MATERIAL" "CHIP")
			("PART_NUMBER" "TMP_QCS31502FB24")
			("LOCATION" "PR261")
		)
		("@t6g_mb_lib.t6g(sch_1):page316_i31@pure_quanta.q_res(chips)"
			("VARIANT" "*")
			("VALUE" "0")
			("TOLERANCE" "5%")
			("WATTAGE" "1/16W")
			("PACK_TYPE" "0402LF")
			("MATERIAL" "EMPTY")
			("PART_NUMBER" "CS00002JB38")
			("LOCATION" "PR1797")
		)
		("@t6g_mb_lib.t6g(sch_1):page316_i49@pure_quanta.q_res(chips)"
			("VARIANT" "*")
			("VALUE" "0")
			("TOLERANCE" "5%")
			("WATTAGE" "1/16W")
			("PACK_TYPE" "0402LF")
			("MATERIAL" "EMPTY")
			("PART_NUMBER" "CS00002JB38")
			("LOCATION" "PR1796")
		)
		("@t6g_mb_lib.t6g(sch_1):page316_i20@pure_quanta.q_res(chips)"
			("VARIANT" "*")
			("VALUE" "0")
			("TOLERANCE" "5%")
			("WATTAGE" "1/16W")
			("PACK_TYPE" "0402LF")
			("MATERIAL" "EMPTY")
			("PART_NUMBER" "CS00002JB38")
			("LOCATION" "PR668")
		)
		("@t6g_mb_lib.t6g(sch_1):page317_i19@pure_quanta.q_res(chips)"
			("VARIANT" "*")
			("VALUE" "0")
			("TOLERANCE" "5%")
			("WATTAGE" "1/16W")
			("PACK_TYPE" "0402LF")
			("MATERIAL" "EMPTY")
			("PART_NUMBER" "CS00002JB38")
			("LOCATION" "PR1799")
		)
		("@t6g_mb_lib.t6g(sch_1):page317_i11@pure_quanta.q_res(chips)"
			("VARIANT" "*")
			("VALUE" "0")
			("TOLERANCE" "5%")
			("WATTAGE" "1/16W")
			("PACK_TYPE" "0402LF")
			("MATERIAL" "EMPTY")
			("PART_NUMBER" "CS00002JB38")
			("LOCATION" "PR678")
		)
		("@t6g_mb_lib.t6g(sch_1):page307_i166@pure_quanta.q_res(chips)"
			("VARIANT" "*")
			("VALUE" "15K")
			("TOLERANCE" "1%")
			("WATTAGE" "1/16W")
			("PACK_TYPE" "0402LF")
			("MATERIAL" "CHIP")
			("PART_NUMBER" "TMP_QCS31502FB24")
			("LOCATION" "PR303")
		)
		("@t6g_mb_lib.t6g(sch_1):page312_i239@pure_quanta.q_res(chips)"
			("VARIANT" "*")
			("VALUE" "0")
			("TOLERANCE" "5%")
			("WATTAGE" "1/16W")
			("PACK_TYPE" "0402LF")
			("MATERIAL" "EMPTY")
			("PART_NUMBER" "CS00002JB38")
			("LOCATION" "PR1332")
		)
		("@t6g_mb_lib.t6g(sch_1):page312_i260@pure_quanta.q_res(chips)"
			("VARIANT" "*")
			("VALUE" "0")
			("TOLERANCE" "5%")
			("WATTAGE" "1/16W")
			("PACK_TYPE" "0402LF")
			("MATERIAL" "EMPTY")
			("PART_NUMBER" "CS00002JB38")
			("LOCATION" "PR1331")
		)
		("@t6g_mb_lib.t6g(sch_1):page312_i210@pure_quanta.q_res(chips)"
			("VARIANT" "*")
			("VALUE" "0")
			("TOLERANCE" "5%")
			("WATTAGE" "1/16W")
			("PACK_TYPE" "0402LF")
			("MATERIAL" "EMPTY")
			("PART_NUMBER" "CS00002JB38")
			("LOCATION" "PR702")
		)
		("@t6g_mb_lib.t6g(sch_1):page312_i277@pure_quanta.q_res(chips)"
			("VARIANT" "*")
			("VALUE" "0")
			("TOLERANCE" "5%")
			("WATTAGE" "1/16W")
			("PACK_TYPE" "0402LF")
			("MATERIAL" "EMPTY")
			("PART_NUMBER" "CS00002JB38")
			("LOCATION" "PR701")
		)
		("@t6g_mb_lib.t6g(sch_1):page319_i259@pure_quanta.q_res(chips)"
			("VARIANT" "*")
			("VALUE" "0")
			("TOLERANCE" "5%")
			("WATTAGE" "1/16W")
			("PACK_TYPE" "0402LF")
			("MATERIAL" "EMPTY")
			("PART_NUMBER" "CS00002JB38")
			("LOCATION" "PR1315")
		)
		("@t6g_mb_lib.t6g(sch_1):page320_i17@pure_quanta.q_res(chips)"
			("VARIANT" "*")
			("VALUE" "0")
			("TOLERANCE" "5%")
			("WATTAGE" "1/16W")
			("PACK_TYPE" "0402LF")
			("MATERIAL" "EMPTY")
			("PART_NUMBER" "CS00002JB38")
			("LOCATION" "PR1805")
		)
		("@t6g_mb_lib.t6g(sch_1):page320_i11@pure_quanta.q_res(chips)"
			("VARIANT" "*")
			("VALUE" "0")
			("TOLERANCE" "5%")
			("WATTAGE" "1/16W")
			("PACK_TYPE" "0402LF")
			("MATERIAL" "EMPTY")
			("PART_NUMBER" "CS00002JB38")
			("LOCATION" "PR706")
		)
		("@t6g_mb_lib.t6g(sch_1):page289_i220@pure_quanta.q_res(chips)"
			("VARIANT" "*")
			("VALUE" "15K")
			("TOLERANCE" "1%")
			("WATTAGE" "1/16W")
			("PACK_TYPE" "0402LF")
			("MATERIAL" "CHIP")
			("PART_NUMBER" "TMP_QCS31502FB24")
			("LOCATION" "PR156")
		)
		("@t6g_mb_lib.t6g(sch_1):page297_i27@pure_quanta.q_res(chips)"
			("VARIANT" "*")
			("VALUE" "15K")
			("TOLERANCE" "1%")
			("WATTAGE" "1/16W")
			("PACK_TYPE" "0402LF")
			("MATERIAL" "CHIP")
			("PART_NUMBER" "TMP_QCS31502FB24")
			("LOCATION" "PR108")
		)
		("@t6g_mb_lib.t6g(sch_1):page298_i180@pure_quanta.q_res(chips)"
			("VARIANT" "*")
			("VALUE" "0")
			("TOLERANCE" "5%")
			("WATTAGE" "1/16W")
			("PACK_TYPE" "0402LF")
			("MATERIAL" "EMPTY")
			("PART_NUMBER" "CS00002JB38")
			("LOCATION" "PR1777")
		)
		("@t6g_mb_lib.t6g(sch_1):page298_i188@pure_quanta.q_res(chips)"
			("VARIANT" "*")
			("VALUE" "0")
			("TOLERANCE" "5%")
			("WATTAGE" "1/16W")
			("PACK_TYPE" "0402LF")
			("MATERIAL" "EMPTY")
			("PART_NUMBER" "CS00002JB38")
			("LOCATION" "PR1776")
		)
		("@t6g_mb_lib.t6g(sch_1):page298_i170@pure_quanta.q_res(chips)"
			("VARIANT" "*")
			("VALUE" "0")
			("TOLERANCE" "5%")
			("WATTAGE" "1/16W")
			("PACK_TYPE" "0402LF")
			("MATERIAL" "EMPTY")
			("PART_NUMBER" "CS00002JB38")
			("LOCATION" "PR437")
		)
		("@t6g_mb_lib.t6g(sch_1):page299_i19@pure_quanta.q_res(chips)"
			("VARIANT" "*")
			("VALUE" "0")
			("TOLERANCE" "5%")
			("WATTAGE" "1/16W")
			("PACK_TYPE" "0402LF")
			("MATERIAL" "EMPTY")
			("PART_NUMBER" "CS00002JB38")
			("LOCATION" "PR1779")
		)
		("@t6g_mb_lib.t6g(sch_1):page299_i13@pure_quanta.q_res(chips)"
			("VARIANT" "*")
			("VALUE" "0")
			("TOLERANCE" "5%")
			("WATTAGE" "1/16W")
			("PACK_TYPE" "0402LF")
			("MATERIAL" "EMPTY")
			("PART_NUMBER" "CS00002JB38")
			("LOCATION" "PR442")
		)
		("@t6g_mb_lib.t6g(sch_1):page308_i25@pure_quanta.q_res(chips)"
			("VARIANT" "*")
			("VALUE" "0")
			("TOLERANCE" "5%")
			("WATTAGE" "1/16W")
			("PACK_TYPE" "0402LF")
			("MATERIAL" "EMPTY")
			("PART_NUMBER" "CS00002JB38")
			("LOCATION" "PR639")
		)
		("@t6g_mb_lib.t6g(sch_1):page290_i31@pure_quanta.q_res(chips)"
			("VARIANT" "*")
			("VALUE" "0")
			("TOLERANCE" "5%")
			("WATTAGE" "1/16W")
			("PACK_TYPE" "0402LF")
			("MATERIAL" "EMPTY")
			("PART_NUMBER" "CS00002JB38")
			("LOCATION" "PR402")
		)
		("@t6g_mb_lib.t6g(sch_1):page301_i58@pure_quanta.q_res(chips)"
			("VARIANT" "*")
			("VALUE" "0")
			("TOLERANCE" "5%")
			("WATTAGE" "1/16W")
			("PACK_TYPE" "0402LF")
			("MATERIAL" "EMPTY")
			("PART_NUMBER" "CS00002JB38")
			("LOCATION" "PR1311")
		)
		("@t6g_mb_lib.t6g(sch_1):page302_i337@pure_quanta.q_res(chips)"
			("VARIANT" "*")
			("VALUE" "0")
			("TOLERANCE" "5%")
			("WATTAGE" "1/16W")
			("PACK_TYPE" "0402LF")
			("MATERIAL" "CHIP")
			("PART_NUMBER" "CS00002JB38")
			("LOCATION" "PR636")
		)
		("@t6g_mb_lib.t6g(sch_1):page294_i14@pure_quanta.q_res(chips)"
			("VARIANT" "*")
			("VALUE" "0")
			("TOLERANCE" "5%")
			("WATTAGE" "1/16W")
			("PACK_TYPE" "0402LF")
			("MATERIAL" "CHIP")
			("PART_NUMBER" "CS00002JB38")
			("LOCATION" "PR633")
		)
		("@t6g_mb_lib.t6g(sch_1):page294_i26@pure_quanta.q_res(chips)"
			("VARIANT" "*")
			("VALUE" "0")
			("TOLERANCE" "5%")
			("WATTAGE" "1/16W")
			("PACK_TYPE" "0402LF")
			("MATERIAL" "CHIP")
			("PART_NUMBER" "CS00002JB38")
			("LOCATION" "PR632")
		)
		("@t6g_mb_lib.t6g(sch_1):page316_i28@pure_quanta.q_res(chips)"
			("VARIANT" "*")
			("VALUE" "0")
			("TOLERANCE" "5%")
			("WATTAGE" "1/16W")
			("PACK_TYPE" "0402LF")
			("MATERIAL" "CHIP")
			("PART_NUMBER" "CS00002JB38")
			("LOCATION" "PR677")
		)
		("@t6g_mb_lib.t6g(sch_1):page317_i16@pure_quanta.q_res(chips)"
			("VARIANT" "*")
			("VALUE" "0")
			("TOLERANCE" "5%")
			("WATTAGE" "1/16W")
			("PACK_TYPE" "0402LF")
			("MATERIAL" "CHIP")
			("PART_NUMBER" "CS00002JB38")
			("LOCATION" "PR699")
		)
		("@t6g_mb_lib.t6g(sch_1):page312_i219@pure_quanta.q_res(chips)"
			("VARIANT" "*")
			("VALUE" "0")
			("TOLERANCE" "5%")
			("WATTAGE" "1/16W")
			("PACK_TYPE" "0402LF")
			("MATERIAL" "CHIP")
			("PART_NUMBER" "CS00002JB38")
			("LOCATION" "PR704")
		)
		("@t6g_mb_lib.t6g(sch_1):page312_i235@pure_quanta.q_res(chips)"
			("VARIANT" "*")
			("VALUE" "0")
			("TOLERANCE" "5%")
			("WATTAGE" "1/16W")
			("PACK_TYPE" "0402LF")
			("MATERIAL" "CHIP")
			("PART_NUMBER" "CS00002JB38")
			("LOCATION" "PR703")
		)
		("@t6g_mb_lib.t6g(sch_1):page319_i260@pure_quanta.q_res(chips)"
			("VARIANT" "*")
			("VALUE" "0")
			("TOLERANCE" "5%")
			("WATTAGE" "1/16W")
			("PACK_TYPE" "0402LF")
			("MATERIAL" "CHIP")
			("PART_NUMBER" "CS00002JB38")
			("LOCATION" "PR410")
		)
		("@t6g_mb_lib.t6g(sch_1):page320_i14@pure_quanta.q_res(chips)"
			("VARIANT" "*")
			("VALUE" "0")
			("TOLERANCE" "5%")
			("WATTAGE" "1/16W")
			("PACK_TYPE" "0402LF")
			("MATERIAL" "CHIP")
			("PART_NUMBER" "CS00002JB38")
			("LOCATION" "PR707")
		)
		("@t6g_mb_lib.t6g(sch_1):page298_i176@pure_quanta.q_res(chips)"
			("VARIANT" "*")
			("VALUE" "0")
			("TOLERANCE" "5%")
			("WATTAGE" "1/16W")
			("PACK_TYPE" "0402LF")
			("MATERIAL" "CHIP")
			("PART_NUMBER" "CS00002JB38")
			("LOCATION" "PR441")
		)
		("@t6g_mb_lib.t6g(sch_1):page299_i15@pure_quanta.q_res(chips)"
			("VARIANT" "*")
			("VALUE" "0")
			("TOLERANCE" "5%")
			("WATTAGE" "1/16W")
			("PACK_TYPE" "0402LF")
			("MATERIAL" "CHIP")
			("PART_NUMBER" "CS00002JB38")
			("LOCATION" "PR443")
		)
		("@t6g_mb_lib.t6g(sch_1):page308_i34@pure_quanta.q_res(chips)"
			("VARIANT" "*")
			("VALUE" "0")
			("TOLERANCE" "5%")
			("WATTAGE" "1/16W")
			("PACK_TYPE" "0402LF")
			("MATERIAL" "CHIP")
			("PART_NUMBER" "CS00002JB38")
			("LOCATION" "PR640")
		)
		("@t6g_mb_lib.t6g(sch_1):page290_i36@pure_quanta.q_res(chips)"
			("VARIANT" "*")
			("VALUE" "0")
			("TOLERANCE" "5%")
			("WATTAGE" "1/16W")
			("PACK_TYPE" "0402LF")
			("MATERIAL" "CHIP")
			("PART_NUMBER" "CS00002JB38")
			("LOCATION" "PR403")
		)
		("@t6g_mb_lib.t6g(sch_1):page301_i59@pure_quanta.q_res(chips)"
			("VARIANT" "*")
			("VALUE" "0")
			("TOLERANCE" "5%")
			("WATTAGE" "1/16W")
			("PACK_TYPE" "0402LF")
			("MATERIAL" "CHIP")
			("PART_NUMBER" "CS00002JB38")
			("LOCATION" "PR409")
		)
		("@t6g_mb_lib.t6g(sch_1):page315_i93@pure_quanta.q_res(chips)"
			("VARIANT" "*")
			("VALUE" "10K")
			("TOLERANCE" "1%")
			("WATTAGE" "1/16W")
			("PACK_TYPE" "0402LF")
			("MATERIAL" "CHIP")
			("PART_NUMBER" "CS31002FB08")
			("LOCATION" "PR667")
		)
		("@t6g_mb_lib.t6g(sch_1):page315_i70@pure_quanta.q_res(chips)"
			("VARIANT" "*")
			("VALUE" "10K")
			("TOLERANCE" "1%")
			("WATTAGE" "1/16W")
			("PACK_TYPE" "0402LF")
			("MATERIAL" "CHIP")
			("PART_NUMBER" "CS31002FB08")
			("LOCATION" "PR665")
		)
		("@t6g_mb_lib.t6g(sch_1):page307_i260@pure_quanta.q_res(chips)"
			("VARIANT" "*")
			("VALUE" "10K")
			("TOLERANCE" "1%")
			("WATTAGE" "1/16W")
			("PACK_TYPE" "0402LF")
			("MATERIAL" "CHIP")
			("PART_NUMBER" "CS31002FB08")
			("LOCATION" "PR637")
		)
		("@t6g_mb_lib.t6g(sch_1):page319_i263@pure_quanta.q_res(chips)"
			("VARIANT" "*")
			("VALUE" "10K")
			("TOLERANCE" "1%")
			("WATTAGE" "1/16W")
			("PACK_TYPE" "0402LF")
			("MATERIAL" "CHIP")
			("PART_NUMBER" "CS31002FB08")
			("LOCATION" "PR705")
		)
		("@t6g_mb_lib.t6g(sch_1):page289_i288@pure_quanta.q_res(chips)"
			("VARIANT" "*")
			("VALUE" "10K")
			("TOLERANCE" "1%")
			("WATTAGE" "1/16W")
			("PACK_TYPE" "0402LF")
			("MATERIAL" "CHIP")
			("PART_NUMBER" "CS31002FB08")
			("LOCATION" "PR400")
		)
		("@t6g_mb_lib.t6g(sch_1):page297_i79@pure_quanta.q_res(chips)"
			("VARIANT" "*")
			("VALUE" "10K")
			("TOLERANCE" "1%")
			("WATTAGE" "1/16W")
			("PACK_TYPE" "0402LF")
			("MATERIAL" "CHIP")
			("PART_NUMBER" "CS31002FB08")
			("LOCATION" "PR436")
		)
		("@t6g_mb_lib.t6g(sch_1):page297_i73@pure_quanta.q_res(chips)"
			("VARIANT" "*")
			("VALUE" "10K")
			("TOLERANCE" "1%")
			("WATTAGE" "1/16W")
			("PACK_TYPE" "0402LF")
			("MATERIAL" "CHIP")
			("PART_NUMBER" "CS31002FB08")
			("LOCATION" "PR435")
		)
		("@t6g_mb_lib.t6g(sch_1):page301_i57@pure_quanta.q_res(chips)"
			("VARIANT" "*")
			("VALUE" "10K")
			("TOLERANCE" "1%")
			("WATTAGE" "1/16W")
			("PACK_TYPE" "0402LF")
			("MATERIAL" "CHIP")
			("PART_NUMBER" "CS31002FB08")
			("LOCATION" "PR634")
		)
		("@t6g_mb_lib.t6g(sch_1):page315_i56@pure_quanta.q_res(chips)"
			("VARIANT" "*")
			("VALUE" "1K")
			("TOLERANCE" "1%")
			("WATTAGE" "1/16W")
			("PACK_TYPE" "0402LF")
			("MATERIAL" "CHIP")
			("PART_NUMBER" "TMP_QCS21002FB24")
			("LOCATION" "PR276")
		)
		("@t6g_mb_lib.t6g(sch_1):page307_i208@pure_quanta.q_res(chips)"
			("VARIANT" "*")
			("VALUE" "1K")
			("TOLERANCE" "1%")
			("WATTAGE" "1/16W")
			("PACK_TYPE" "0402LF")
			("MATERIAL" "CHIP")
			("PART_NUMBER" "TMP_QCS21002FB24")
			("LOCATION" "PR313")
		)
		("@t6g_mb_lib.t6g(sch_1):page319_i238@pure_quanta.q_res(chips)"
			("VARIANT" "*")
			("VALUE" "1K")
			("TOLERANCE" "1%")
			("WATTAGE" "1/16W")
			("PACK_TYPE" "0402LF")
			("MATERIAL" "CHIP")
			("PART_NUMBER" "TMP_QCS21002FB24")
			("LOCATION" "PR218")
		)
		("@t6g_mb_lib.t6g(sch_1):page319_i236@pure_quanta.q_res(chips)"
			("VARIANT" "*")
			("VALUE" "0")
			("TOLERANCE" "5%")
			("WATTAGE" "1/16W")
			("PACK_TYPE" "0402LF")
			("MATERIAL" "CHIP")
			("PART_NUMBER" "CS00002JB38")
			("LOCATION" "PR214")
		)
		("@t6g_mb_lib.t6g(sch_1):page289_i229@pure_quanta.q_res(chips)"
			("VARIANT" "*")
			("VALUE" "1K")
			("TOLERANCE" "1%")
			("WATTAGE" "1/16W")
			("PACK_TYPE" "0402LF")
			("MATERIAL" "CHIP")
			("PART_NUMBER" "TMP_QCS21002FB24")
			("LOCATION" "PR166")
		)
		("@t6g_mb_lib.t6g(sch_1):page297_i36@pure_quanta.q_res(chips)"
			("VARIANT" "*")
			("VALUE" "1K")
			("TOLERANCE" "1%")
			("WATTAGE" "1/16W")
			("PACK_TYPE" "0402LF")
			("MATERIAL" "CHIP")
			("PART_NUMBER" "TMP_QCS21002FB24")
			("LOCATION" "PR123")
		)
		("@t6g_mb_lib.t6g(sch_1):page301_i46@pure_quanta.q_res(chips)"
			("VARIANT" "*")
			("VALUE" "1K")
			("TOLERANCE" "1%")
			("WATTAGE" "1/16W")
			("PACK_TYPE" "0402LF")
			("MATERIAL" "CHIP")
			("PART_NUMBER" "TMP_QCS21002FB24")
			("LOCATION" "PR373")
		)
		("@t6g_mb_lib.t6g(sch_1):page301_i12@pure_quanta.q_res(chips)"
			("VARIANT" "*")
			("VALUE" "0")
			("TOLERANCE" "5%")
			("WATTAGE" "1/16W")
			("PACK_TYPE" "0402LF")
			("MATERIAL" "CHIP")
			("PART_NUMBER" "CS00002JB38")
			("LOCATION" "PR369")
		)
		("@t6g_mb_lib.t6g(sch_1):page315_i10@pure_quanta.q_res(chips)"
			("VARIANT" "*")
			("VALUE" "3.32K")
			("TOLERANCE" "1%")
			("WATTAGE" "1/16W")
			("PACK_TYPE" "0402LF")
			("MATERIAL" "CHIP")
			("PART_NUMBER" "CS23322FB20")
			("LOCATION" "PR258")
		)
		("@t6g_mb_lib.t6g(sch_1):page307_i161@pure_quanta.q_res(chips)"
			("VARIANT" "*")
			("VALUE" "3.32K")
			("TOLERANCE" "1%")
			("WATTAGE" "1/16W")
			("PACK_TYPE" "0402LF")
			("MATERIAL" "CHIP")
			("PART_NUMBER" "CS23322FB20")
			("LOCATION" "PR306")
		)
		("@t6g_mb_lib.t6g(sch_1):page319_i204@pure_quanta.q_res(chips)"
			("VARIANT" "*")
			("VALUE" "3.32K")
			("TOLERANCE" "1%")
			("WATTAGE" "1/16W")
			("PACK_TYPE" "0402LF")
			("MATERIAL" "CHIP")
			("PART_NUMBER" "CS23322FB20")
			("LOCATION" "PR202")
		)
		("@t6g_mb_lib.t6g(sch_1):page313_i34@pure_quanta.q_res(chips)"
			("VARIANT" "*")
			("VALUE" "0")
			("TOLERANCE" "5%")
			("WATTAGE" "1/16W")
			("PACK_TYPE" "0402LF")
			("MATERIAL" "CHIP")
			("PART_NUMBER" "CS00002JB38")
			("LOCATION" "PR1803")
		)
		("@t6g_mb_lib.t6g(sch_1):page313_i43@pure_quanta.q_res(chips)"
			("VARIANT" "*")
			("VALUE" "0")
			("TOLERANCE" "5%")
			("WATTAGE" "1/16W")
			("PACK_TYPE" "0402LF")
			("MATERIAL" "CHIP")
			("PART_NUMBER" "CS00002JB38")
			("LOCATION" "PR1802")
		)
		("@t6g_mb_lib.t6g(sch_1):page295_i33@pure_quanta.q_res(chips)"
			("VARIANT" "*")
			("VALUE" "0")
			("TOLERANCE" "5%")
			("WATTAGE" "1/16W")
			("PACK_TYPE" "0402LF")
			("MATERIAL" "CHIP")
			("PART_NUMBER" "CS00002JB38")
			("LOCATION" "PR1783")
		)
		("@t6g_mb_lib.t6g(sch_1):page295_i45@pure_quanta.q_res(chips)"
			("VARIANT" "*")
			("VALUE" "0")
			("TOLERANCE" "5%")
			("WATTAGE" "1/16W")
			("PACK_TYPE" "0402LF")
			("MATERIAL" "CHIP")
			("PART_NUMBER" "CS00002JB38")
			("LOCATION" "PR1782")
		)
		("@t6g_mb_lib.t6g(sch_1):page294_i40@pure_quanta.q_res(chips)"
			("VARIANT" "*")
			("VALUE" "0")
			("TOLERANCE" "5%")
			("WATTAGE" "1/16W")
			("PACK_TYPE" "0402LF")
			("MATERIAL" "CHIP")
			("PART_NUMBER" "CS00002JB38")
			("LOCATION" "PR1781")
		)
		("@t6g_mb_lib.t6g(sch_1):page294_i51@pure_quanta.q_res(chips)"
			("VARIANT" "*")
			("VALUE" "0")
			("TOLERANCE" "5%")
			("WATTAGE" "1/16W")
			("PACK_TYPE" "0402LF")
			("MATERIAL" "CHIP")
			("PART_NUMBER" "CS00002JB38")
			("LOCATION" "PR1780")
		)
		("@t6g_mb_lib.t6g(sch_1):page309_i47@pure_quanta.q_res(chips)"
			("VARIANT" "*")
			("VALUE" "0")
			("TOLERANCE" "5%")
			("WATTAGE" "1/16W")
			("PACK_TYPE" "0402LF")
			("MATERIAL" "CHIP")
			("PART_NUMBER" "CS00002JB38")
			("LOCATION" "PR1789")
		)
		("@t6g_mb_lib.t6g(sch_1):page309_i34@pure_quanta.q_res(chips)"
			("VARIANT" "*")
			("VALUE" "0")
			("TOLERANCE" "5%")
			("WATTAGE" "1/16W")
			("PACK_TYPE" "0402LF")
			("MATERIAL" "CHIP")
			("PART_NUMBER" "CS00002JB38")
			("LOCATION" "PR1788")
		)
		("@t6g_mb_lib.t6g(sch_1):page310_i47@pure_quanta.q_res(chips)"
			("VARIANT" "*")
			("VALUE" "0")
			("TOLERANCE" "5%")
			("WATTAGE" "1/16W")
			("PACK_TYPE" "0402LF")
			("MATERIAL" "CHIP")
			("PART_NUMBER" "CS00002JB38")
			("LOCATION" "PR1791")
		)
		("@t6g_mb_lib.t6g(sch_1):page310_i36@pure_quanta.q_res(chips)"
			("VARIANT" "*")
			("VALUE" "0")
			("TOLERANCE" "5%")
			("WATTAGE" "1/16W")
			("PACK_TYPE" "0402LF")
			("MATERIAL" "CHIP")
			("PART_NUMBER" "CS00002JB38")
			("LOCATION" "PR1790")
		)
		("@t6g_mb_lib.t6g(sch_1):page311_i47@pure_quanta.q_res(chips)"
			("VARIANT" "*")
			("VALUE" "0")
			("TOLERANCE" "5%")
			("WATTAGE" "1/16W")
			("PACK_TYPE" "0402LF")
			("MATERIAL" "CHIP")
			("PART_NUMBER" "CS00002JB38")
			("LOCATION" "PR1793")
		)
		("@t6g_mb_lib.t6g(sch_1):page311_i39@pure_quanta.q_res(chips)"
			("VARIANT" "*")
			("VALUE" "0")
			("TOLERANCE" "5%")
			("WATTAGE" "1/16W")
			("PACK_TYPE" "0402LF")
			("MATERIAL" "CHIP")
			("PART_NUMBER" "CS00002JB38")
			("LOCATION" "PR1792")
		)
		("@t6g_mb_lib.t6g(sch_1):page312_i242@pure_quanta.q_res(chips)"
			("VARIANT" "*")
			("VALUE" "0")
			("TOLERANCE" "5%")
			("WATTAGE" "1/16W")
			("PACK_TYPE" "0402LF")
			("MATERIAL" "CHIP")
			("PART_NUMBER" "CS00002JB38")
			("LOCATION" "PR1801")
		)
		("@t6g_mb_lib.t6g(sch_1):page312_i256@pure_quanta.q_res(chips)"
			("VARIANT" "*")
			("VALUE" "0")
			("TOLERANCE" "5%")
			("WATTAGE" "1/16W")
			("PACK_TYPE" "0402LF")
			("MATERIAL" "CHIP")
			("PART_NUMBER" "CS00002JB38")
			("LOCATION" "PR1800")
		)
		("@t6g_mb_lib.t6g(sch_1):page291_i49@pure_quanta.q_res(chips)"
			("VARIANT" "*")
			("VALUE" "0")
			("TOLERANCE" "5%")
			("WATTAGE" "1/16W")
			("PACK_TYPE" "0402LF")
			("MATERIAL" "CHIP")
			("PART_NUMBER" "CS00002JB38")
			("LOCATION" "PR1769")
		)
		("@t6g_mb_lib.t6g(sch_1):page291_i35@pure_quanta.q_res(chips)"
			("VARIANT" "*")
			("VALUE" "0")
			("TOLERANCE" "5%")
			("WATTAGE" "1/16W")
			("PACK_TYPE" "0402LF")
			("MATERIAL" "CHIP")
			("PART_NUMBER" "CS00002JB38")
			("LOCATION" "PR1768")
		)
		("@t6g_mb_lib.t6g(sch_1):page292_i37@pure_quanta.q_res(chips)"
			("VARIANT" "*")
			("VALUE" "0")
			("TOLERANCE" "5%")
			("WATTAGE" "1/16W")
			("PACK_TYPE" "0402LF")
			("MATERIAL" "CHIP")
			("PART_NUMBER" "CS00002JB38")
			("LOCATION" "PR1771")
		)
		("@t6g_mb_lib.t6g(sch_1):page292_i17@pure_quanta.q_res(chips)"
			("VARIANT" "*")
			("VALUE" "0")
			("TOLERANCE" "5%")
			("WATTAGE" "1/16W")
			("PACK_TYPE" "0402LF")
			("MATERIAL" "CHIP")
			("PART_NUMBER" "CS00002JB38")
			("LOCATION" "PR1770")
		)
		("@t6g_mb_lib.t6g(sch_1):page293_i49@pure_quanta.q_res(chips)"
			("VARIANT" "*")
			("VALUE" "0")
			("TOLERANCE" "5%")
			("WATTAGE" "1/16W")
			("PACK_TYPE" "0402LF")
			("MATERIAL" "CHIP")
			("PART_NUMBER" "CS00002JB38")
			("LOCATION" "PR1773")
		)
		("@t6g_mb_lib.t6g(sch_1):page293_i35@pure_quanta.q_res(chips)"
			("VARIANT" "*")
			("VALUE" "0")
			("TOLERANCE" "5%")
			("WATTAGE" "1/16W")
			("PACK_TYPE" "0402LF")
			("MATERIAL" "CHIP")
			("PART_NUMBER" "CS00002JB38")
			("LOCATION" "PR1772")
		)
		("@t6g_mb_lib.t6g(sch_1):page308_i37@pure_quanta.q_res(chips)"
			("VARIANT" "*")
			("VALUE" "0")
			("TOLERANCE" "5%")
			("WATTAGE" "1/16W")
			("PACK_TYPE" "0402LF")
			("MATERIAL" "CHIP")
			("PART_NUMBER" "CS00002JB38")
			("LOCATION" "PR1767")
		)
		("@t6g_mb_lib.t6g(sch_1):page308_i22@pure_quanta.q_res(chips)"
			("VARIANT" "*")
			("VALUE" "0")
			("TOLERANCE" "5%")
			("WATTAGE" "1/16W")
			("PACK_TYPE" "0402LF")
			("MATERIAL" "CHIP")
			("PART_NUMBER" "CS00002JB38")
			("LOCATION" "PR1766")
		)
		("@t6g_mb_lib.t6g(sch_1):page290_i39@pure_quanta.q_res(chips)"
			("VARIANT" "*")
			("VALUE" "0")
			("TOLERANCE" "5%")
			("WATTAGE" "1/16W")
			("PACK_TYPE" "0402LF")
			("MATERIAL" "CHIP")
			("PART_NUMBER" "CS00002JB38")
			("LOCATION" "PR1787")
		)
		("@t6g_mb_lib.t6g(sch_1):page290_i20@pure_quanta.q_res(chips)"
			("VARIANT" "*")
			("VALUE" "0")
			("TOLERANCE" "5%")
			("WATTAGE" "1/16W")
			("PACK_TYPE" "0402LF")
			("MATERIAL" "CHIP")
			("PART_NUMBER" "CS00002JB38")
			("LOCATION" "PR1786")
		)
		("@t6g_mb_lib.t6g(sch_1):page319_i201@pure_quanta.q_res(chips)"
			("VARIANT" "*")
			("VALUE" "110")
			("TOLERANCE" "1%")
			("WATTAGE" "1/16W")
			("PACK_TYPE" "0402LF")
			("MATERIAL" "CHIP")
			("PART_NUMBER" "TMP_QCS11102FB18")
			("LOCATION" "PR203")
		)
		("@t6g_mb_lib.t6g(sch_1):page301_i6@pure_quanta.q_res(chips)"
			("VARIANT" "*")
			("VALUE" "0")
			("TOLERANCE" "5%")
			("WATTAGE" "1/16W")
			("PACK_TYPE" "0402LF")
			("MATERIAL" "CHIP")
			("PART_NUMBER" "CS00002JB38")
			("LOCATION" "PR358")
		)
		("@t6g_mb_lib.t6g(sch_1):page302_i341@pure_quanta.q_res(chips)"
			("VARIANT" "*")
			("VALUE" "0")
			("TOLERANCE" "5%")
			("WATTAGE" "1/16W")
			("PACK_TYPE" "0402LF")
			("MATERIAL" "CHIP")
			("PART_NUMBER" "CS00002JB38")
			("LOCATION" "PR1784")
		)
		("@t6g_mb_lib.t6g(sch_1):page316_i35@pure_quanta.q_res(chips)"
			("VARIANT" "*")
			("VALUE" "0")
			("TOLERANCE" "5%")
			("WATTAGE" "1/16W")
			("PACK_TYPE" "0402LF")
			("MATERIAL" "CHIP")
			("PART_NUMBER" "CS00002JB38")
			("LOCATION" "PR1795")
		)
		("@t6g_mb_lib.t6g(sch_1):page316_i52@pure_quanta.q_res(chips)"
			("VARIANT" "*")
			("VALUE" "0")
			("TOLERANCE" "5%")
			("WATTAGE" "1/16W")
			("PACK_TYPE" "0402LF")
			("MATERIAL" "CHIP")
			("PART_NUMBER" "CS00002JB38")
			("LOCATION" "PR1794")
		)
		("@t6g_mb_lib.t6g(sch_1):page317_i18@pure_quanta.q_res(chips)"
			("VARIANT" "*")
			("VALUE" "0")
			("TOLERANCE" "5%")
			("WATTAGE" "1/16W")
			("PACK_TYPE" "0402LF")
			("MATERIAL" "CHIP")
			("PART_NUMBER" "CS00002JB38")
			("LOCATION" "PR1798")
		)
		("@t6g_mb_lib.t6g(sch_1):page320_i19@pure_quanta.q_res(chips)"
			("VARIANT" "*")
			("VALUE" "0")
			("TOLERANCE" "5%")
			("WATTAGE" "1/16W")
			("PACK_TYPE" "0402LF")
			("MATERIAL" "CHIP")
			("PART_NUMBER" "CS00002JB38")
			("LOCATION" "PR1804")
		)
		("@t6g_mb_lib.t6g(sch_1):page298_i181@pure_quanta.q_res(chips)"
			("VARIANT" "*")
			("VALUE" "0")
			("TOLERANCE" "5%")
			("WATTAGE" "1/16W")
			("PACK_TYPE" "0402LF")
			("MATERIAL" "CHIP")
			("PART_NUMBER" "CS00002JB38")
			("LOCATION" "PR1775")
		)
		("@t6g_mb_lib.t6g(sch_1):page298_i203@pure_quanta.q_res(chips)"
			("VARIANT" "*")
			("VALUE" "0")
			("TOLERANCE" "5%")
			("WATTAGE" "1/16W")
			("PACK_TYPE" "0402LF")
			("MATERIAL" "CHIP")
			("PART_NUMBER" "CS00002JB38")
			("LOCATION" "PR1774")
		)
		("@t6g_mb_lib.t6g(sch_1):page299_i30@pure_quanta.q_res(chips)"
			("VARIANT" "*")
			("VALUE" "0")
			("TOLERANCE" "5%")
			("WATTAGE" "1/16W")
			("PACK_TYPE" "0402LF")
			("MATERIAL" "CHIP")
			("PART_NUMBER" "CS00002JB38")
			("LOCATION" "PR1778")
		)
		("@t6g_mb_lib.t6g(sch_1):page319_i202@pure_quanta.q_res(chips)"
			("VARIANT" "*")
			("VALUE" "15K")
			("TOLERANCE" "1%")
			("WATTAGE" "1/16W")
			("PACK_TYPE" "0402LF")
			("MATERIAL" "CHIP")
			("PART_NUMBER" "TMP_QCS31502FB24")
			("LOCATION" "PR1410")
		)
		("@t6g_mb_lib.t6g(sch_1):page319_i203@pure_quanta.q_res(chips)"
			("VARIANT" "*")
			("VALUE" "49.9     ")
			("TOLERANCE" "1%  ")
			("WATTAGE" "1/16W")
			("PACK_TYPE" "0402LF")
			("MATERIAL" "EMPTY")
			("PART_NUMBER" "CS04992FB31")
			("LOCATION" "PR1400")
		)
		("@t6g_mb_lib.t6g(sch_1):page301_i9@pure_quanta.q_res(chips)"
			("VARIANT" "*")
			("VALUE" "15K")
			("TOLERANCE" "1%")
			("WATTAGE" "1/16W")
			("PACK_TYPE" "0402LF")
			("MATERIAL" "CHIP")
			("PART_NUMBER" "TMP_QCS31502FB24")
			("LOCATION" "PR1390")
		)
		("@t6g_mb_lib.t6g(sch_1):page301_i10@pure_quanta.q_res(chips)"
			("VARIANT" "*")
			("VALUE" "49.9     ")
			("TOLERANCE" "1%  ")
			("WATTAGE" "1/16W")
			("PACK_TYPE" "0402LF")
			("MATERIAL" "EMPTY")
			("PART_NUMBER" "CS04992FB31")
			("LOCATION" "PR1380")
		)
		("@t6g_mb_lib.t6g(sch_1):page307_i165@pure_quanta.q_res(chips)"
			("VARIANT" "*")
			("VALUE" "110")
			("TOLERANCE" "1%")
			("WATTAGE" "1/16W")
			("PACK_TYPE" "0402LF")
			("MATERIAL" "CHIP")
			("PART_NUMBER" "TMP_QCS11102FB18")
			("LOCATION" "PR318")
		)
		("@t6g_mb_lib.t6g(sch_1):page297_i25@pure_quanta.q_res(chips)"
			("VARIANT" "*")
			("VALUE" "0")
			("TOLERANCE" "5%")
			("WATTAGE" "1/16W")
			("PACK_TYPE" "0402LF")
			("MATERIAL" "CHIP")
			("PART_NUMBER" "CS00002JB38")
			("LOCATION" "PR106")
		)
		("@t6g_mb_lib.t6g(sch_1):page302_i333@pure_quanta.raa2213404gnphb0(chips)"
			("VARIANT" "*")
			("VALUE" "MP86950GLVT-Z")
			("PART_TYPE" "SMLF")
			("MATERIAL" "IC")
			("PART_NUMBER" "AL086950A00")
			("STANDARD" "")
			("LIFECYCLE" "")
			("JEDEC_TYPE" "LGA17_5X4")
			("DESCRIPTION" "IC OTHER(27P)MP86950GLVT-Z(LGA)")
			("MANUFTR" "MPS")
			("MANUF_PN" "MP86950GLVT-Z")
			("RD_CMPLS_LVL" "EP(V1)")
			("CMPLS_LVL" "")
			("FROM_PJ" "S69-CARSON")
			("CLASS" "IC")
			("DIP_SMD" "")
			("DATA" "MPS_MP86950GLVT-Z.pdf")
			("EE_CHECK_LIST" "")
			("FP_ECN" "")
			("PSL" "")
			("CREATOR" "")
			("STATUS" "")
			("MSD" "Level-3")
			("ESD_CDM" "NA")
			("ESD_HBM" "NA")
			("ESD_MM" "NA")
			("PIN_LENGTH_SHORT_PIN" "0 MILS")
			("PIN_LENGTH_LONG_PIN" "0 MILS")
			("CREATEDAY" "20180807")
			("LOCATION" "PU36")
		)
		("@t6g_mb_lib.t6g(sch_1):page316_i12@pure_quanta.raa2213404gnphb0(chips)"
			("VARIANT" "*")
			("VALUE" "MP86950GLVT-Z")
			("PART_TYPE" "SMLF")
			("MATERIAL" "IC")
			("PART_NUMBER" "AL086950A00")
			("STANDARD" "")
			("LIFECYCLE" "")
			("JEDEC_TYPE" "LGA17_5X4")
			("DESCRIPTION" "IC OTHER(27P)MP86950GLVT-Z(LGA)")
			("MANUFTR" "MPS")
			("MANUF_PN" "MP86950GLVT-Z")
			("RD_CMPLS_LVL" "EP(V1)")
			("CMPLS_LVL" "")
			("FROM_PJ" "S69-CARSON")
			("CLASS" "IC")
			("DIP_SMD" "")
			("DATA" "MPS_MP86950GLVT-Z.pdf")
			("EE_CHECK_LIST" "")
			("FP_ECN" "")
			("PSL" "")
			("CREATOR" "")
			("STATUS" "")
			("MSD" "Level-3")
			("ESD_CDM" "NA")
			("ESD_HBM" "NA")
			("ESD_MM" "NA")
			("PIN_LENGTH_SHORT_PIN" "0 MILS")
			("PIN_LENGTH_LONG_PIN" "0 MILS")
			("CREATEDAY" "20180807")
			("LOCATION" "PU51_P1_2")
		)
		("@t6g_mb_lib.t6g(sch_1):page316_i17@pure_quanta.raa2213404gnphb0(chips)"
			("VARIANT" "*")
			("VALUE" "MP86950GLVT-Z")
			("PART_TYPE" "SMLF")
			("MATERIAL" "IC")
			("PART_NUMBER" "AL086950A00")
			("STANDARD" "")
			("LIFECYCLE" "")
			("JEDEC_TYPE" "LGA17_5X4")
			("DESCRIPTION" "IC OTHER(27P)MP86950GLVT-Z(LGA)")
			("MANUFTR" "MPS")
			("MANUF_PN" "MP86950GLVT-Z")
			("RD_CMPLS_LVL" "EP(V1)")
			("CMPLS_LVL" "")
			("FROM_PJ" "S69-CARSON")
			("CLASS" "IC")
			("DIP_SMD" "")
			("DATA" "MPS_MP86950GLVT-Z.pdf")
			("EE_CHECK_LIST" "")
			("FP_ECN" "")
			("PSL" "")
			("CREATOR" "")
			("STATUS" "")
			("MSD" "Level-3")
			("ESD_CDM" "NA")
			("ESD_HBM" "NA")
			("ESD_MM" "NA")
			("PIN_LENGTH_SHORT_PIN" "0 MILS")
			("PIN_LENGTH_LONG_PIN" "0 MILS")
			("CREATEDAY" "20180807")
			("LOCATION" "PU50_P1_1")
		)
		("@t6g_mb_lib.t6g(sch_1):page317_i14@pure_quanta.raa2213404gnphb0(chips)"
			("VARIANT" "*")
			("VALUE" "MP86950GLVT-Z")
			("PART_TYPE" "SMLF")
			("MATERIAL" "IC")
			("PART_NUMBER" "AL086950A00")
			("STANDARD" "")
			("LIFECYCLE" "")
			("JEDEC_TYPE" "LGA17_5X4")
			("DESCRIPTION" "IC OTHER(27P)MP86950GLVT-Z(LGA)")
			("MANUFTR" "MPS")
			("MANUF_PN" "MP86950GLVT-Z")
			("RD_CMPLS_LVL" "EP(V1)")
			("CMPLS_LVL" "")
			("FROM_PJ" "S69-CARSON")
			("CLASS" "IC")
			("DIP_SMD" "")
			("DATA" "MPS_MP86950GLVT-Z.pdf")
			("EE_CHECK_LIST" "")
			("FP_ECN" "")
			("PSL" "")
			("CREATOR" "")
			("STATUS" "")
			("MSD" "Level-3")
			("ESD_CDM" "NA")
			("ESD_HBM" "NA")
			("ESD_MM" "NA")
			("PIN_LENGTH_SHORT_PIN" "0 MILS")
			("PIN_LENGTH_LONG_PIN" "0 MILS")
			("CREATEDAY" "20180807")
			("LOCATION" "PU49")
		)
		("@t6g_mb_lib.t6g(sch_1):page320_i38@pure_quanta.raa2213404gnphb0(chips)"
			("VARIANT" "*")
			("VALUE" "MP86950GLVT-Z")
			("PART_TYPE" "SMLF")
			("MATERIAL" "IC")
			("PART_NUMBER" "AL086950A00")
			("STANDARD" "")
			("LIFECYCLE" "")
			("JEDEC_TYPE" "LGA17_5X4")
			("DESCRIPTION" "IC OTHER(27P)MP86950GLVT-Z(LGA)")
			("MANUFTR" "MPS")
			("MANUF_PN" "MP86950GLVT-Z")
			("RD_CMPLS_LVL" "EP(V1)")
			("CMPLS_LVL" "")
			("FROM_PJ" "S69-CARSON")
			("CLASS" "IC")
			("DIP_SMD" "")
			("DATA" "MPS_MP86950GLVT-Z.pdf")
			("EE_CHECK_LIST" "")
			("FP_ECN" "")
			("PSL" "")
			("CREATOR" "")
			("STATUS" "")
			("MSD" "Level-3")
			("ESD_CDM" "NA")
			("ESD_HBM" "NA")
			("ESD_MM" "NA")
			("PIN_LENGTH_SHORT_PIN" "0 MILS")
			("PIN_LENGTH_LONG_PIN" "0 MILS")
			("CREATEDAY" "20180807")
			("LOCATION" "PU17")
		)
		("@t6g_mb_lib.t6g(sch_1):page298_i164@pure_quanta.raa2213404gnphb0(chips)"
			("VARIANT" "*")
			("VALUE" "MP86950GLVT-Z")
			("PART_TYPE" "SMLF")
			("MATERIAL" "IC")
			("PART_NUMBER" "AL086950A00")
			("STANDARD" "")
			("LIFECYCLE" "")
			("JEDEC_TYPE" "LGA17_5X4")
			("DESCRIPTION" "IC OTHER(27P)MP86950GLVT-Z(LGA)")
			("MANUFTR" "MPS")
			("MANUF_PN" "MP86950GLVT-Z")
			("RD_CMPLS_LVL" "EP(V1)")
			("CMPLS_LVL" "")
			("FROM_PJ" "S69-CARSON")
			("CLASS" "IC")
			("DIP_SMD" "")
			("DATA" "MPS_MP86950GLVT-Z.pdf")
			("EE_CHECK_LIST" "")
			("FP_ECN" "")
			("PSL" "")
			("CREATOR" "")
			("STATUS" "")
			("MSD" "Level-3")
			("ESD_CDM" "NA")
			("ESD_HBM" "NA")
			("ESD_MM" "NA")
			("PIN_LENGTH_SHORT_PIN" "0 MILS")
			("PIN_LENGTH_LONG_PIN" "0 MILS")
			("CREATEDAY" "20180807")
			("LOCATION" "PU44_P0_2")
		)
		("@t6g_mb_lib.t6g(sch_1):page298_i166@pure_quanta.raa2213404gnphb0(chips)"
			("VARIANT" "*")
			("PART_TYPE" "SMLF")
			("MATERIAL" "IC")
			("VALUE" "MP86950GLVT-Z")
			("PART_NUMBER" "AL086950A00")
			("PIN_LENGTH_LONG_PIN" "0 MILS")
			("MSD" "Level-3")
			("DESCRIPTION" "IC OTHER(27P)MP86950GLVT-Z(LGA)")
			("EE_CHECK_LIST" "")
			("CLASS" "IC")
			("MANUFTR" "MPS")
			("ESD_MM" "NA")
			("ESD_CDM" "NA")
			("FROM_PJ" "S69-CARSON")
			("DIP_SMD" "")
			("CREATEDAY" "20180807")
			("STANDARD" "")
			("PIN_LENGTH_SHORT_PIN" "0 MILS")
			("ESD_HBM" "NA")
			("LIFECYCLE" "")
			("STATUS" "")
			("PSL" "")
			("RD_CMPLS_LVL" "EP(V1)")
			("FP_ECN" "")
			("MANUF_PN" "MP86950GLVT-Z")
			("CMPLS_LVL" "")
			("JEDEC_TYPE" "LGA17_5X4")
			("DATA" "MPS_MP86950GLVT-Z.pdf")
			("CREATOR" "")
			("LOCATION" "PU43_P0_1")
		)
		("@t6g_mb_lib.t6g(sch_1):page299_i11@pure_quanta.raa2213404gnphb0(chips)"
			("VARIANT" "*")
			("VALUE" "MP86950GLVT-Z")
			("PART_TYPE" "SMLF")
			("MATERIAL" "IC")
			("PART_NUMBER" "AL086950A00")
			("STANDARD" "")
			("LIFECYCLE" "")
			("JEDEC_TYPE" "LGA17_5X4")
			("DESCRIPTION" "IC OTHER(27P)MP86950GLVT-Z(LGA)")
			("MANUFTR" "MPS")
			("MANUF_PN" "MP86950GLVT-Z")
			("RD_CMPLS_LVL" "EP(V1)")
			("CMPLS_LVL" "")
			("FROM_PJ" "S69-CARSON")
			("CLASS" "IC")
			("DIP_SMD" "")
			("DATA" "MPS_MP86950GLVT-Z.pdf")
			("EE_CHECK_LIST" "")
			("FP_ECN" "")
			("PSL" "")
			("CREATOR" "")
			("STATUS" "")
			("MSD" "Level-3")
			("ESD_CDM" "NA")
			("ESD_HBM" "NA")
			("ESD_MM" "NA")
			("PIN_LENGTH_SHORT_PIN" "0 MILS")
			("PIN_LENGTH_LONG_PIN" "0 MILS")
			("CREATEDAY" "20180807")
			("LOCATION" "PU42")
		)
		("@t6g_mb_lib.t6g(sch_1):page182_i183@pure_quanta.conn2_aaabat029p15(chips)"
			("LOCATION" "BT1")
		)
		("@t6g_mb_lib.t6g(sch_1):page182_i190@pure_quanta.q_cap(chips)"
			("LOCATION" "C610")
		)
		("@t6g_mb_lib.t6g(sch_1):page182_i171@pure_quanta.q_cap(chips)"
			("LOCATION" "C611")
		)
		("@t6g_mb_lib.t6g(sch_1):page182_i161@pure_quanta.mosfet_n_gsd(chips)"
			("LOCATION" "Q108")
		)
		("@t6g_mb_lib.t6g(sch_1):page182_i157@pure_quanta.mosfet_n_gsd(chips)"
			("LOCATION" "Q109")
		)
		("@t6g_mb_lib.t6g(sch_1):page182_i109@pure_quanta.q_res(chips)"
			("LOCATION" "R7P4")
		)
		("@t6g_mb_lib.t6g(sch_1):page182_i191@pure_quanta.q_res(chips)"
			("LOCATION" "R1202")
		)
		("@t6g_mb_lib.t6g(sch_1):page182_i164@pure_quanta.q_res(chips)"
			("LOCATION" "R1839")
		)
		("@t6g_mb_lib.t6g(sch_1):page182_i165@pure_quanta.q_res(chips)"
			("LOCATION" "R1840")
		)
		("@t6g_mb_lib.t6g(sch_1):page182_i180@pure_quanta.q_res(chips)"
			("LOCATION" "R2456")
		)
		("@t6g_mb_lib.t6g(sch_1):page182_i163@pure_quanta.q_res(chips)"
			("LOCATION" "R2457")
		)
		("@t6g_mb_lib.t6g(sch_1):page182_i184@pure_quanta.q_res(chips)"
			("LOCATION" "R3760")
		)
		("@t6g_mb_lib.t6g(sch_1):page182_i186@pure_quanta.q_res(chips)"
			("LOCATION" "R3761")
		)
		("@t6g_mb_lib.t6g(sch_1):page182_i137@pure_quanta.emmitsburg_rev0p9(chips)"
			("LOCATION" "U8")
		)
		("@t6g_mb_lib.t6g(sch_1):page182_i174@pure_quanta.bas70057f(chips)"
			("LOCATION" "U62")
		)
		("@t6g_mb_lib.t6g(sch_1):page40_i34@pure_quanta.q_cap(chips)"
			("LOCATION" "C1")
		)
		("@t6g_mb_lib.t6g(sch_1):page40_i52@pure_quanta.socket4677_azifs035p001c01(chips)"
			("LOCATION" "U2")
		)
		("@t6g_mb_lib.t6g(sch_1):page40_i53@pure_quanta.socket4677_azifs035p001c01(chips)"
			("LOCATION" "U2")
		)
		("@t6g_mb_lib.t6g(sch_1):page102_i506@pure_quanta.q_cap(chips)"
			("LOCATION" "C2")
		)
		("@t6g_mb_lib.t6g(sch_1):page102_i510@pure_quanta.q_cap(chips)"
			("LOCATION" "C3")
		)
		("@t6g_mb_lib.t6g(sch_1):page102_i502@pure_quanta.q_cap(chips)"
			("LOCATION" "C4")
		)
		("@t6g_mb_lib.t6g(sch_1):page102_i511@pure_quanta.sconn288_adr50001p013c01(chips)"
			("LOCATION" "J1")
		)
		("@t6g_mb_lib.t6g(sch_1):page102_i512@pure_quanta.sconn288_adr50001p013c01(chips)"
			("LOCATION" "J1")
		)
		("@t6g_mb_lib.t6g(sch_1):page102_i513@pure_quanta.sconn288_adr50001p013c01(chips)"
			("LOCATION" "J1")
		)
		("@t6g_mb_lib.t6g(sch_1):page102_i499@pure_quanta.q_res(chips)"
			("LOCATION" "R26")
		)
		("@t6g_mb_lib.t6g(sch_1):page103_i354@pure_quanta.q_cap(chips)"
			("LOCATION" "C5")
		)
		("@t6g_mb_lib.t6g(sch_1):page103_i357@pure_quanta.q_cap(chips)"
			("LOCATION" "C6")
		)
		("@t6g_mb_lib.t6g(sch_1):page103_i351@pure_quanta.q_cap(chips)"
			("LOCATION" "C7")
		)
		("@t6g_mb_lib.t6g(sch_1):page103_i358@pure_quanta.sconn288_adr50001p003c01(chips)"
			("LOCATION" "J2")
		)
		("@t6g_mb_lib.t6g(sch_1):page103_i359@pure_quanta.sconn288_adr50001p003c01(chips)"
			("LOCATION" "J2")
		)
		("@t6g_mb_lib.t6g(sch_1):page103_i360@pure_quanta.sconn288_adr50001p003c01(chips)"
			("LOCATION" "J2")
		)
		("@t6g_mb_lib.t6g(sch_1):page103_i362@pure_quanta.q_res(chips)"
			("LOCATION" "R27")
		)
		("@t6g_mb_lib.t6g(sch_1):page104_i338@pure_quanta.q_cap(chips)"
			("LOCATION" "C8")
		)
		("@t6g_mb_lib.t6g(sch_1):page104_i344@pure_quanta.q_cap(chips)"
			("LOCATION" "C9")
		)
		("@t6g_mb_lib.t6g(sch_1):page104_i341@pure_quanta.q_cap(chips)"
			("LOCATION" "C10")
		)
		("@t6g_mb_lib.t6g(sch_1):page104_i345@pure_quanta.sconn288_adr50001p013c01(chips)"
			("LOCATION" "J3")
		)
		("@t6g_mb_lib.t6g(sch_1):page104_i346@pure_quanta.sconn288_adr50001p013c01(chips)"
			("LOCATION" "J3")
		)
		("@t6g_mb_lib.t6g(sch_1):page104_i347@pure_quanta.sconn288_adr50001p013c01(chips)"
			("LOCATION" "J3")
		)
		("@t6g_mb_lib.t6g(sch_1):page104_i349@pure_quanta.q_res(chips)"
			("LOCATION" "R28")
		)
		("@t6g_mb_lib.t6g(sch_1):page105_i340@pure_quanta.q_cap(chips)"
			("LOCATION" "C11")
		)
		("@t6g_mb_lib.t6g(sch_1):page105_i344@pure_quanta.q_cap(chips)"
			("LOCATION" "C12")
		)
		("@t6g_mb_lib.t6g(sch_1):page105_i338@pure_quanta.q_cap(chips)"
			("LOCATION" "C1372")
		)
		("@t6g_mb_lib.t6g(sch_1):page105_i345@pure_quanta.sconn288_adr50001p003c01(chips)"
			("LOCATION" "J4")
		)
		("@t6g_mb_lib.t6g(sch_1):page105_i346@pure_quanta.sconn288_adr50001p003c01(chips)"
			("LOCATION" "J4")
		)
		("@t6g_mb_lib.t6g(sch_1):page105_i347@pure_quanta.sconn288_adr50001p003c01(chips)"
			("LOCATION" "J4")
		)
		("@t6g_mb_lib.t6g(sch_1):page105_i348@pure_quanta.q_res(chips)"
			("LOCATION" "R29")
		)
		("@t6g_mb_lib.t6g(sch_1):page150_i64@pure_quanta.q_cap(chips)"
			("LOCATION" "C13")
		)
		("@t6g_mb_lib.t6g(sch_1):page150_i72@pure_quanta.q_cap(chips)"
			("LOCATION" "C898")
		)
		("@t6g_mb_lib.t6g(sch_1):page150_i51@pure_quanta.q_cap(chips)"
			("LOCATION" "C899")
		)
		("@t6g_mb_lib.t6g(sch_1):page150_i45@pure_quanta.q_cap(chips)"
			("LOCATION" "C900")
		)
		("@t6g_mb_lib.t6g(sch_1):page150_i76@pure_quanta.q_cap(chips)"
			("LOCATION" "C2509")
		)
		("@t6g_mb_lib.t6g(sch_1):page150_i57@pure_quanta.q_cap(chips)"
			("LOCATION" "C2510")
		)
		("@t6g_mb_lib.t6g(sch_1):page150_i74@pure_quanta.diode_tvs(chips)"
			("LOCATION" "D58")
		)
		("@t6g_mb_lib.t6g(sch_1):page150_i48@pure_quanta.schottky_ac(chips)"
			("LOCATION" "D59")
		)
		("@t6g_mb_lib.t6g(sch_1):page150_i69@pure_quanta.q_short(chips)"
			("LOCATION" "J271")
		)
		("@t6g_mb_lib.t6g(sch_1):page150_i68@pure_quanta.q_short(chips)"
			("LOCATION" "J272")
		)
		("@t6g_mb_lib.t6g(sch_1):page150_i55@pure_quanta.q_res(chips)"
			("LOCATION" "R1137")
		)
		("@t6g_mb_lib.t6g(sch_1):page150_i67@pure_quanta.q_res(chips)"
			("LOCATION" "R2654")
		)
		("@t6g_mb_lib.t6g(sch_1):page150_i43@pure_quanta.q_res(chips)"
			("LOCATION" "R2655")
		)
		("@t6g_mb_lib.t6g(sch_1):page150_i62@pure_quanta.tps259521dsgr(chips)"
			("LOCATION" "U24")
		)
		("@t6g_mb_lib.t6g(sch_1):page150_i50@pure_quanta.tps259541dsgr(chips)"
			("LOCATION" "U38")
		)
		("@t6g_mb_lib.t6g(sch_1):page106_i340@pure_quanta.q_cap(chips)"
			("LOCATION" "C14")
		)
		("@t6g_mb_lib.t6g(sch_1):page106_i344@pure_quanta.q_cap(chips)"
			("LOCATION" "C15")
		)
		("@t6g_mb_lib.t6g(sch_1):page106_i338@pure_quanta.q_cap(chips)"
			("LOCATION" "C16")
		)
		("@t6g_mb_lib.t6g(sch_1):page106_i345@pure_quanta.sconn288_adr50001p013c01(chips)"
			("LOCATION" "J5")
		)
		("@t6g_mb_lib.t6g(sch_1):page106_i346@pure_quanta.sconn288_adr50001p013c01(chips)"
			("LOCATION" "J5")
		)
		("@t6g_mb_lib.t6g(sch_1):page106_i347@pure_quanta.sconn288_adr50001p013c01(chips)"
			("LOCATION" "J5")
		)
		("@t6g_mb_lib.t6g(sch_1):page106_i349@pure_quanta.q_res(chips)"
			("LOCATION" "R30")
		)
		("@t6g_mb_lib.t6g(sch_1):page107_i340@pure_quanta.q_cap(chips)"
			("LOCATION" "C17")
		)
		("@t6g_mb_lib.t6g(sch_1):page107_i344@pure_quanta.q_cap(chips)"
			("LOCATION" "C18")
		)
		("@t6g_mb_lib.t6g(sch_1):page107_i338@pure_quanta.q_cap(chips)"
			("LOCATION" "C19")
		)
		("@t6g_mb_lib.t6g(sch_1):page107_i345@pure_quanta.sconn288_adr50001p003c01(chips)"
			("LOCATION" "J6")
		)
		("@t6g_mb_lib.t6g(sch_1):page107_i346@pure_quanta.sconn288_adr50001p003c01(chips)"
			("LOCATION" "J6")
		)
		("@t6g_mb_lib.t6g(sch_1):page107_i347@pure_quanta.sconn288_adr50001p003c01(chips)"
			("LOCATION" "J6")
		)
		("@t6g_mb_lib.t6g(sch_1):page107_i349@pure_quanta.q_res(chips)"
			("LOCATION" "R31")
		)
		("@t6g_mb_lib.t6g(sch_1):page108_i340@pure_quanta.q_cap(chips)"
			("LOCATION" "C20")
		)
		("@t6g_mb_lib.t6g(sch_1):page108_i344@pure_quanta.q_cap(chips)"
			("LOCATION" "C21")
		)
		("@t6g_mb_lib.t6g(sch_1):page108_i338@pure_quanta.q_cap(chips)"
			("LOCATION" "C22")
		)
		("@t6g_mb_lib.t6g(sch_1):page108_i345@pure_quanta.sconn288_adr50001p013c01(chips)"
			("LOCATION" "J7")
		)
		("@t6g_mb_lib.t6g(sch_1):page108_i346@pure_quanta.sconn288_adr50001p013c01(chips)"
			("LOCATION" "J7")
		)
		("@t6g_mb_lib.t6g(sch_1):page108_i347@pure_quanta.sconn288_adr50001p013c01(chips)"
			("LOCATION" "J7")
		)
		("@t6g_mb_lib.t6g(sch_1):page108_i349@pure_quanta.q_res(chips)"
			("LOCATION" "R32")
		)
		("@t6g_mb_lib.t6g(sch_1):page109_i341@pure_quanta.q_cap(chips)"
			("LOCATION" "C23")
		)
		("@t6g_mb_lib.t6g(sch_1):page109_i345@pure_quanta.q_cap(chips)"
			("LOCATION" "C24")
		)
		("@t6g_mb_lib.t6g(sch_1):page109_i339@pure_quanta.q_cap(chips)"
			("LOCATION" "C25")
		)
		("@t6g_mb_lib.t6g(sch_1):page109_i346@pure_quanta.sconn288_adr50001p003c01(chips)"
			("LOCATION" "J8")
		)
		("@t6g_mb_lib.t6g(sch_1):page109_i347@pure_quanta.sconn288_adr50001p003c01(chips)"
			("LOCATION" "J8")
		)
		("@t6g_mb_lib.t6g(sch_1):page109_i348@pure_quanta.sconn288_adr50001p003c01(chips)"
			("LOCATION" "J8")
		)
		("@t6g_mb_lib.t6g(sch_1):page109_i350@pure_quanta.q_res(chips)"
			("LOCATION" "R33")
		)
		("@t6g_mb_lib.t6g(sch_1):page110_i338@pure_quanta.q_cap(chips)"
			("LOCATION" "C26")
		)
		("@t6g_mb_lib.t6g(sch_1):page110_i343@pure_quanta.q_cap(chips)"
			("LOCATION" "C27")
		)
		("@t6g_mb_lib.t6g(sch_1):page110_i336@pure_quanta.q_cap(chips)"
			("LOCATION" "C28")
		)
		("@t6g_mb_lib.t6g(sch_1):page110_i344@pure_quanta.sconn288_adr50001p013c01(chips)"
			("LOCATION" "J9")
		)
		("@t6g_mb_lib.t6g(sch_1):page110_i345@pure_quanta.sconn288_adr50001p013c01(chips)"
			("LOCATION" "J9")
		)
		("@t6g_mb_lib.t6g(sch_1):page110_i346@pure_quanta.sconn288_adr50001p013c01(chips)"
			("LOCATION" "J9")
		)
		("@t6g_mb_lib.t6g(sch_1):page110_i331@pure_quanta.q_res(chips)"
			("LOCATION" "R34")
		)
		("@t6g_mb_lib.t6g(sch_1):page111_i341@pure_quanta.q_cap(chips)"
			("LOCATION" "C29")
		)
		("@t6g_mb_lib.t6g(sch_1):page111_i344@pure_quanta.q_cap(chips)"
			("LOCATION" "C30")
		)
		("@t6g_mb_lib.t6g(sch_1):page111_i338@pure_quanta.q_cap(chips)"
			("LOCATION" "C31")
		)
		("@t6g_mb_lib.t6g(sch_1):page111_i345@pure_quanta.sconn288_adr50001p003c01(chips)"
			("LOCATION" "J10")
		)
		("@t6g_mb_lib.t6g(sch_1):page111_i346@pure_quanta.sconn288_adr50001p003c01(chips)"
			("LOCATION" "J10")
		)
		("@t6g_mb_lib.t6g(sch_1):page111_i347@pure_quanta.sconn288_adr50001p003c01(chips)"
			("LOCATION" "J10")
		)
		("@t6g_mb_lib.t6g(sch_1):page111_i349@pure_quanta.q_res(chips)"
			("LOCATION" "R35")
		)
		("@t6g_mb_lib.t6g(sch_1):page112_i341@pure_quanta.q_cap(chips)"
			("LOCATION" "C32")
		)
		("@t6g_mb_lib.t6g(sch_1):page112_i344@pure_quanta.q_cap(chips)"
			("LOCATION" "C33")
		)
		("@t6g_mb_lib.t6g(sch_1):page112_i338@pure_quanta.q_cap(chips)"
			("LOCATION" "C34")
		)
		("@t6g_mb_lib.t6g(sch_1):page112_i345@pure_quanta.sconn288_adr50001p013c01(chips)"
			("LOCATION" "J11")
		)
		("@t6g_mb_lib.t6g(sch_1):page112_i346@pure_quanta.sconn288_adr50001p013c01(chips)"
			("LOCATION" "J11")
		)
		("@t6g_mb_lib.t6g(sch_1):page112_i347@pure_quanta.sconn288_adr50001p013c01(chips)"
			("LOCATION" "J11")
		)
		("@t6g_mb_lib.t6g(sch_1):page112_i349@pure_quanta.q_res(chips)"
			("LOCATION" "R36")
		)
		("@t6g_mb_lib.t6g(sch_1):page113_i341@pure_quanta.q_cap(chips)"
			("LOCATION" "C35")
		)
		("@t6g_mb_lib.t6g(sch_1):page113_i344@pure_quanta.q_cap(chips)"
			("LOCATION" "C36")
		)
		("@t6g_mb_lib.t6g(sch_1):page113_i338@pure_quanta.q_cap(chips)"
			("LOCATION" "C37")
		)
		("@t6g_mb_lib.t6g(sch_1):page113_i345@pure_quanta.sconn288_adr50001p003c01(chips)"
			("LOCATION" "J12")
		)
		("@t6g_mb_lib.t6g(sch_1):page113_i346@pure_quanta.sconn288_adr50001p003c01(chips)"
			("LOCATION" "J12")
		)
		("@t6g_mb_lib.t6g(sch_1):page113_i347@pure_quanta.sconn288_adr50001p003c01(chips)"
			("LOCATION" "J12")
		)
		("@t6g_mb_lib.t6g(sch_1):page113_i348@pure_quanta.q_res(chips)"
			("LOCATION" "R37")
		)
		("@t6g_mb_lib.t6g(sch_1):page114_i341@pure_quanta.q_cap(chips)"
			("LOCATION" "C38")
		)
		("@t6g_mb_lib.t6g(sch_1):page114_i344@pure_quanta.q_cap(chips)"
			("LOCATION" "C39")
		)
		("@t6g_mb_lib.t6g(sch_1):page114_i338@pure_quanta.q_cap(chips)"
			("LOCATION" "C40")
		)
		("@t6g_mb_lib.t6g(sch_1):page114_i345@pure_quanta.sconn288_adr50001p013c01(chips)"
			("LOCATION" "J13")
		)
		("@t6g_mb_lib.t6g(sch_1):page114_i346@pure_quanta.sconn288_adr50001p013c01(chips)"
			("LOCATION" "J13")
		)
		("@t6g_mb_lib.t6g(sch_1):page114_i347@pure_quanta.sconn288_adr50001p013c01(chips)"
			("LOCATION" "J13")
		)
		("@t6g_mb_lib.t6g(sch_1):page114_i348@pure_quanta.q_res(chips)"
			("LOCATION" "R38")
		)
		("@t6g_mb_lib.t6g(sch_1):page115_i341@pure_quanta.q_cap(chips)"
			("LOCATION" "C41")
		)
		("@t6g_mb_lib.t6g(sch_1):page115_i344@pure_quanta.q_cap(chips)"
			("LOCATION" "C42")
		)
		("@t6g_mb_lib.t6g(sch_1):page115_i338@pure_quanta.q_cap(chips)"
			("LOCATION" "C43")
		)
		("@t6g_mb_lib.t6g(sch_1):page115_i345@pure_quanta.sconn288_adr50001p003c01(chips)"
			("LOCATION" "J14")
		)
		("@t6g_mb_lib.t6g(sch_1):page115_i346@pure_quanta.sconn288_adr50001p003c01(chips)"
			("LOCATION" "J14")
		)
		("@t6g_mb_lib.t6g(sch_1):page115_i347@pure_quanta.sconn288_adr50001p003c01(chips)"
			("LOCATION" "J14")
		)
		("@t6g_mb_lib.t6g(sch_1):page115_i348@pure_quanta.q_res(chips)"
			("LOCATION" "R39")
		)
		("@t6g_mb_lib.t6g(sch_1):page116_i341@pure_quanta.q_cap(chips)"
			("LOCATION" "C44")
		)
		("@t6g_mb_lib.t6g(sch_1):page116_i344@pure_quanta.q_cap(chips)"
			("LOCATION" "C45")
		)
		("@t6g_mb_lib.t6g(sch_1):page116_i338@pure_quanta.q_cap(chips)"
			("LOCATION" "C46")
		)
		("@t6g_mb_lib.t6g(sch_1):page116_i345@pure_quanta.sconn288_adr50001p013c01(chips)"
			("LOCATION" "J15")
		)
		("@t6g_mb_lib.t6g(sch_1):page116_i346@pure_quanta.sconn288_adr50001p013c01(chips)"
			("LOCATION" "J15")
		)
		("@t6g_mb_lib.t6g(sch_1):page116_i347@pure_quanta.sconn288_adr50001p013c01(chips)"
			("LOCATION" "J15")
		)
		("@t6g_mb_lib.t6g(sch_1):page116_i348@pure_quanta.q_res(chips)"
			("LOCATION" "R40")
		)
		("@t6g_mb_lib.t6g(sch_1):page117_i341@pure_quanta.q_cap(chips)"
			("LOCATION" "C47")
		)
		("@t6g_mb_lib.t6g(sch_1):page117_i344@pure_quanta.q_cap(chips)"
			("LOCATION" "C48")
		)
		("@t6g_mb_lib.t6g(sch_1):page117_i339@pure_quanta.q_cap(chips)"
			("LOCATION" "C49")
		)
		("@t6g_mb_lib.t6g(sch_1):page117_i345@pure_quanta.sconn288_adr50001p003c01(chips)"
			("LOCATION" "J16")
		)
		("@t6g_mb_lib.t6g(sch_1):page117_i346@pure_quanta.sconn288_adr50001p003c01(chips)"
			("LOCATION" "J16")
		)
		("@t6g_mb_lib.t6g(sch_1):page117_i347@pure_quanta.sconn288_adr50001p003c01(chips)"
			("LOCATION" "J16")
		)
		("@t6g_mb_lib.t6g(sch_1):page117_i348@pure_quanta.q_res(chips)"
			("LOCATION" "R41")
		)
		("@t6g_mb_lib.t6g(sch_1):page118_i506@pure_quanta.q_cap(chips)"
			("LOCATION" "C50")
		)
		("@t6g_mb_lib.t6g(sch_1):page118_i510@pure_quanta.q_cap(chips)"
			("LOCATION" "C51")
		)
		("@t6g_mb_lib.t6g(sch_1):page118_i504@pure_quanta.q_cap(chips)"
			("LOCATION" "C52")
		)
		("@t6g_mb_lib.t6g(sch_1):page118_i511@pure_quanta.sconn288_adr50001p013c01(chips)"
			("LOCATION" "J17")
		)
		("@t6g_mb_lib.t6g(sch_1):page118_i512@pure_quanta.sconn288_adr50001p013c01(chips)"
			("LOCATION" "J17")
		)
		("@t6g_mb_lib.t6g(sch_1):page118_i513@pure_quanta.sconn288_adr50001p013c01(chips)"
			("LOCATION" "J17")
		)
		("@t6g_mb_lib.t6g(sch_1):page118_i499@pure_quanta.q_res(chips)"
			("LOCATION" "R42")
		)
		("@t6g_mb_lib.t6g(sch_1):page119_i354@pure_quanta.q_cap(chips)"
			("LOCATION" "C53")
		)
		("@t6g_mb_lib.t6g(sch_1):page119_i357@pure_quanta.q_cap(chips)"
			("LOCATION" "C54")
		)
		("@t6g_mb_lib.t6g(sch_1):page119_i351@pure_quanta.q_cap(chips)"
			("LOCATION" "C55")
		)
		("@t6g_mb_lib.t6g(sch_1):page119_i358@pure_quanta.sconn288_adr50001p003c01(chips)"
			("LOCATION" "J18")
		)
		("@t6g_mb_lib.t6g(sch_1):page119_i359@pure_quanta.sconn288_adr50001p003c01(chips)"
			("LOCATION" "J18")
		)
		("@t6g_mb_lib.t6g(sch_1):page119_i360@pure_quanta.sconn288_adr50001p003c01(chips)"
			("LOCATION" "J18")
		)
		("@t6g_mb_lib.t6g(sch_1):page119_i361@pure_quanta.q_res(chips)"
			("LOCATION" "R43")
		)
		("@t6g_mb_lib.t6g(sch_1):page120_i341@pure_quanta.q_cap(chips)"
			("LOCATION" "C56")
		)
		("@t6g_mb_lib.t6g(sch_1):page120_i344@pure_quanta.q_cap(chips)"
			("LOCATION" "C57")
		)
		("@t6g_mb_lib.t6g(sch_1):page120_i338@pure_quanta.q_cap(chips)"
			("LOCATION" "C58")
		)
		("@t6g_mb_lib.t6g(sch_1):page120_i345@pure_quanta.sconn288_adr50001p013c01(chips)"
			("LOCATION" "J19")
		)
		("@t6g_mb_lib.t6g(sch_1):page120_i346@pure_quanta.sconn288_adr50001p013c01(chips)"
			("LOCATION" "J19")
		)
		("@t6g_mb_lib.t6g(sch_1):page120_i347@pure_quanta.sconn288_adr50001p013c01(chips)"
			("LOCATION" "J19")
		)
		("@t6g_mb_lib.t6g(sch_1):page120_i348@pure_quanta.q_res(chips)"
			("LOCATION" "R44")
		)
		("@t6g_mb_lib.t6g(sch_1):page121_i341@pure_quanta.q_cap(chips)"
			("LOCATION" "C59")
		)
		("@t6g_mb_lib.t6g(sch_1):page121_i344@pure_quanta.q_cap(chips)"
			("LOCATION" "C60")
		)
		("@t6g_mb_lib.t6g(sch_1):page121_i338@pure_quanta.q_cap(chips)"
			("LOCATION" "C61")
		)
		("@t6g_mb_lib.t6g(sch_1):page121_i345@pure_quanta.sconn288_adr50001p003c01(chips)"
			("LOCATION" "J20")
		)
		("@t6g_mb_lib.t6g(sch_1):page121_i346@pure_quanta.sconn288_adr50001p003c01(chips)"
			("LOCATION" "J20")
		)
		("@t6g_mb_lib.t6g(sch_1):page121_i347@pure_quanta.sconn288_adr50001p003c01(chips)"
			("LOCATION" "J20")
		)
		("@t6g_mb_lib.t6g(sch_1):page121_i348@pure_quanta.q_res(chips)"
			("LOCATION" "R45")
		)
		("@t6g_mb_lib.t6g(sch_1):page122_i341@pure_quanta.q_cap(chips)"
			("LOCATION" "C62")
		)
		("@t6g_mb_lib.t6g(sch_1):page122_i344@pure_quanta.q_cap(chips)"
			("LOCATION" "C63")
		)
		("@t6g_mb_lib.t6g(sch_1):page122_i338@pure_quanta.q_cap(chips)"
			("LOCATION" "C64")
		)
		("@t6g_mb_lib.t6g(sch_1):page122_i345@pure_quanta.sconn288_adr50001p013c01(chips)"
			("LOCATION" "J21")
		)
		("@t6g_mb_lib.t6g(sch_1):page122_i346@pure_quanta.sconn288_adr50001p013c01(chips)"
			("LOCATION" "J21")
		)
		("@t6g_mb_lib.t6g(sch_1):page122_i347@pure_quanta.sconn288_adr50001p013c01(chips)"
			("LOCATION" "J21")
		)
		("@t6g_mb_lib.t6g(sch_1):page122_i348@pure_quanta.q_res(chips)"
			("LOCATION" "R46")
		)
		("@t6g_mb_lib.t6g(sch_1):page123_i341@pure_quanta.q_cap(chips)"
			("LOCATION" "C65")
		)
		("@t6g_mb_lib.t6g(sch_1):page123_i344@pure_quanta.q_cap(chips)"
			("LOCATION" "C66")
		)
		("@t6g_mb_lib.t6g(sch_1):page123_i338@pure_quanta.q_cap(chips)"
			("LOCATION" "C67")
		)
		("@t6g_mb_lib.t6g(sch_1):page123_i347@pure_quanta.sconn288_adr50001p003c01(chips)"
			("LOCATION" "J22")
		)
		("@t6g_mb_lib.t6g(sch_1):page123_i346@pure_quanta.sconn288_adr50001p003c01(chips)"
			("LOCATION" "J22")
		)
		("@t6g_mb_lib.t6g(sch_1):page123_i345@pure_quanta.sconn288_adr50001p003c01(chips)"
			("LOCATION" "J22")
		)
		("@t6g_mb_lib.t6g(sch_1):page123_i348@pure_quanta.q_res(chips)"
			("LOCATION" "R47")
		)
		("@t6g_mb_lib.t6g(sch_1):page124_i341@pure_quanta.q_cap(chips)"
			("LOCATION" "C68")
		)
		("@t6g_mb_lib.t6g(sch_1):page124_i344@pure_quanta.q_cap(chips)"
			("LOCATION" "C69")
		)
		("@t6g_mb_lib.t6g(sch_1):page124_i338@pure_quanta.q_cap(chips)"
			("LOCATION" "C70")
		)
		("@t6g_mb_lib.t6g(sch_1):page124_i345@pure_quanta.sconn288_adr50001p013c01(chips)"
			("LOCATION" "J23")
		)
		("@t6g_mb_lib.t6g(sch_1):page124_i346@pure_quanta.sconn288_adr50001p013c01(chips)"
			("LOCATION" "J23")
		)
		("@t6g_mb_lib.t6g(sch_1):page124_i347@pure_quanta.sconn288_adr50001p013c01(chips)"
			("LOCATION" "J23")
		)
		("@t6g_mb_lib.t6g(sch_1):page124_i348@pure_quanta.q_res(chips)"
			("LOCATION" "R48")
		)
		("@t6g_mb_lib.t6g(sch_1):page71_i36@pure_quanta.q_cap(chips)"
			("LOCATION" "C71")
		)
		("@t6g_mb_lib.t6g(sch_1):page71_i52@pure_quanta.socket4677_azifs035p001c01(chips)"
			("LOCATION" "U1")
		)
		("@t6g_mb_lib.t6g(sch_1):page71_i53@pure_quanta.socket4677_azifs035p001c01(chips)"
			("LOCATION" "U1")
		)
		("@t6g_mb_lib.t6g(sch_1):page133_i340@pure_quanta.q_cap(chips)"
			("LOCATION" "C72")
		)
		("@t6g_mb_lib.t6g(sch_1):page133_i344@pure_quanta.q_cap(chips)"
			("LOCATION" "C73")
		)
		("@t6g_mb_lib.t6g(sch_1):page133_i338@pure_quanta.q_cap(chips)"
			("LOCATION" "C74")
		)
		("@t6g_mb_lib.t6g(sch_1):page133_i345@pure_quanta.sconn288_adr50001p003c01(chips)"
			("LOCATION" "J32")
		)
		("@t6g_mb_lib.t6g(sch_1):page133_i346@pure_quanta.sconn288_adr50001p003c01(chips)"
			("LOCATION" "J32")
		)
		("@t6g_mb_lib.t6g(sch_1):page133_i347@pure_quanta.sconn288_adr50001p003c01(chips)"
			("LOCATION" "J32")
		)
		("@t6g_mb_lib.t6g(sch_1):page133_i348@pure_quanta.q_res(chips)"
			("LOCATION" "R72")
		)
		("@t6g_mb_lib.t6g(sch_1):page132_i340@pure_quanta.q_cap(chips)"
			("LOCATION" "C75")
		)
		("@t6g_mb_lib.t6g(sch_1):page132_i344@pure_quanta.q_cap(chips)"
			("LOCATION" "C76")
		)
		("@t6g_mb_lib.t6g(sch_1):page132_i338@pure_quanta.q_cap(chips)"
			("LOCATION" "C77")
		)
		("@t6g_mb_lib.t6g(sch_1):page132_i345@pure_quanta.sconn288_adr50001p013c01(chips)"
			("LOCATION" "J31")
		)
		("@t6g_mb_lib.t6g(sch_1):page132_i346@pure_quanta.sconn288_adr50001p013c01(chips)"
			("LOCATION" "J31")
		)
		("@t6g_mb_lib.t6g(sch_1):page132_i347@pure_quanta.sconn288_adr50001p013c01(chips)"
			("LOCATION" "J31")
		)
		("@t6g_mb_lib.t6g(sch_1):page132_i348@pure_quanta.q_res(chips)"
			("LOCATION" "R73")
		)
		("@t6g_mb_lib.t6g(sch_1):page131_i340@pure_quanta.q_cap(chips)"
			("LOCATION" "C78")
		)
		("@t6g_mb_lib.t6g(sch_1):page131_i344@pure_quanta.q_cap(chips)"
			("LOCATION" "C79")
		)
		("@t6g_mb_lib.t6g(sch_1):page131_i338@pure_quanta.q_cap(chips)"
			("LOCATION" "C80")
		)
		("@t6g_mb_lib.t6g(sch_1):page131_i345@pure_quanta.sconn288_adr50001p003c01(chips)"
			("LOCATION" "J30")
		)
		("@t6g_mb_lib.t6g(sch_1):page131_i346@pure_quanta.sconn288_adr50001p003c01(chips)"
			("LOCATION" "J30")
		)
		("@t6g_mb_lib.t6g(sch_1):page131_i347@pure_quanta.sconn288_adr50001p003c01(chips)"
			("LOCATION" "J30")
		)
		("@t6g_mb_lib.t6g(sch_1):page131_i348@pure_quanta.q_res(chips)"
			("LOCATION" "R74")
		)
		("@t6g_mb_lib.t6g(sch_1):page130_i341@pure_quanta.q_cap(chips)"
			("LOCATION" "C81")
		)
		("@t6g_mb_lib.t6g(sch_1):page130_i344@pure_quanta.q_cap(chips)"
			("LOCATION" "C82")
		)
		("@t6g_mb_lib.t6g(sch_1):page130_i338@pure_quanta.q_cap(chips)"
			("LOCATION" "C83")
		)
		("@t6g_mb_lib.t6g(sch_1):page130_i346@pure_quanta.sconn288_adr50001p013c01(chips)"
			("LOCATION" "J29")
		)
		("@t6g_mb_lib.t6g(sch_1):page130_i347@pure_quanta.sconn288_adr50001p013c01(chips)"
			("LOCATION" "J29")
		)
		("@t6g_mb_lib.t6g(sch_1):page130_i345@pure_quanta.sconn288_adr50001p013c01(chips)"
			("LOCATION" "J29")
		)
		("@t6g_mb_lib.t6g(sch_1):page130_i348@pure_quanta.q_res(chips)"
			("LOCATION" "R75")
		)
		("@t6g_mb_lib.t6g(sch_1):page129_i341@pure_quanta.q_cap(chips)"
			("LOCATION" "C84")
		)
		("@t6g_mb_lib.t6g(sch_1):page129_i344@pure_quanta.q_cap(chips)"
			("LOCATION" "C85")
		)
		("@t6g_mb_lib.t6g(sch_1):page129_i338@pure_quanta.q_cap(chips)"
			("LOCATION" "C86")
		)
		("@t6g_mb_lib.t6g(sch_1):page129_i345@pure_quanta.sconn288_adr50001p003c01(chips)"
			("LOCATION" "J28")
		)
		("@t6g_mb_lib.t6g(sch_1):page129_i346@pure_quanta.sconn288_adr50001p003c01(chips)"
			("LOCATION" "J28")
		)
		("@t6g_mb_lib.t6g(sch_1):page129_i347@pure_quanta.sconn288_adr50001p003c01(chips)"
			("LOCATION" "J28")
		)
		("@t6g_mb_lib.t6g(sch_1):page129_i348@pure_quanta.q_res(chips)"
			("LOCATION" "R76")
		)
		("@t6g_mb_lib.t6g(sch_1):page128_i341@pure_quanta.q_cap(chips)"
			("LOCATION" "C87")
		)
		("@t6g_mb_lib.t6g(sch_1):page128_i345@pure_quanta.q_cap(chips)"
			("LOCATION" "C88")
		)
		("@t6g_mb_lib.t6g(sch_1):page128_i338@pure_quanta.q_cap(chips)"
			("LOCATION" "C89")
		)
		("@t6g_mb_lib.t6g(sch_1):page128_i346@pure_quanta.sconn288_adr50001p013c01(chips)"
			("LOCATION" "J27")
		)
		("@t6g_mb_lib.t6g(sch_1):page128_i347@pure_quanta.sconn288_adr50001p013c01(chips)"
			("LOCATION" "J27")
		)
		("@t6g_mb_lib.t6g(sch_1):page128_i348@pure_quanta.sconn288_adr50001p013c01(chips)"
			("LOCATION" "J27")
		)
		("@t6g_mb_lib.t6g(sch_1):page128_i349@pure_quanta.q_res(chips)"
			("LOCATION" "R77")
		)
		("@t6g_mb_lib.t6g(sch_1):page127_i341@pure_quanta.q_cap(chips)"
			("LOCATION" "C90")
		)
		("@t6g_mb_lib.t6g(sch_1):page127_i346@pure_quanta.q_cap(chips)"
			("LOCATION" "C91")
		)
		("@t6g_mb_lib.t6g(sch_1):page127_i338@pure_quanta.q_cap(chips)"
			("LOCATION" "C92")
		)
		("@t6g_mb_lib.t6g(sch_1):page127_i347@pure_quanta.sconn288_adr50001p003c01(chips)"
			("LOCATION" "J26")
		)
		("@t6g_mb_lib.t6g(sch_1):page127_i348@pure_quanta.sconn288_adr50001p003c01(chips)"
			("LOCATION" "J26")
		)
		("@t6g_mb_lib.t6g(sch_1):page127_i349@pure_quanta.sconn288_adr50001p003c01(chips)"
			("LOCATION" "J26")
		)
		("@t6g_mb_lib.t6g(sch_1):page127_i350@pure_quanta.q_res(chips)"
			("LOCATION" "R78")
		)
		("@t6g_mb_lib.t6g(sch_1):page126_i339@pure_quanta.q_cap(chips)"
			("LOCATION" "C93")
		)
		("@t6g_mb_lib.t6g(sch_1):page126_i343@pure_quanta.q_cap(chips)"
			("LOCATION" "C94")
		)
		("@t6g_mb_lib.t6g(sch_1):page126_i336@pure_quanta.q_cap(chips)"
			("LOCATION" "C95")
		)
		("@t6g_mb_lib.t6g(sch_1):page126_i345@pure_quanta.sconn288_adr50001p013c01(chips)"
			("LOCATION" "J25")
		)
		("@t6g_mb_lib.t6g(sch_1):page126_i346@pure_quanta.sconn288_adr50001p013c01(chips)"
			("LOCATION" "J25")
		)
		("@t6g_mb_lib.t6g(sch_1):page126_i344@pure_quanta.sconn288_adr50001p013c01(chips)"
			("LOCATION" "J25")
		)
		("@t6g_mb_lib.t6g(sch_1):page126_i331@pure_quanta.q_res(chips)"
			("LOCATION" "R79")
		)
		("@t6g_mb_lib.t6g(sch_1):page125_i342@pure_quanta.q_cap(chips)"
			("LOCATION" "C96")
		)
		("@t6g_mb_lib.t6g(sch_1):page125_i345@pure_quanta.q_cap(chips)"
			("LOCATION" "C97")
		)
		("@t6g_mb_lib.t6g(sch_1):page125_i339@pure_quanta.q_cap(chips)"
			("LOCATION" "C98")
		)
		("@t6g_mb_lib.t6g(sch_1):page125_i346@pure_quanta.sconn288_adr50001p003c01(chips)"
			("LOCATION" "J24")
		)
		("@t6g_mb_lib.t6g(sch_1):page125_i347@pure_quanta.sconn288_adr50001p003c01(chips)"
			("LOCATION" "J24")
		)
		("@t6g_mb_lib.t6g(sch_1):page125_i348@pure_quanta.sconn288_adr50001p003c01(chips)"
			("LOCATION" "J24")
		)
		("@t6g_mb_lib.t6g(sch_1):page125_i349@pure_quanta.q_res(chips)"
			("LOCATION" "R80")
		)
		("@t6g_mb_lib.t6g(sch_1):page98_i67@pure_quanta.q_cap(chips)"
			("LOCATION" "C99")
		)
		("@t6g_mb_lib.t6g(sch_1):page98_i55@pure_quanta.q_cap(chips)"
			("LOCATION" "C106")
		)
		("@t6g_mb_lib.t6g(sch_1):page98_i82@pure_quanta.mosfet_n_123(chips)"
			("LOCATION" "Q105")
		)
		("@t6g_mb_lib.t6g(sch_1):page98_i85@pure_quanta.mosfet_n_123(chips)"
			("LOCATION" "Q106")
		)
		("@t6g_mb_lib.t6g(sch_1):page98_i58@pure_quanta.q_res(chips)"
			("LOCATION" "R81")
		)
		("@t6g_mb_lib.t6g(sch_1):page98_i99@pure_quanta.q_res(chips)"
			("LOCATION" "R199")
		)
		("@t6g_mb_lib.t6g(sch_1):page98_i97@pure_quanta.q_res(chips)"
			("LOCATION" "R200")
		)
		("@t6g_mb_lib.t6g(sch_1):page98_i96@pure_quanta.q_res(chips)"
			("LOCATION" "R201")
		)
		("@t6g_mb_lib.t6g(sch_1):page98_i108@pure_quanta.q_res(chips)"
			("LOCATION" "R203")
		)
		("@t6g_mb_lib.t6g(sch_1):page98_i109@pure_quanta.q_res(chips)"
			("LOCATION" "R204")
		)
		("@t6g_mb_lib.t6g(sch_1):page98_i110@pure_quanta.q_res(chips)"
			("LOCATION" "R205")
		)
		("@t6g_mb_lib.t6g(sch_1):page98_i111@pure_quanta.q_res(chips)"
			("LOCATION" "R206")
		)
		("@t6g_mb_lib.t6g(sch_1):page98_i87@pure_quanta.q_res(chips)"
			("LOCATION" "R207")
		)
		("@t6g_mb_lib.t6g(sch_1):page98_i88@pure_quanta.q_res(chips)"
			("LOCATION" "R208")
		)
		("@t6g_mb_lib.t6g(sch_1):page98_i89@pure_quanta.q_res(chips)"
			("LOCATION" "R209")
		)
		("@t6g_mb_lib.t6g(sch_1):page98_i91@pure_quanta.q_res(chips)"
			("LOCATION" "R210")
		)
		("@t6g_mb_lib.t6g(sch_1):page98_i100@pure_quanta.q_res(chips)"
			("LOCATION" "R211")
		)
		("@t6g_mb_lib.t6g(sch_1):page98_i101@pure_quanta.q_res(chips)"
			("LOCATION" "R212")
		)
		("@t6g_mb_lib.t6g(sch_1):page98_i102@pure_quanta.q_res(chips)"
			("LOCATION" "R213")
		)
		("@t6g_mb_lib.t6g(sch_1):page98_i103@pure_quanta.q_res(chips)"
			("LOCATION" "R214")
		)
		("@t6g_mb_lib.t6g(sch_1):page98_i104@pure_quanta.q_res(chips)"
			("LOCATION" "R215")
		)
		("@t6g_mb_lib.t6g(sch_1):page98_i105@pure_quanta.q_res(chips)"
			("LOCATION" "R216")
		)
		("@t6g_mb_lib.t6g(sch_1):page98_i106@pure_quanta.q_res(chips)"
			("LOCATION" "R217")
		)
		("@t6g_mb_lib.t6g(sch_1):page98_i107@pure_quanta.q_res(chips)"
			("LOCATION" "R218")
		)
		("@t6g_mb_lib.t6g(sch_1):page98_i63@pure_quanta.q_res(chips)"
			("LOCATION" "R219")
		)
		("@t6g_mb_lib.t6g(sch_1):page98_i66@pure_quanta.q_res(chips)"
			("LOCATION" "R220")
		)
		("@t6g_mb_lib.t6g(sch_1):page98_i61@pure_quanta.q_res(chips)"
			("LOCATION" "R221")
		)
		("@t6g_mb_lib.t6g(sch_1):page98_i62@pure_quanta.q_res(chips)"
			("LOCATION" "R222")
		)
		("@t6g_mb_lib.t6g(sch_1):page98_i57@pure_quanta.q_res(chips)"
			("LOCATION" "R223")
		)
		("@t6g_mb_lib.t6g(sch_1):page98_i59@pure_quanta.q_res(chips)"
			("LOCATION" "R224")
		)
		("@t6g_mb_lib.t6g(sch_1):page98_i76@pure_quanta.q_res(chips)"
			("LOCATION" "R225")
		)
		("@t6g_mb_lib.t6g(sch_1):page98_i77@pure_quanta.q_res(chips)"
			("LOCATION" "R226")
		)
		("@t6g_mb_lib.t6g(sch_1):page98_i78@pure_quanta.q_res(chips)"
			("LOCATION" "R227")
		)
		("@t6g_mb_lib.t6g(sch_1):page98_i79@pure_quanta.q_res(chips)"
			("LOCATION" "R228")
		)
		("@t6g_mb_lib.t6g(sch_1):page98_i94@pure_quanta.q_res(chips)"
			("LOCATION" "R2069")
		)
		("@t6g_mb_lib.t6g(sch_1):page98_i83@pure_quanta.q_res(chips)"
			("LOCATION" "R2070")
		)
		("@t6g_mb_lib.t6g(sch_1):page98_i86@pure_quanta.q_res(chips)"
			("LOCATION" "R2071")
		)
		("@t6g_mb_lib.t6g(sch_1):page98_i80@pure_quanta.gtl2014pw(chips)"
			("LOCATION" "U180")
		)
		("@t6g_mb_lib.t6g(sch_1):page93_i36@pure_quanta.q_cap(chips)"
			("LOCATION" "C100")
		)
		("@t6g_mb_lib.t6g(sch_1):page93_i42@pure_quanta.q_cap(chips)"
			("LOCATION" "C107")
		)
		("@t6g_mb_lib.t6g(sch_1):page93_i47@pure_quanta.q_res(chips)"
			("LOCATION" "R82")
		)
		("@t6g_mb_lib.t6g(sch_1):page93_i32@pure_quanta.q_res(chips)"
			("LOCATION" "R83")
		)
		("@t6g_mb_lib.t6g(sch_1):page93_i26@pure_quanta.q_res(chips)"
			("LOCATION" "R296")
		)
		("@t6g_mb_lib.t6g(sch_1):page93_i25@pure_quanta.q_res(chips)"
			("LOCATION" "R297")
		)
		("@t6g_mb_lib.t6g(sch_1):page93_i24@pure_quanta.q_res(chips)"
			("LOCATION" "R298")
		)
		("@t6g_mb_lib.t6g(sch_1):page93_i23@pure_quanta.q_res(chips)"
			("LOCATION" "R299")
		)
		("@t6g_mb_lib.t6g(sch_1):page93_i13@pure_quanta.q_res(chips)"
			("LOCATION" "R300")
		)
		("@t6g_mb_lib.t6g(sch_1):page93_i12@pure_quanta.q_res(chips)"
			("LOCATION" "R301")
		)
		("@t6g_mb_lib.t6g(sch_1):page93_i11@pure_quanta.q_res(chips)"
			("LOCATION" "R302")
		)
		("@t6g_mb_lib.t6g(sch_1):page93_i8@pure_quanta.q_res(chips)"
			("LOCATION" "R303")
		)
		("@t6g_mb_lib.t6g(sch_1):page93_i7@pure_quanta.q_res(chips)"
			("LOCATION" "R304")
		)
		("@t6g_mb_lib.t6g(sch_1):page93_i6@pure_quanta.q_res(chips)"
			("LOCATION" "R305")
		)
		("@t6g_mb_lib.t6g(sch_1):page93_i16@pure_quanta.q_res(chips)"
			("LOCATION" "R306")
		)
		("@t6g_mb_lib.t6g(sch_1):page93_i17@pure_quanta.q_res(chips)"
			("LOCATION" "R307")
		)
		("@t6g_mb_lib.t6g(sch_1):page93_i15@pure_quanta.q_res(chips)"
			("LOCATION" "R308")
		)
		("@t6g_mb_lib.t6g(sch_1):page93_i39@pure_quanta.q_res(chips)"
			("LOCATION" "R310")
		)
		("@t6g_mb_lib.t6g(sch_1):page93_i38@pure_quanta.q_res(chips)"
			("LOCATION" "R311")
		)
		("@t6g_mb_lib.t6g(sch_1):page93_i31@pure_quanta.q_res(chips)"
			("LOCATION" "R312")
		)
		("@t6g_mb_lib.t6g(sch_1):page93_i30@pure_quanta.q_res(chips)"
			("LOCATION" "R313")
		)
		("@t6g_mb_lib.t6g(sch_1):page93_i29@pure_quanta.q_res(chips)"
			("LOCATION" "R314")
		)
		("@t6g_mb_lib.t6g(sch_1):page93_i28@pure_quanta.q_res(chips)"
			("LOCATION" "R315")
		)
		("@t6g_mb_lib.t6g(sch_1):page93_i27@pure_quanta.gtl2014pw(chips)"
			("LOCATION" "U9")
		)
		("@t6g_mb_lib.t6g(sch_1):page77_i400@pure_quanta.q_cap(chips)"
			("LOCATION" "C101")
		)
		("@t6g_mb_lib.t6g(sch_1):page77_i395@pure_quanta.q_cap(chips)"
			("LOCATION" "C212")
		)
		("@t6g_mb_lib.t6g(sch_1):page77_i393@pure_quanta.q_cap(chips)"
			("LOCATION" "C213")
		)
		("@t6g_mb_lib.t6g(sch_1):page77_i378@pure_quanta.q_cap(chips)"
			("LOCATION" "C214")
		)
		("@t6g_mb_lib.t6g(sch_1):page77_i377@pure_quanta.q_cap(chips)"
			("LOCATION" "C215")
		)
		("@t6g_mb_lib.t6g(sch_1):page77_i372@pure_quanta.q_cap(chips)"
			("LOCATION" "C216")
		)
		("@t6g_mb_lib.t6g(sch_1):page77_i369@pure_quanta.q_cap(chips)"
			("LOCATION" "C217")
		)
		("@t6g_mb_lib.t6g(sch_1):page77_i368@pure_quanta.q_cap(chips)"
			("LOCATION" "C218")
		)
		("@t6g_mb_lib.t6g(sch_1):page77_i341@pure_quanta.q_cap(chips)"
			("LOCATION" "C219")
		)
		("@t6g_mb_lib.t6g(sch_1):page77_i271@pure_quanta.q_cap(chips)"
			("LOCATION" "C220")
		)
		("@t6g_mb_lib.t6g(sch_1):page77_i402@pure_quanta.q_cap(chips)"
			("LOCATION" "C399")
		)
		("@t6g_mb_lib.t6g(sch_1):page77_i412@pure_quanta.q_cap(chips)"
			("LOCATION" "C400")
		)
		("@t6g_mb_lib.t6g(sch_1):page77_i396@pure_quanta.q_cap(chips)"
			("LOCATION" "C401")
		)
		("@t6g_mb_lib.t6g(sch_1):page77_i410@pure_quanta.q_cap(chips)"
			("LOCATION" "C402")
		)
		("@t6g_mb_lib.t6g(sch_1):page77_i394@pure_quanta.q_cap(chips)"
			("LOCATION" "C403")
		)
		("@t6g_mb_lib.t6g(sch_1):page77_i409@pure_quanta.q_cap(chips)"
			("LOCATION" "C404")
		)
		("@t6g_mb_lib.t6g(sch_1):page77_i379@pure_quanta.q_cap(chips)"
			("LOCATION" "C405")
		)
		("@t6g_mb_lib.t6g(sch_1):page77_i408@pure_quanta.q_cap(chips)"
			("LOCATION" "C406")
		)
		("@t6g_mb_lib.t6g(sch_1):page77_i406@pure_quanta.q_cap(chips)"
			("LOCATION" "C407")
		)
		("@t6g_mb_lib.t6g(sch_1):page77_i374@pure_quanta.q_cap(chips)"
			("LOCATION" "C408")
		)
		("@t6g_mb_lib.t6g(sch_1):page77_i405@pure_quanta.q_cap(chips)"
			("LOCATION" "C409")
		)
		("@t6g_mb_lib.t6g(sch_1):page77_i371@pure_quanta.q_cap(chips)"
			("LOCATION" "C410")
		)
		("@t6g_mb_lib.t6g(sch_1):page77_i404@pure_quanta.q_cap(chips)"
			("LOCATION" "C411")
		)
		("@t6g_mb_lib.t6g(sch_1):page77_i370@pure_quanta.q_cap(chips)"
			("LOCATION" "C412")
		)
		("@t6g_mb_lib.t6g(sch_1):page77_i403@pure_quanta.q_cap(chips)"
			("LOCATION" "C413")
		)
		("@t6g_mb_lib.t6g(sch_1):page77_i342@pure_quanta.q_cap(chips)"
			("LOCATION" "C414")
		)
		("@t6g_mb_lib.t6g(sch_1):page77_i348@pure_quanta.q_cap(chips)"
			("LOCATION" "C415")
		)
		("@t6g_mb_lib.t6g(sch_1):page77_i340@pure_quanta.q_cap(chips)"
			("LOCATION" "C416")
		)
		("@t6g_mb_lib.t6g(sch_1):page77_i347@pure_quanta.q_cap(chips)"
			("LOCATION" "C417")
		)
		("@t6g_mb_lib.t6g(sch_1):page77_i344@pure_quanta.q_cap(chips)"
			("LOCATION" "C418")
		)
		("@t6g_mb_lib.t6g(sch_1):page77_i315@pure_quanta.q_cap(chips)"
			("LOCATION" "C419")
		)
		("@t6g_mb_lib.t6g(sch_1):page77_i313@pure_quanta.q_cap(chips)"
			("LOCATION" "C420")
		)
		("@t6g_mb_lib.t6g(sch_1):page77_i310@pure_quanta.q_cap(chips)"
			("LOCATION" "C421")
		)
		("@t6g_mb_lib.t6g(sch_1):page77_i306@pure_quanta.q_cap(chips)"
			("LOCATION" "C422")
		)
		("@t6g_mb_lib.t6g(sch_1):page77_i311@pure_quanta.q_cap(chips)"
			("LOCATION" "C590")
		)
		("@t6g_mb_lib.t6g(sch_1):page77_i386@pure_quanta.q_cap(chips)"
			("LOCATION" "C966")
		)
		("@t6g_mb_lib.t6g(sch_1):page77_i388@pure_quanta.q_cap(chips)"
			("LOCATION" "C967")
		)
		("@t6g_mb_lib.t6g(sch_1):page77_i390@pure_quanta.q_cap(chips)"
			("LOCATION" "C968")
		)
		("@t6g_mb_lib.t6g(sch_1):page77_i398@pure_quanta.q_cap(chips)"
			("LOCATION" "C969")
		)
		("@t6g_mb_lib.t6g(sch_1):page77_i382@pure_quanta.q_cap(chips)"
			("LOCATION" "C970")
		)
		("@t6g_mb_lib.t6g(sch_1):page77_i383@pure_quanta.q_cap(chips)"
			("LOCATION" "C971")
		)
		("@t6g_mb_lib.t6g(sch_1):page77_i385@pure_quanta.q_cap(chips)"
			("LOCATION" "C972")
		)
		("@t6g_mb_lib.t6g(sch_1):page77_i392@pure_quanta.q_cap(chips)"
			("LOCATION" "C973")
		)
		("@t6g_mb_lib.t6g(sch_1):page77_i380@pure_quanta.q_cap(chips)"
			("LOCATION" "C974")
		)
		("@t6g_mb_lib.t6g(sch_1):page77_i381@pure_quanta.q_cap(chips)"
			("LOCATION" "C975")
		)
		("@t6g_mb_lib.t6g(sch_1):page77_i384@pure_quanta.q_cap(chips)"
			("LOCATION" "C976")
		)
		("@t6g_mb_lib.t6g(sch_1):page77_i391@pure_quanta.q_cap(chips)"
			("LOCATION" "C977")
		)
		("@t6g_mb_lib.t6g(sch_1):page77_i361@pure_quanta.q_cap(chips)"
			("LOCATION" "C978")
		)
		("@t6g_mb_lib.t6g(sch_1):page77_i362@pure_quanta.q_cap(chips)"
			("LOCATION" "C979")
		)
		("@t6g_mb_lib.t6g(sch_1):page77_i364@pure_quanta.q_cap(chips)"
			("LOCATION" "C980")
		)
		("@t6g_mb_lib.t6g(sch_1):page77_i376@pure_quanta.q_cap(chips)"
			("LOCATION" "C981")
		)
		("@t6g_mb_lib.t6g(sch_1):page77_i359@pure_quanta.q_cap(chips)"
			("LOCATION" "C982")
		)
		("@t6g_mb_lib.t6g(sch_1):page77_i360@pure_quanta.q_cap(chips)"
			("LOCATION" "C983")
		)
		("@t6g_mb_lib.t6g(sch_1):page77_i363@pure_quanta.q_cap(chips)"
			("LOCATION" "C984")
		)
		("@t6g_mb_lib.t6g(sch_1):page77_i375@pure_quanta.q_cap(chips)"
			("LOCATION" "C985")
		)
		("@t6g_mb_lib.t6g(sch_1):page77_i354@pure_quanta.q_cap(chips)"
			("LOCATION" "C986")
		)
		("@t6g_mb_lib.t6g(sch_1):page77_i355@pure_quanta.q_cap(chips)"
			("LOCATION" "C987")
		)
		("@t6g_mb_lib.t6g(sch_1):page77_i358@pure_quanta.q_cap(chips)"
			("LOCATION" "C988")
		)
		("@t6g_mb_lib.t6g(sch_1):page77_i367@pure_quanta.q_cap(chips)"
			("LOCATION" "C989")
		)
		("@t6g_mb_lib.t6g(sch_1):page77_i352@pure_quanta.q_cap(chips)"
			("LOCATION" "C990")
		)
		("@t6g_mb_lib.t6g(sch_1):page77_i353@pure_quanta.q_cap(chips)"
			("LOCATION" "C991")
		)
		("@t6g_mb_lib.t6g(sch_1):page77_i357@pure_quanta.q_cap(chips)"
			("LOCATION" "C992")
		)
		("@t6g_mb_lib.t6g(sch_1):page77_i366@pure_quanta.q_cap(chips)"
			("LOCATION" "C993")
		)
		("@t6g_mb_lib.t6g(sch_1):page77_i350@pure_quanta.q_cap(chips)"
			("LOCATION" "C994")
		)
		("@t6g_mb_lib.t6g(sch_1):page77_i351@pure_quanta.q_cap(chips)"
			("LOCATION" "C995")
		)
		("@t6g_mb_lib.t6g(sch_1):page77_i356@pure_quanta.q_cap(chips)"
			("LOCATION" "C996")
		)
		("@t6g_mb_lib.t6g(sch_1):page77_i365@pure_quanta.q_cap(chips)"
			("LOCATION" "C997")
		)
		("@t6g_mb_lib.t6g(sch_1):page77_i327@pure_quanta.q_cap(chips)"
			("LOCATION" "C998")
		)
		("@t6g_mb_lib.t6g(sch_1):page77_i328@pure_quanta.q_cap(chips)"
			("LOCATION" "C999")
		)
		("@t6g_mb_lib.t6g(sch_1):page77_i332@pure_quanta.q_cap(chips)"
			("LOCATION" "C1000")
		)
		("@t6g_mb_lib.t6g(sch_1):page77_i338@pure_quanta.q_cap(chips)"
			("LOCATION" "C1001")
		)
		("@t6g_mb_lib.t6g(sch_1):page77_i324@pure_quanta.q_cap(chips)"
			("LOCATION" "C1002")
		)
		("@t6g_mb_lib.t6g(sch_1):page77_i326@pure_quanta.q_cap(chips)"
			("LOCATION" "C1003")
		)
		("@t6g_mb_lib.t6g(sch_1):page77_i330@pure_quanta.q_cap(chips)"
			("LOCATION" "C1004")
		)
		("@t6g_mb_lib.t6g(sch_1):page77_i336@pure_quanta.q_cap(chips)"
			("LOCATION" "C1005")
		)
		("@t6g_mb_lib.t6g(sch_1):page77_i318@pure_quanta.q_cap(chips)"
			("LOCATION" "C1006")
		)
		("@t6g_mb_lib.t6g(sch_1):page77_i320@pure_quanta.q_cap(chips)"
			("LOCATION" "C1007")
		)
		("@t6g_mb_lib.t6g(sch_1):page77_i323@pure_quanta.q_cap(chips)"
			("LOCATION" "C1008")
		)
		("@t6g_mb_lib.t6g(sch_1):page77_i335@pure_quanta.q_cap(chips)"
			("LOCATION" "C1009")
		)
		("@t6g_mb_lib.t6g(sch_1):page77_i316@pure_quanta.q_cap(chips)"
			("LOCATION" "C1010")
		)
		("@t6g_mb_lib.t6g(sch_1):page77_i317@pure_quanta.q_cap(chips)"
			("LOCATION" "C1011")
		)
		("@t6g_mb_lib.t6g(sch_1):page77_i321@pure_quanta.q_cap(chips)"
			("LOCATION" "C1012")
		)
		("@t6g_mb_lib.t6g(sch_1):page77_i333@pure_quanta.q_cap(chips)"
			("LOCATION" "C1013")
		)
		("@t6g_mb_lib.t6g(sch_1):page77_i299@pure_quanta.q_cap(chips)"
			("LOCATION" "C1014")
		)
		("@t6g_mb_lib.t6g(sch_1):page77_i300@pure_quanta.q_cap(chips)"
			("LOCATION" "C1015")
		)
		("@t6g_mb_lib.t6g(sch_1):page77_i302@pure_quanta.q_cap(chips)"
			("LOCATION" "C1016")
		)
		("@t6g_mb_lib.t6g(sch_1):page77_i308@pure_quanta.q_cap(chips)"
			("LOCATION" "C1017")
		)
		("@t6g_mb_lib.t6g(sch_1):page77_i297@pure_quanta.q_cap(chips)"
			("LOCATION" "C1018")
		)
		("@t6g_mb_lib.t6g(sch_1):page77_i298@pure_quanta.q_cap(chips)"
			("LOCATION" "C1019")
		)
		("@t6g_mb_lib.t6g(sch_1):page77_i301@pure_quanta.q_cap(chips)"
			("LOCATION" "C1020")
		)
		("@t6g_mb_lib.t6g(sch_1):page77_i307@pure_quanta.q_cap(chips)"
			("LOCATION" "C1021")
		)
		("@t6g_mb_lib.t6g(sch_1):page77_i291@pure_quanta.q_cap(chips)"
			("LOCATION" "C1022")
		)
		("@t6g_mb_lib.t6g(sch_1):page77_i293@pure_quanta.q_cap(chips)"
			("LOCATION" "C1023")
		)
		("@t6g_mb_lib.t6g(sch_1):page77_i296@pure_quanta.q_cap(chips)"
			("LOCATION" "C1024")
		)
		("@t6g_mb_lib.t6g(sch_1):page77_i305@pure_quanta.q_cap(chips)"
			("LOCATION" "C1025")
		)
		("@t6g_mb_lib.t6g(sch_1):page77_i290@pure_quanta.q_cap(chips)"
			("LOCATION" "C1026")
		)
		("@t6g_mb_lib.t6g(sch_1):page77_i292@pure_quanta.q_cap(chips)"
			("LOCATION" "C1027")
		)
		("@t6g_mb_lib.t6g(sch_1):page77_i295@pure_quanta.q_cap(chips)"
			("LOCATION" "C1028")
		)
		("@t6g_mb_lib.t6g(sch_1):page77_i304@pure_quanta.q_cap(chips)"
			("LOCATION" "C1029")
		)
		("@t6g_mb_lib.t6g(sch_1):page77_i288@pure_quanta.q_cap(chips)"
			("LOCATION" "C1030")
		)
		("@t6g_mb_lib.t6g(sch_1):page77_i289@pure_quanta.q_cap(chips)"
			("LOCATION" "C1031")
		)
		("@t6g_mb_lib.t6g(sch_1):page77_i294@pure_quanta.q_cap(chips)"
			("LOCATION" "C1032")
		)
		("@t6g_mb_lib.t6g(sch_1):page77_i303@pure_quanta.q_cap(chips)"
			("LOCATION" "C1033")
		)
		("@t6g_mb_lib.t6g(sch_1):page77_i279@pure_quanta.q_cap(chips)"
			("LOCATION" "C1034")
		)
		("@t6g_mb_lib.t6g(sch_1):page77_i280@pure_quanta.q_cap(chips)"
			("LOCATION" "C1035")
		)
		("@t6g_mb_lib.t6g(sch_1):page77_i282@pure_quanta.q_cap(chips)"
			("LOCATION" "C1036")
		)
		("@t6g_mb_lib.t6g(sch_1):page77_i286@pure_quanta.q_cap(chips)"
			("LOCATION" "C1037")
		)
		("@t6g_mb_lib.t6g(sch_1):page77_i276@pure_quanta.q_cap(chips)"
			("LOCATION" "C1038")
		)
		("@t6g_mb_lib.t6g(sch_1):page77_i278@pure_quanta.q_cap(chips)"
			("LOCATION" "C1039")
		)
		("@t6g_mb_lib.t6g(sch_1):page77_i281@pure_quanta.q_cap(chips)"
			("LOCATION" "C1040")
		)
		("@t6g_mb_lib.t6g(sch_1):page77_i285@pure_quanta.q_cap(chips)"
			("LOCATION" "C1041")
		)
		("@t6g_mb_lib.t6g(sch_1):page77_i272@pure_quanta.q_cap(chips)"
			("LOCATION" "C1043")
		)
		("@t6g_mb_lib.t6g(sch_1):page77_i274@pure_quanta.q_cap(chips)"
			("LOCATION" "C1044")
		)
		("@t6g_mb_lib.t6g(sch_1):page77_i283@pure_quanta.q_cap(chips)"
			("LOCATION" "C1045")
		)
		("@t6g_mb_lib.t6g(sch_1):page89_i40@pure_quanta.q_cap(chips)"
			("LOCATION" "C102")
		)
		("@t6g_mb_lib.t6g(sch_1):page89_i54@pure_quanta.q_cap(chips)"
			("LOCATION" "C1212")
		)
		("@t6g_mb_lib.t6g(sch_1):page89_i29@pure_quanta.q_res(chips)"
			("LOCATION" "R88")
		)
		("@t6g_mb_lib.t6g(sch_1):page89_i46@pure_quanta.q_res(chips)"
			("LOCATION" "R89")
		)
		("@t6g_mb_lib.t6g(sch_1):page89_i24@pure_quanta.q_res(chips)"
			("LOCATION" "R336")
		)
		("@t6g_mb_lib.t6g(sch_1):page89_i22@pure_quanta.q_res(chips)"
			("LOCATION" "R337")
		)
		("@t6g_mb_lib.t6g(sch_1):page89_i23@pure_quanta.q_res(chips)"
			("LOCATION" "R338")
		)
		("@t6g_mb_lib.t6g(sch_1):page89_i21@pure_quanta.q_res(chips)"
			("LOCATION" "R339")
		)
		("@t6g_mb_lib.t6g(sch_1):page89_i20@pure_quanta.q_res(chips)"
			("LOCATION" "R340")
		)
		("@t6g_mb_lib.t6g(sch_1):page89_i19@pure_quanta.q_res(chips)"
			("LOCATION" "R341")
		)
		("@t6g_mb_lib.t6g(sch_1):page89_i18@pure_quanta.q_res(chips)"
			("LOCATION" "R342")
		)
		("@t6g_mb_lib.t6g(sch_1):page89_i17@pure_quanta.q_res(chips)"
			("LOCATION" "R343")
		)
		("@t6g_mb_lib.t6g(sch_1):page89_i16@pure_quanta.q_res(chips)"
			("LOCATION" "R344")
		)
		("@t6g_mb_lib.t6g(sch_1):page89_i15@pure_quanta.q_res(chips)"
			("LOCATION" "R345")
		)
		("@t6g_mb_lib.t6g(sch_1):page89_i14@pure_quanta.q_res(chips)"
			("LOCATION" "R346")
		)
		("@t6g_mb_lib.t6g(sch_1):page89_i13@pure_quanta.q_res(chips)"
			("LOCATION" "R347")
		)
		("@t6g_mb_lib.t6g(sch_1):page89_i27@pure_quanta.q_res(chips)"
			("LOCATION" "R348")
		)
		("@t6g_mb_lib.t6g(sch_1):page89_i25@pure_quanta.q_res(chips)"
			("LOCATION" "R349")
		)
		("@t6g_mb_lib.t6g(sch_1):page89_i26@pure_quanta.q_res(chips)"
			("LOCATION" "R350")
		)
		("@t6g_mb_lib.t6g(sch_1):page89_i30@pure_quanta.q_res(chips)"
			("LOCATION" "R351")
		)
		("@t6g_mb_lib.t6g(sch_1):page89_i31@pure_quanta.q_res(chips)"
			("LOCATION" "R352")
		)
		("@t6g_mb_lib.t6g(sch_1):page89_i32@pure_quanta.q_res(chips)"
			("LOCATION" "R353")
		)
		("@t6g_mb_lib.t6g(sch_1):page89_i44@pure_quanta.q_res(chips)"
			("LOCATION" "R354")
		)
		("@t6g_mb_lib.t6g(sch_1):page89_i43@pure_quanta.q_res(chips)"
			("LOCATION" "R355")
		)
		("@t6g_mb_lib.t6g(sch_1):page89_i38@pure_quanta.q_res(chips)"
			("LOCATION" "R356")
		)
		("@t6g_mb_lib.t6g(sch_1):page89_i36@pure_quanta.q_res(chips)"
			("LOCATION" "R357")
		)
		("@t6g_mb_lib.t6g(sch_1):page89_i37@pure_quanta.q_res(chips)"
			("LOCATION" "R358")
		)
		("@t6g_mb_lib.t6g(sch_1):page89_i53@pure_quanta.q_res(chips)"
			("LOCATION" "R359")
		)
		("@t6g_mb_lib.t6g(sch_1):page89_i52@pure_quanta.q_res(chips)"
			("LOCATION" "R360")
		)
		("@t6g_mb_lib.t6g(sch_1):page89_i50@pure_quanta.q_res(chips)"
			("LOCATION" "R361")
		)
		("@t6g_mb_lib.t6g(sch_1):page89_i51@pure_quanta.q_res(chips)"
			("LOCATION" "R362")
		)
		("@t6g_mb_lib.t6g(sch_1):page89_i49@pure_quanta.q_res(chips)"
			("LOCATION" "R363")
		)
		("@t6g_mb_lib.t6g(sch_1):page89_i48@pure_quanta.q_res(chips)"
			("LOCATION" "R364")
		)
		("@t6g_mb_lib.t6g(sch_1):page89_i35@pure_quanta.gtl2014pw(chips)"
			("LOCATION" "U11")
		)
		("@t6g_mb_lib.t6g(sch_1):page176_i348@pure_quanta.q_cap(chips)"
			("LOCATION" "C103")
		)
		("@t6g_mb_lib.t6g(sch_1):page176_i346@pure_quanta.q_cap(chips)"
			("LOCATION" "C104")
		)
		("@t6g_mb_lib.t6g(sch_1):page176_i339@pure_quanta.q_cap(chips)"
			("LOCATION" "C609")
		)
		("@t6g_mb_lib.t6g(sch_1):page176_i329@pure_quanta.q_cap(chips)"
			("LOCATION" "C1507")
		)
		("@t6g_mb_lib.t6g(sch_1):page176_i328@pure_quanta.q_cap(chips)"
			("LOCATION" "C1508")
		)
		("@t6g_mb_lib.t6g(sch_1):page176_i325@pure_quanta.q_res(chips)"
			("LOCATION" "R120")
		)
		("@t6g_mb_lib.t6g(sch_1):page176_i341@pure_quanta.q_res(chips)"
			("LOCATION" "R477")
		)
		("@t6g_mb_lib.t6g(sch_1):page176_i344@pure_quanta.q_res(chips)"
			("LOCATION" "R1316")
		)
		("@t6g_mb_lib.t6g(sch_1):page176_i343@pure_quanta.q_res(chips)"
			("LOCATION" "R1720")
		)
		("@t6g_mb_lib.t6g(sch_1):page176_i322@pure_quanta.q_res(chips)"
			("LOCATION" "R1721")
		)
		("@t6g_mb_lib.t6g(sch_1):page176_i350@pure_quanta.emmitsburg_rev0p9(chips)"
			("LOCATION" "U8")
		)
		("@t6g_mb_lib.t6g(sch_1):page176_i326@pure_quanta.q_crystal(chips)"
			("LOCATION" "Y1")
		)
		("@t6g_mb_lib.t6g(sch_1):page176_i345@pure_quanta.q_xtal_4p_13bi_24gnd(chips)"
			("LOCATION" "Y3")
		)
		("@t6g_mb_lib.t6g(sch_1):page94_i25@pure_quanta.q_cap(chips)"
			("LOCATION" "C105")
		)
		("@t6g_mb_lib.t6g(sch_1):page94_i9@pure_quanta.q_res(chips)"
			("LOCATION" "R187")
		)
		("@t6g_mb_lib.t6g(sch_1):page94_i1@pure_quanta.q_res(chips)"
			("LOCATION" "R188")
		)
		("@t6g_mb_lib.t6g(sch_1):page94_i10@pure_quanta.q_res(chips)"
			("LOCATION" "R189")
		)
		("@t6g_mb_lib.t6g(sch_1):page94_i5@pure_quanta.q_res(chips)"
			("LOCATION" "R190")
		)
		("@t6g_mb_lib.t6g(sch_1):page94_i4@pure_quanta.q_res(chips)"
			("LOCATION" "R191")
		)
		("@t6g_mb_lib.t6g(sch_1):page94_i13@pure_quanta.q_res(chips)"
			("LOCATION" "R192")
		)
		("@t6g_mb_lib.t6g(sch_1):page94_i23@pure_quanta.q_res(chips)"
			("LOCATION" "R193")
		)
		("@t6g_mb_lib.t6g(sch_1):page94_i14@pure_quanta.q_res(chips)"
			("LOCATION" "R194")
		)
		("@t6g_mb_lib.t6g(sch_1):page94_i22@pure_quanta.q_res(chips)"
			("LOCATION" "R195")
		)
		("@t6g_mb_lib.t6g(sch_1):page94_i17@pure_quanta.q_res(chips)"
			("LOCATION" "R196")
		)
		("@t6g_mb_lib.t6g(sch_1):page94_i26@pure_quanta.q_res(chips)"
			("LOCATION" "R197")
		)
		("@t6g_mb_lib.t6g(sch_1):page94_i18@pure_quanta.q_res(chips)"
			("LOCATION" "R198")
		)
		("@t6g_mb_lib.t6g(sch_1):page94_i7@pure_quanta.\\74lvc1g07gv\\(chips)"
			("LOCATION" "U7")
		)
		("@t6g_mb_lib.t6g(sch_1):page141_i139@pure_quanta.q_cap_diffbus(chips)"
			("LOCATION" "C108")
		)
		("@t6g_mb_lib.t6g(sch_1):page141_i140@pure_quanta.q_cap_diffbus(chips)"
			("LOCATION" "C109")
		)
		("@t6g_mb_lib.t6g(sch_1):page141_i166@pure_quanta.q_cap_diffbus(chips)"
			("LOCATION" "C641")
		)
		("@t6g_mb_lib.t6g(sch_1):page141_i136@pure_quanta.q_cap_diffbus(chips)"
			("LOCATION" "C642")
		)
		("@t6g_mb_lib.t6g(sch_1):page141_i141@pure_quanta.q_cap_diffbus(chips)"
			("LOCATION" "C645")
		)
		("@t6g_mb_lib.t6g(sch_1):page141_i145@pure_quanta.q_cap_diffbus(chips)"
			("LOCATION" "C646")
		)
		("@t6g_mb_lib.t6g(sch_1):page141_i146@pure_quanta.q_cap_diffbus(chips)"
			("LOCATION" "C647")
		)
		("@t6g_mb_lib.t6g(sch_1):page141_i147@pure_quanta.q_cap_diffbus(chips)"
			("LOCATION" "C648")
		)
		("@t6g_mb_lib.t6g(sch_1):page141_i133@pure_quanta.q_cap_diffbus(chips)"
			("LOCATION" "C654")
		)
		("@t6g_mb_lib.t6g(sch_1):page141_i134@pure_quanta.q_cap_diffbus(chips)"
			("LOCATION" "C656")
		)
		("@t6g_mb_lib.t6g(sch_1):page141_i137@pure_quanta.q_cap_diffbus(chips)"
			("LOCATION" "C657")
		)
		("@t6g_mb_lib.t6g(sch_1):page141_i138@pure_quanta.q_cap_diffbus(chips)"
			("LOCATION" "C658")
		)
		("@t6g_mb_lib.t6g(sch_1):page141_i142@pure_quanta.q_cap_diffbus(chips)"
			("LOCATION" "C659")
		)
		("@t6g_mb_lib.t6g(sch_1):page141_i143@pure_quanta.q_cap_diffbus(chips)"
			("LOCATION" "C660")
		)
		("@t6g_mb_lib.t6g(sch_1):page141_i144@pure_quanta.q_cap_diffbus(chips)"
			("LOCATION" "C661")
		)
		("@t6g_mb_lib.t6g(sch_1):page141_i148@pure_quanta.q_cap_diffbus(chips)"
			("LOCATION" "C662")
		)
		("@t6g_mb_lib.t6g(sch_1):page141_i151@pure_quanta.q_cap_diffbus(chips)"
			("LOCATION" "C663")
		)
		("@t6g_mb_lib.t6g(sch_1):page141_i152@pure_quanta.q_cap_diffbus(chips)"
			("LOCATION" "C664")
		)
		("@t6g_mb_lib.t6g(sch_1):page141_i156@pure_quanta.q_cap_diffbus(chips)"
			("LOCATION" "C665")
		)
		("@t6g_mb_lib.t6g(sch_1):page141_i155@pure_quanta.q_cap_diffbus(chips)"
			("LOCATION" "C666")
		)
		("@t6g_mb_lib.t6g(sch_1):page141_i157@pure_quanta.q_cap_diffbus(chips)"
			("LOCATION" "C667")
		)
		("@t6g_mb_lib.t6g(sch_1):page141_i161@pure_quanta.q_cap_diffbus(chips)"
			("LOCATION" "C668")
		)
		("@t6g_mb_lib.t6g(sch_1):page141_i162@pure_quanta.q_cap_diffbus(chips)"
			("LOCATION" "C669")
		)
		("@t6g_mb_lib.t6g(sch_1):page141_i163@pure_quanta.q_cap_diffbus(chips)"
			("LOCATION" "C670")
		)
		("@t6g_mb_lib.t6g(sch_1):page141_i149@pure_quanta.q_cap_diffbus(chips)"
			("LOCATION" "C671")
		)
		("@t6g_mb_lib.t6g(sch_1):page141_i150@pure_quanta.q_cap_diffbus(chips)"
			("LOCATION" "C672")
		)
		("@t6g_mb_lib.t6g(sch_1):page141_i153@pure_quanta.q_cap_diffbus(chips)"
			("LOCATION" "C673")
		)
		("@t6g_mb_lib.t6g(sch_1):page141_i154@pure_quanta.q_cap_diffbus(chips)"
			("LOCATION" "C674")
		)
		("@t6g_mb_lib.t6g(sch_1):page141_i158@pure_quanta.q_cap_diffbus(chips)"
			("LOCATION" "C675")
		)
		("@t6g_mb_lib.t6g(sch_1):page141_i159@pure_quanta.q_cap_diffbus(chips)"
			("LOCATION" "C676")
		)
		("@t6g_mb_lib.t6g(sch_1):page141_i160@pure_quanta.q_cap_diffbus(chips)"
			("LOCATION" "C677")
		)
		("@t6g_mb_lib.t6g(sch_1):page141_i164@pure_quanta.q_cap_diffbus(chips)"
			("LOCATION" "C678")
		)
		("@t6g_mb_lib.t6g(sch_1):page200_i25@pure_quanta.q_cap(chips)"
			("LOCATION" "C110")
		)
		("@t6g_mb_lib.t6g(sch_1):page200_i48@pure_quanta.q_cap(chips)"
			("LOCATION" "C111")
		)
		("@t6g_mb_lib.t6g(sch_1):page200_i43@pure_quanta.q_cap(chips)"
			("LOCATION" "C112")
		)
		("@t6g_mb_lib.t6g(sch_1):page200_i17@pure_quanta.q_cap(chips)"
			("LOCATION" "C113")
		)
		("@t6g_mb_lib.t6g(sch_1):page200_i3@pure_quanta.q_cap(chips)"
			("LOCATION" "C114")
		)
		("@t6g_mb_lib.t6g(sch_1):page200_i36@pure_quanta.q_cap(chips)"
			("LOCATION" "C115")
		)
		("@t6g_mb_lib.t6g(sch_1):page200_i5@pure_quanta.q_res(chips)"
			("LOCATION" "R797")
		)
		("@t6g_mb_lib.t6g(sch_1):page200_i20@pure_quanta.q_res(chips)"
			("LOCATION" "R798")
		)
		("@t6g_mb_lib.t6g(sch_1):page200_i10@pure_quanta.q_res(chips)"
			("LOCATION" "R801")
		)
		("@t6g_mb_lib.t6g(sch_1):page200_i49@pure_quanta.q_res(chips)"
			("LOCATION" "R802")
		)
		("@t6g_mb_lib.t6g(sch_1):page200_i45@pure_quanta.q_res(chips)"
			("LOCATION" "R808")
		)
		("@t6g_mb_lib.t6g(sch_1):page200_i52@pure_quanta.q_res(chips)"
			("LOCATION" "R3666")
		)
		("@t6g_mb_lib.t6g(sch_1):page200_i51@pure_quanta.q_res(chips)"
			("LOCATION" "R3667")
		)
		("@t6g_mb_lib.t6g(sch_1):page200_i22@pure_quanta.sn74hc595brwn(chips)"
			("LOCATION" "U27")
		)
		("@t6g_mb_lib.t6g(sch_1):page200_i38@pure_quanta.sn74hc595brwn(chips)"
			("LOCATION" "U30")
		)
		("@t6g_mb_lib.t6g(sch_1):page200_i14@pure_quanta.sn74lvc1g14dbvr(chips)"
			("LOCATION" "U31")
		)
		("@t6g_mb_lib.t6g(sch_1):page200_i7@pure_quanta.sn74lvc1g14dbvr(chips)"
			("LOCATION" "U32")
		)
		("@t6g_mb_lib.t6g(sch_1):page275_i43@pure_quanta.q_cap(chips)"
			("LOCATION" "C116")
		)
		("@t6g_mb_lib.t6g(sch_1):page275_i33@pure_quanta.q_cap(chips)"
			("LOCATION" "C2894")
		)
		("@t6g_mb_lib.t6g(sch_1):page275_i35@pure_quanta.q_cap(chips)"
			("LOCATION" "C2895")
		)
		("@t6g_mb_lib.t6g(sch_1):page275_i34@pure_quanta.q_cap(chips)"
			("LOCATION" "C2896")
		)
		("@t6g_mb_lib.t6g(sch_1):page275_i38@pure_quanta.q_cap(chips)"
			("LOCATION" "C2897")
		)
		("@t6g_mb_lib.t6g(sch_1):page275_i77@pure_quanta.sconn10_436501010(chips)"
			("LOCATION" "J74")
		)
		("@t6g_mb_lib.t6g(sch_1):page275_i78@pure_quanta.sconn10_436501010(chips)"
			("LOCATION" "J75")
		)
		("@t6g_mb_lib.t6g(sch_1):page275_i17@pure_quanta.mosfet_nch_dual(chips)"
			("LOCATION" "Q2")
		)
		("@t6g_mb_lib.t6g(sch_1):page275_i18@pure_quanta.mosfet_nch_dual(chips)"
			("LOCATION" "Q2")
		)
		("@t6g_mb_lib.t6g(sch_1):page275_i59@pure_quanta.mosfet_nch_dual(chips)"
			("LOCATION" "Q313")
		)
		("@t6g_mb_lib.t6g(sch_1):page275_i56@pure_quanta.mosfet_nch_dual(chips)"
			("LOCATION" "Q313")
		)
		("@t6g_mb_lib.t6g(sch_1):page275_i69@pure_quanta.mosfet_nch_dual(chips)"
			("LOCATION" "Q314")
		)
		("@t6g_mb_lib.t6g(sch_1):page275_i66@pure_quanta.mosfet_nch_dual(chips)"
			("LOCATION" "Q314")
		)
		("@t6g_mb_lib.t6g(sch_1):page275_i19@pure_quanta.mosfet_nch_dual(chips)"
			("LOCATION" "Q322")
		)
		("@t6g_mb_lib.t6g(sch_1):page275_i20@pure_quanta.mosfet_nch_dual(chips)"
			("LOCATION" "Q322")
		)
		("@t6g_mb_lib.t6g(sch_1):page275_i70@pure_quanta.q_res(chips)"
			("LOCATION" "R1481")
		)
		("@t6g_mb_lib.t6g(sch_1):page275_i61@pure_quanta.q_res(chips)"
			("LOCATION" "R1482")
		)
		("@t6g_mb_lib.t6g(sch_1):page275_i48@pure_quanta.q_res(chips)"
			("LOCATION" "R2130")
		)
		("@t6g_mb_lib.t6g(sch_1):page275_i49@pure_quanta.q_res(chips)"
			("LOCATION" "R2131")
		)
		("@t6g_mb_lib.t6g(sch_1):page275_i15@pure_quanta.q_res(chips)"
			("LOCATION" "R3556")
		)
		("@t6g_mb_lib.t6g(sch_1):page275_i67@pure_quanta.q_res(chips)"
			("LOCATION" "R3696")
		)
		("@t6g_mb_lib.t6g(sch_1):page275_i57@pure_quanta.q_res(chips)"
			("LOCATION" "R3697")
		)
		("@t6g_mb_lib.t6g(sch_1):page275_i54@pure_quanta.q_res(chips)"
			("LOCATION" "R3698")
		)
		("@t6g_mb_lib.t6g(sch_1):page275_i51@pure_quanta.q_res(chips)"
			("LOCATION" "R3699")
		)
		("@t6g_mb_lib.t6g(sch_1):page275_i46@pure_quanta.sn74lvc1g32dbvr(chips)"
			("LOCATION" "U129")
		)
		("@t6g_mb_lib.t6g(sch_1):page207_i639@pure_quanta.q_cap(chips)"
			("LOCATION" "C117")
		)
		("@t6g_mb_lib.t6g(sch_1):page207_i602@pure_quanta.q_res(chips)"
			("LOCATION" "R452")
		)
		("@t6g_mb_lib.t6g(sch_1):page207_i598@pure_quanta.q_res(chips)"
			("LOCATION" "R458")
		)
		("@t6g_mb_lib.t6g(sch_1):page207_i604@pure_quanta.q_res(chips)"
			("LOCATION" "R529")
		)
		("@t6g_mb_lib.t6g(sch_1):page207_i600@pure_quanta.q_res(chips)"
			("LOCATION" "R530")
		)
		("@t6g_mb_lib.t6g(sch_1):page207_i641@pure_quanta.q_res(chips)"
			("LOCATION" "R531")
		)
		("@t6g_mb_lib.t6g(sch_1):page207_i644@pure_quanta.q_res(chips)"
			("LOCATION" "R532")
		)
		("@t6g_mb_lib.t6g(sch_1):page207_i637@pure_quanta.q_res(chips)"
			("LOCATION" "R549")
		)
		("@t6g_mb_lib.t6g(sch_1):page207_i638@pure_quanta.q_res(chips)"
			("LOCATION" "R550")
		)
		("@t6g_mb_lib.t6g(sch_1):page207_i635@pure_quanta.q_res(chips)"
			("LOCATION" "R551")
		)
		("@t6g_mb_lib.t6g(sch_1):page207_i636@pure_quanta.q_res(chips)"
			("LOCATION" "R552")
		)
		("@t6g_mb_lib.t6g(sch_1):page207_i634@pure_quanta.q_res(chips)"
			("LOCATION" "R657")
		)
		("@t6g_mb_lib.t6g(sch_1):page207_i601@pure_quanta.q_res(chips)"
			("LOCATION" "R3534")
		)
		("@t6g_mb_lib.t6g(sch_1):page207_i597@pure_quanta.q_res(chips)"
			("LOCATION" "R3535")
		)
		("@t6g_mb_lib.t6g(sch_1):page207_i652@pure_quanta.q_res(chips)"
			("LOCATION" "R3750")
		)
		("@t6g_mb_lib.t6g(sch_1):page207_i647@pure_quanta.q_res(chips)"
			("LOCATION" "R3751")
		)
		("@t6g_mb_lib.t6g(sch_1):page207_i617@pure_quanta.pca9546apwr(chips)"
			("LOCATION" "U12")
		)
		("@t6g_mb_lib.t6g(sch_1):page208_i129@pure_quanta.q_cap(chips)"
			("LOCATION" "C118")
		)
		("@t6g_mb_lib.t6g(sch_1):page208_i139@pure_quanta.q_cap(chips)"
			("LOCATION" "C585")
		)
		("@t6g_mb_lib.t6g(sch_1):page208_i134@pure_quanta.q_cap(chips)"
			("LOCATION" "C586")
		)
		("@t6g_mb_lib.t6g(sch_1):page208_i143@pure_quanta.q_cap(chips)"
			("LOCATION" "C587")
		)
		("@t6g_mb_lib.t6g(sch_1):page208_i135@pure_quanta.q_cap(chips)"
			("LOCATION" "C588")
		)
		("@t6g_mb_lib.t6g(sch_1):page208_i131@pure_quanta.q_cap(chips)"
			("LOCATION" "C589")
		)
		("@t6g_mb_lib.t6g(sch_1):page208_i191@pure_quanta.q_cap(chips)"
			("LOCATION" "C591")
		)
		("@t6g_mb_lib.t6g(sch_1):page208_i183@pure_quanta.q_cap(chips)"
			("LOCATION" "C594")
		)
		("@t6g_mb_lib.t6g(sch_1):page208_i145@pure_quanta.q_cap(chips)"
			("LOCATION" "C595")
		)
		("@t6g_mb_lib.t6g(sch_1):page208_i185@pure_quanta.q_cap(chips)"
			("LOCATION" "C679")
		)
		("@t6g_mb_lib.t6g(sch_1):page208_i151@pure_quanta.q_cap(chips)"
			("LOCATION" "C743")
		)
		("@t6g_mb_lib.t6g(sch_1):page208_i195@pure_quanta.q_cap(chips)"
			("LOCATION" "C744")
		)
		("@t6g_mb_lib.t6g(sch_1):page208_i146@pure_quanta.q_cap(chips)"
			("LOCATION" "C745")
		)
		("@t6g_mb_lib.t6g(sch_1):page208_i187@pure_quanta.q_cap(chips)"
			("LOCATION" "C746")
		)
		("@t6g_mb_lib.t6g(sch_1):page208_i153@pure_quanta.q_cap(chips)"
			("LOCATION" "C747")
		)
		("@t6g_mb_lib.t6g(sch_1):page208_i189@pure_quanta.q_cap(chips)"
			("LOCATION" "C748")
		)
		("@t6g_mb_lib.t6g(sch_1):page208_i154@pure_quanta.q_cap(chips)"
			("LOCATION" "C749")
		)
		("@t6g_mb_lib.t6g(sch_1):page208_i197@pure_quanta.q_cap(chips)"
			("LOCATION" "C750")
		)
		("@t6g_mb_lib.t6g(sch_1):page208_i159@pure_quanta.q_cap(chips)"
			("LOCATION" "C751")
		)
		("@t6g_mb_lib.t6g(sch_1):page208_i200@pure_quanta.q_cap(chips)"
			("LOCATION" "C752")
		)
		("@t6g_mb_lib.t6g(sch_1):page208_i161@pure_quanta.q_cap(chips)"
			("LOCATION" "C753")
		)
		("@t6g_mb_lib.t6g(sch_1):page208_i203@pure_quanta.q_cap(chips)"
			("LOCATION" "C754")
		)
		("@t6g_mb_lib.t6g(sch_1):page208_i175@pure_quanta.q_cap(chips)"
			("LOCATION" "C755")
		)
		("@t6g_mb_lib.t6g(sch_1):page208_i211@pure_quanta.q_cap(chips)"
			("LOCATION" "C756")
		)
		("@t6g_mb_lib.t6g(sch_1):page208_i177@pure_quanta.q_cap(chips)"
			("LOCATION" "C757")
		)
		("@t6g_mb_lib.t6g(sch_1):page208_i213@pure_quanta.q_cap(chips)"
			("LOCATION" "C802")
		)
		("@t6g_mb_lib.t6g(sch_1):page208_i149@pure_quanta.q_cap(chips)"
			("LOCATION" "C805")
		)
		("@t6g_mb_lib.t6g(sch_1):page208_i193@pure_quanta.q_cap(chips)"
			("LOCATION" "C806")
		)
		("@t6g_mb_lib.t6g(sch_1):page208_i141@pure_quanta.q_inductor(chips)"
			("LOCATION" "L93")
		)
		("@t6g_mb_lib.t6g(sch_1):page208_i137@pure_quanta.q_inductor(chips)"
			("LOCATION" "L94")
		)
		("@t6g_mb_lib.t6g(sch_1):page208_i157@pure_quanta.q_res(chips)"
			("LOCATION" "R85")
		)
		("@t6g_mb_lib.t6g(sch_1):page208_i201@pure_quanta.q_res(chips)"
			("LOCATION" "R86")
		)
		("@t6g_mb_lib.t6g(sch_1):page208_i206@pure_quanta.q_res(chips)"
			("LOCATION" "R379")
		)
		("@t6g_mb_lib.t6g(sch_1):page208_i205@pure_quanta.q_res(chips)"
			("LOCATION" "R380")
		)
		("@t6g_mb_lib.t6g(sch_1):page208_i164@pure_quanta.q_res(chips)"
			("LOCATION" "R381")
		)
		("@t6g_mb_lib.t6g(sch_1):page208_i163@pure_quanta.q_res(chips)"
			("LOCATION" "R382")
		)
		("@t6g_mb_lib.t6g(sch_1):page208_i219@pure_quanta.q_res(chips)"
			("LOCATION" "R553")
		)
		("@t6g_mb_lib.t6g(sch_1):page208_i169@pure_quanta.q_res(chips)"
			("LOCATION" "R554")
		)
		("@t6g_mb_lib.t6g(sch_1):page208_i221@pure_quanta.q_res(chips)"
			("LOCATION" "R564")
		)
		("@t6g_mb_lib.t6g(sch_1):page208_i170@pure_quanta.q_res(chips)"
			("LOCATION" "R565")
		)
		("@t6g_mb_lib.t6g(sch_1):page208_i171@pure_quanta.q_res(chips)"
			("LOCATION" "R1162")
		)
		("@t6g_mb_lib.t6g(sch_1):page208_i218@pure_quanta.q_res(chips)"
			("LOCATION" "R1163")
		)
		("@t6g_mb_lib.t6g(sch_1):page208_i341@pure_quanta.q_res(chips)"
			("LOCATION" "R3703")
		)
		("@t6g_mb_lib.t6g(sch_1):page208_i343@pure_quanta.q_res(chips)"
			("LOCATION" "R3710")
		)
		("@t6g_mb_lib.t6g(sch_1):page208_i225@pure_quanta.\\9zxl0851ekilft\\(chips)"
			("LOCATION" "U102")
		)
		("@t6g_mb_lib.t6g(sch_1):page208_i246@pure_quanta.\\9zxl0851ekilft\\(chips)"
			("LOCATION" "U103")
		)
		("@t6g_mb_lib.t6g(sch_1):page206_i476@pure_quanta.q_cap(chips)"
			("LOCATION" "C119")
		)
		("@t6g_mb_lib.t6g(sch_1):page206_i472@pure_quanta.q_cap(chips)"
			("LOCATION" "C120")
		)
		("@t6g_mb_lib.t6g(sch_1):page206_i457@pure_quanta.q_cap(chips)"
			("LOCATION" "C122")
		)
		("@t6g_mb_lib.t6g(sch_1):page206_i529@pure_quanta.q_cap(chips)"
			("LOCATION" "C123")
		)
		("@t6g_mb_lib.t6g(sch_1):page206_i475@pure_quanta.q_cap(chips)"
			("LOCATION" "C125")
		)
		("@t6g_mb_lib.t6g(sch_1):page206_i459@pure_quanta.q_cap(chips)"
			("LOCATION" "C126")
		)
		("@t6g_mb_lib.t6g(sch_1):page206_i477@pure_quanta.q_cap(chips)"
			("LOCATION" "C127")
		)
		("@t6g_mb_lib.t6g(sch_1):page206_i479@pure_quanta.q_cap(chips)"
			("LOCATION" "C128")
		)
		("@t6g_mb_lib.t6g(sch_1):page206_i481@pure_quanta.q_cap(chips)"
			("LOCATION" "C129")
		)
		("@t6g_mb_lib.t6g(sch_1):page206_i451@pure_quanta.q_inductor(chips)"
			("LOCATION" "L87")
		)
		("@t6g_mb_lib.t6g(sch_1):page206_i453@pure_quanta.q_inductor(chips)"
			("LOCATION" "L88")
		)
		("@t6g_mb_lib.t6g(sch_1):page206_i448@pure_quanta.q_res(chips)"
			("LOCATION" "R112")
		)
		("@t6g_mb_lib.t6g(sch_1):page206_i443@pure_quanta.q_res(chips)"
			("LOCATION" "R172")
		)
		("@t6g_mb_lib.t6g(sch_1):page206_i442@pure_quanta.q_res(chips)"
			("LOCATION" "R202")
		)
		("@t6g_mb_lib.t6g(sch_1):page206_i447@pure_quanta.q_res(chips)"
			("LOCATION" "R455")
		)
		("@t6g_mb_lib.t6g(sch_1):page206_i441@pure_quanta.q_res(chips)"
			("LOCATION" "R463")
		)
		("@t6g_mb_lib.t6g(sch_1):page206_i444@pure_quanta.q_res(chips)"
			("LOCATION" "R464")
		)
		("@t6g_mb_lib.t6g(sch_1):page206_i470@pure_quanta.q_res(chips)"
			("LOCATION" "R465")
		)
		("@t6g_mb_lib.t6g(sch_1):page206_i471@pure_quanta.q_res(chips)"
			("LOCATION" "R466")
		)
		("@t6g_mb_lib.t6g(sch_1):page206_i580@pure_quanta.q_res(chips)"
			("LOCATION" "R467")
		)
		("@t6g_mb_lib.t6g(sch_1):page206_i594@pure_quanta.q_res(chips)"
			("LOCATION" "R3713")
		)
		("@t6g_mb_lib.t6g(sch_1):page206_i596@pure_quanta.q_res(chips)"
			("LOCATION" "R3714")
		)
		("@t6g_mb_lib.t6g(sch_1):page206_i598@pure_quanta.q_res(chips)"
			("LOCATION" "R3749")
		)
		("@t6g_mb_lib.t6g(sch_1):page206_i570@pure_quanta.\\9qxl2001bnhgi8\\(chips)"
			("LOCATION" "U105")
		)
		("@t6g_mb_lib.t6g(sch_1):page194_i52@pure_quanta.q_cap(chips)"
			("LOCATION" "C121")
		)
		("@t6g_mb_lib.t6g(sch_1):page194_i76@pure_quanta.q_cap(chips)"
			("LOCATION" "C124")
		)
		("@t6g_mb_lib.t6g(sch_1):page194_i73@pure_quanta.q_cap(chips)"
			("LOCATION" "C334")
		)
		("@t6g_mb_lib.t6g(sch_1):page194_i37@pure_quanta.q_cap(chips)"
			("LOCATION" "C1176")
		)
		("@t6g_mb_lib.t6g(sch_1):page194_i48@pure_quanta.q_cap(chips)"
			("LOCATION" "C2714")
		)
		("@t6g_mb_lib.t6g(sch_1):page194_i61@pure_quanta.q_cap(chips)"
			("LOCATION" "C2715")
		)
		("@t6g_mb_lib.t6g(sch_1):page194_i59@pure_quanta.q_res(chips)"
			("LOCATION" "R649")
		)
		("@t6g_mb_lib.t6g(sch_1):page194_i46@pure_quanta.q_res(chips)"
			("LOCATION" "R807")
		)
		("@t6g_mb_lib.t6g(sch_1):page194_i54@pure_quanta.q_res(chips)"
			("LOCATION" "R1712")
		)
		("@t6g_mb_lib.t6g(sch_1):page194_i79@pure_quanta.q_res(chips)"
			("LOCATION" "R2172")
		)
		("@t6g_mb_lib.t6g(sch_1):page194_i71@pure_quanta.q_res(chips)"
			("LOCATION" "R2173")
		)
		("@t6g_mb_lib.t6g(sch_1):page194_i80@pure_quanta.q_res(chips)"
			("LOCATION" "R3665")
		)
		("@t6g_mb_lib.t6g(sch_1):page194_i82@pure_quanta.q_res(chips)"
			("LOCATION" "R3675")
		)
		("@t6g_mb_lib.t6g(sch_1):page194_i23@pure_quanta.sn74hc595brwn(chips)"
			("LOCATION" "U47")
		)
		("@t6g_mb_lib.t6g(sch_1):page194_i39@pure_quanta.sn74hc595brwn(chips)"
			("LOCATION" "U65")
		)
		("@t6g_mb_lib.t6g(sch_1):page194_i45@pure_quanta.sn74lvc1g14dbvr(chips)"
			("LOCATION" "U211")
		)
		("@t6g_mb_lib.t6g(sch_1):page194_i58@pure_quanta.sn74lvc1g14dbvr(chips)"
			("LOCATION" "U212")
		)
		("@t6g_mb_lib.t6g(sch_1):page168_i146@pure_quanta.q_cap_diffbus(chips)"
			("LOCATION" "C130")
		)
		("@t6g_mb_lib.t6g(sch_1):page168_i145@pure_quanta.q_cap_diffbus(chips)"
			("LOCATION" "C131")
		)
		("@t6g_mb_lib.t6g(sch_1):page168_i144@pure_quanta.q_cap_diffbus(chips)"
			("LOCATION" "C132")
		)
		("@t6g_mb_lib.t6g(sch_1):page168_i134@pure_quanta.q_cap_diffbus(chips)"
			("LOCATION" "C133")
		)
		("@t6g_mb_lib.t6g(sch_1):page168_i139@pure_quanta.q_cap_diffbus(chips)"
			("LOCATION" "C134")
		)
		("@t6g_mb_lib.t6g(sch_1):page168_i138@pure_quanta.q_cap_diffbus(chips)"
			("LOCATION" "C135")
		)
		("@t6g_mb_lib.t6g(sch_1):page168_i137@pure_quanta.q_cap_diffbus(chips)"
			("LOCATION" "C136")
		)
		("@t6g_mb_lib.t6g(sch_1):page168_i136@pure_quanta.q_cap_diffbus(chips)"
			("LOCATION" "C137")
		)
		("@t6g_mb_lib.t6g(sch_1):page168_i147@pure_quanta.q_cap_diffbus(chips)"
			("LOCATION" "C138")
		)
		("@t6g_mb_lib.t6g(sch_1):page168_i133@pure_quanta.q_cap_diffbus(chips)"
			("LOCATION" "C201")
		)
		("@t6g_mb_lib.t6g(sch_1):page168_i143@pure_quanta.q_cap_diffbus(chips)"
			("LOCATION" "C202")
		)
		("@t6g_mb_lib.t6g(sch_1):page168_i148@pure_quanta.q_cap_diffbus(chips)"
			("LOCATION" "C203")
		)
		("@t6g_mb_lib.t6g(sch_1):page168_i142@pure_quanta.q_cap_diffbus(chips)"
			("LOCATION" "C204")
		)
		("@t6g_mb_lib.t6g(sch_1):page168_i141@pure_quanta.q_cap_diffbus(chips)"
			("LOCATION" "C205")
		)
		("@t6g_mb_lib.t6g(sch_1):page168_i140@pure_quanta.q_cap_diffbus(chips)"
			("LOCATION" "C206")
		)
		("@t6g_mb_lib.t6g(sch_1):page168_i135@pure_quanta.q_cap_diffbus(chips)"
			("LOCATION" "C207")
		)
		("@t6g_mb_lib.t6g(sch_1):page168_i151@pure_quanta.q_cap_diffbus(chips)"
			("LOCATION" "C208")
		)
		("@t6g_mb_lib.t6g(sch_1):page168_i152@pure_quanta.q_cap_diffbus(chips)"
			("LOCATION" "C209")
		)
		("@t6g_mb_lib.t6g(sch_1):page168_i158@pure_quanta.q_cap_diffbus(chips)"
			("LOCATION" "C210")
		)
		("@t6g_mb_lib.t6g(sch_1):page168_i159@pure_quanta.q_cap_diffbus(chips)"
			("LOCATION" "C211")
		)
		("@t6g_mb_lib.t6g(sch_1):page168_i160@pure_quanta.q_cap_diffbus(chips)"
			("LOCATION" "C319")
		)
		("@t6g_mb_lib.t6g(sch_1):page168_i161@pure_quanta.q_cap_diffbus(chips)"
			("LOCATION" "C331")
		)
		("@t6g_mb_lib.t6g(sch_1):page168_i162@pure_quanta.q_cap_diffbus(chips)"
			("LOCATION" "C596")
		)
		("@t6g_mb_lib.t6g(sch_1):page168_i163@pure_quanta.q_cap_diffbus(chips)"
			("LOCATION" "C597")
		)
		("@t6g_mb_lib.t6g(sch_1):page168_i149@pure_quanta.q_cap_diffbus(chips)"
			("LOCATION" "C598")
		)
		("@t6g_mb_lib.t6g(sch_1):page168_i150@pure_quanta.q_cap_diffbus(chips)"
			("LOCATION" "C599")
		)
		("@t6g_mb_lib.t6g(sch_1):page168_i153@pure_quanta.q_cap_diffbus(chips)"
			("LOCATION" "C600")
		)
		("@t6g_mb_lib.t6g(sch_1):page168_i154@pure_quanta.q_cap_diffbus(chips)"
			("LOCATION" "C601")
		)
		("@t6g_mb_lib.t6g(sch_1):page168_i155@pure_quanta.q_cap_diffbus(chips)"
			("LOCATION" "C602")
		)
		("@t6g_mb_lib.t6g(sch_1):page168_i156@pure_quanta.q_cap_diffbus(chips)"
			("LOCATION" "C603")
		)
		("@t6g_mb_lib.t6g(sch_1):page168_i157@pure_quanta.q_cap_diffbus(chips)"
			("LOCATION" "C604")
		)
		("@t6g_mb_lib.t6g(sch_1):page168_i164@pure_quanta.q_cap_diffbus(chips)"
			("LOCATION" "C605")
		)
		("@t6g_mb_lib.t6g(sch_1):page84_i117@pure_quanta.q_cap_diffbus(chips)"
			("LOCATION" "C139")
		)
		("@t6g_mb_lib.t6g(sch_1):page84_i118@pure_quanta.q_cap_diffbus(chips)"
			("LOCATION" "C140")
		)
		("@t6g_mb_lib.t6g(sch_1):page84_i119@pure_quanta.q_cap_diffbus(chips)"
			("LOCATION" "C141")
		)
		("@t6g_mb_lib.t6g(sch_1):page84_i120@pure_quanta.q_cap_diffbus(chips)"
			("LOCATION" "C142")
		)
		("@t6g_mb_lib.t6g(sch_1):page84_i121@pure_quanta.q_cap_diffbus(chips)"
			("LOCATION" "C143")
		)
		("@t6g_mb_lib.t6g(sch_1):page84_i122@pure_quanta.q_cap_diffbus(chips)"
			("LOCATION" "C144")
		)
		("@t6g_mb_lib.t6g(sch_1):page84_i135@pure_quanta.q_cap_diffbus(chips)"
			("LOCATION" "C145")
		)
		("@t6g_mb_lib.t6g(sch_1):page84_i134@pure_quanta.q_cap_diffbus(chips)"
			("LOCATION" "C146")
		)
		("@t6g_mb_lib.t6g(sch_1):page84_i133@pure_quanta.q_cap_diffbus(chips)"
			("LOCATION" "C147")
		)
		("@t6g_mb_lib.t6g(sch_1):page84_i136@pure_quanta.q_cap_diffbus(chips)"
			("LOCATION" "C148")
		)
		("@t6g_mb_lib.t6g(sch_1):page84_i137@pure_quanta.q_cap_diffbus(chips)"
			("LOCATION" "C149")
		)
		("@t6g_mb_lib.t6g(sch_1):page84_i138@pure_quanta.q_cap_diffbus(chips)"
			("LOCATION" "C150")
		)
		("@t6g_mb_lib.t6g(sch_1):page84_i139@pure_quanta.q_cap_diffbus(chips)"
			("LOCATION" "C151")
		)
		("@t6g_mb_lib.t6g(sch_1):page84_i140@pure_quanta.q_cap_diffbus(chips)"
			("LOCATION" "C152")
		)
		("@t6g_mb_lib.t6g(sch_1):page84_i142@pure_quanta.q_cap_diffbus(chips)"
			("LOCATION" "C153")
		)
		("@t6g_mb_lib.t6g(sch_1):page84_i141@pure_quanta.q_cap_diffbus(chips)"
			("LOCATION" "C154")
		)
		("@t6g_mb_lib.t6g(sch_1):page84_i168@pure_quanta.q_cap_diffbus(chips)"
			("LOCATION" "C155")
		)
		("@t6g_mb_lib.t6g(sch_1):page84_i169@pure_quanta.q_cap_diffbus(chips)"
			("LOCATION" "C156")
		)
		("@t6g_mb_lib.t6g(sch_1):page84_i171@pure_quanta.q_cap_diffbus(chips)"
			("LOCATION" "C157")
		)
		("@t6g_mb_lib.t6g(sch_1):page84_i170@pure_quanta.q_cap_diffbus(chips)"
			("LOCATION" "C158")
		)
		("@t6g_mb_lib.t6g(sch_1):page84_i173@pure_quanta.q_cap_diffbus(chips)"
			("LOCATION" "C159")
		)
		("@t6g_mb_lib.t6g(sch_1):page84_i172@pure_quanta.q_cap_diffbus(chips)"
			("LOCATION" "C160")
		)
		("@t6g_mb_lib.t6g(sch_1):page84_i181@pure_quanta.q_cap_diffbus(chips)"
			("LOCATION" "C161")
		)
		("@t6g_mb_lib.t6g(sch_1):page84_i191@pure_quanta.q_cap_diffbus(chips)"
			("LOCATION" "C162")
		)
		("@t6g_mb_lib.t6g(sch_1):page84_i190@pure_quanta.q_cap_diffbus(chips)"
			("LOCATION" "C163")
		)
		("@t6g_mb_lib.t6g(sch_1):page84_i105@pure_quanta.q_cap_diffbus(chips)"
			("LOCATION" "C164")
		)
		("@t6g_mb_lib.t6g(sch_1):page84_i193@pure_quanta.q_cap_diffbus(chips)"
			("LOCATION" "C165")
		)
		("@t6g_mb_lib.t6g(sch_1):page84_i192@pure_quanta.q_cap_diffbus(chips)"
			("LOCATION" "C166")
		)
		("@t6g_mb_lib.t6g(sch_1):page84_i194@pure_quanta.q_cap_diffbus(chips)"
			("LOCATION" "C167")
		)
		("@t6g_mb_lib.t6g(sch_1):page84_i195@pure_quanta.q_cap_diffbus(chips)"
			("LOCATION" "C168")
		)
		("@t6g_mb_lib.t6g(sch_1):page84_i197@pure_quanta.q_cap_diffbus(chips)"
			("LOCATION" "C169")
		)
		("@t6g_mb_lib.t6g(sch_1):page84_i196@pure_quanta.q_cap_diffbus(chips)"
			("LOCATION" "C170")
		)
		("@t6g_mb_lib.t6g(sch_1):page172_i16@pure_quanta.q_cap_diffbus(chips)"
			("LOCATION" "C171")
		)
		("@t6g_mb_lib.t6g(sch_1):page172_i9@pure_quanta.q_cap_diffbus(chips)"
			("LOCATION" "C172")
		)
		("@t6g_mb_lib.t6g(sch_1):page172_i6@pure_quanta.q_cap_diffbus(chips)"
			("LOCATION" "C173")
		)
		("@t6g_mb_lib.t6g(sch_1):page172_i72@pure_quanta.q_cap_diffbus(chips)"
			("LOCATION" "C174")
		)
		("@t6g_mb_lib.t6g(sch_1):page172_i70@pure_quanta.q_cap_diffbus(chips)"
			("LOCATION" "C175")
		)
		("@t6g_mb_lib.t6g(sch_1):page172_i62@pure_quanta.q_cap_diffbus(chips)"
			("LOCATION" "C176")
		)
		("@t6g_mb_lib.t6g(sch_1):page172_i20@pure_quanta.q_cap_diffbus(chips)"
			("LOCATION" "C177")
		)
		("@t6g_mb_lib.t6g(sch_1):page172_i18@pure_quanta.q_cap_diffbus(chips)"
			("LOCATION" "C178")
		)
		("@t6g_mb_lib.t6g(sch_1):page172_i10@pure_quanta.q_cap_diffbus(chips)"
			("LOCATION" "C179")
		)
		("@t6g_mb_lib.t6g(sch_1):page172_i8@pure_quanta.q_cap_diffbus(chips)"
			("LOCATION" "C180")
		)
		("@t6g_mb_lib.t6g(sch_1):page172_i7@pure_quanta.q_cap_diffbus(chips)"
			("LOCATION" "C181")
		)
		("@t6g_mb_lib.t6g(sch_1):page172_i92@pure_quanta.q_cap_diffbus(chips)"
			("LOCATION" "C182")
		)
		("@t6g_mb_lib.t6g(sch_1):page172_i90@pure_quanta.q_cap_diffbus(chips)"
			("LOCATION" "C183")
		)
		("@t6g_mb_lib.t6g(sch_1):page172_i49@pure_quanta.q_cap_diffbus(chips)"
			("LOCATION" "C185")
		)
		("@t6g_mb_lib.t6g(sch_1):page172_i47@pure_quanta.q_cap_diffbus(chips)"
			("LOCATION" "C186")
		)
		("@t6g_mb_lib.t6g(sch_1):page172_i46@pure_quanta.q_cap_diffbus(chips)"
			("LOCATION" "C187")
		)
		("@t6g_mb_lib.t6g(sch_1):page172_i39@pure_quanta.q_cap_diffbus(chips)"
			("LOCATION" "C188")
		)
		("@t6g_mb_lib.t6g(sch_1):page172_i36@pure_quanta.q_cap_diffbus(chips)"
			("LOCATION" "C189")
		)
		("@t6g_mb_lib.t6g(sch_1):page172_i91@pure_quanta.q_cap_diffbus(chips)"
			("LOCATION" "C190")
		)
		("@t6g_mb_lib.t6g(sch_1):page172_i89@pure_quanta.q_cap_diffbus(chips)"
			("LOCATION" "C191")
		)
		("@t6g_mb_lib.t6g(sch_1):page172_i61@pure_quanta.q_cap_diffbus(chips)"
			("LOCATION" "C192")
		)
		("@t6g_mb_lib.t6g(sch_1):page172_i50@pure_quanta.q_cap_diffbus(chips)"
			("LOCATION" "C193")
		)
		("@t6g_mb_lib.t6g(sch_1):page172_i48@pure_quanta.q_cap_diffbus(chips)"
			("LOCATION" "C194")
		)
		("@t6g_mb_lib.t6g(sch_1):page172_i40@pure_quanta.q_cap_diffbus(chips)"
			("LOCATION" "C195")
		)
		("@t6g_mb_lib.t6g(sch_1):page172_i38@pure_quanta.q_cap_diffbus(chips)"
			("LOCATION" "C196")
		)
		("@t6g_mb_lib.t6g(sch_1):page172_i37@pure_quanta.q_cap_diffbus(chips)"
			("LOCATION" "C197")
		)
		("@t6g_mb_lib.t6g(sch_1):page172_i88@pure_quanta.q_cap_diffbus(chips)"
			("LOCATION" "C704")
		)
		("@t6g_mb_lib.t6g(sch_1):page172_i73@pure_quanta.q_cap_diffbus(chips)"
			("LOCATION" "C2557")
		)
		("@t6g_mb_lib.t6g(sch_1):page172_i71@pure_quanta.q_cap_diffbus(chips)"
			("LOCATION" "C2558")
		)
		("@t6g_mb_lib.t6g(sch_1):page172_i69@pure_quanta.q_cap_diffbus(chips)"
			("LOCATION" "C2559")
		)
		("@t6g_mb_lib.t6g(sch_1):page172_i19@pure_quanta.q_cap_diffbus(chips)"
			("LOCATION" "C2560")
		)
		("@t6g_mb_lib.t6g(sch_1):page172_i17@pure_quanta.q_cap_diffbus(chips)"
			("LOCATION" "C2561")
		)
		("@t6g_mb_lib.t6g(sch_1):page279_i31@pure_quanta.q_cap(chips)"
			("LOCATION" "C184")
		)
		("@t6g_mb_lib.t6g(sch_1):page279_i41@pure_quanta.q_cap(chips)"
			("LOCATION" "C199")
		)
		("@t6g_mb_lib.t6g(sch_1):page279_i33@pure_quanta.q_cap(chips)"
			("LOCATION" "C706")
		)
		("@t6g_mb_lib.t6g(sch_1):page279_i39@pure_quanta.q_cap(chips)"
			("LOCATION" "C707")
		)
		("@t6g_mb_lib.t6g(sch_1):page279_i45@pure_quanta.q_cap(chips)"
			("LOCATION" "C708")
		)
		("@t6g_mb_lib.t6g(sch_1):page279_i50@pure_quanta.q_diode(chips)"
			("LOCATION" "D76")
		)
		("@t6g_mb_lib.t6g(sch_1):page279_i56@pure_quanta.q_diode(chips)"
			("LOCATION" "D79")
		)
		("@t6g_mb_lib.t6g(sch_1):page279_i21@pure_quanta.mosfet_dual_6p(chips)"
			("LOCATION" "Q20")
		)
		("@t6g_mb_lib.t6g(sch_1):page279_i10@pure_quanta.q_res(chips)"
			("LOCATION" "R892")
		)
		("@t6g_mb_lib.t6g(sch_1):page279_i22@pure_quanta.q_res(chips)"
			("LOCATION" "R1067")
		)
		("@t6g_mb_lib.t6g(sch_1):page279_i24@pure_quanta.q_res(chips)"
			("LOCATION" "R1068")
		)
		("@t6g_mb_lib.t6g(sch_1):page279_i20@pure_quanta.q_res(chips)"
			("LOCATION" "R1069")
		)
		("@t6g_mb_lib.t6g(sch_1):page279_i19@pure_quanta.q_res(chips)"
			("LOCATION" "R1070")
		)
		("@t6g_mb_lib.t6g(sch_1):page279_i8@pure_quanta.q_res(chips)"
			("LOCATION" "R1071")
		)
		("@t6g_mb_lib.t6g(sch_1):page279_i7@pure_quanta.q_res(chips)"
			("LOCATION" "R1072")
		)
		("@t6g_mb_lib.t6g(sch_1):page279_i11@pure_quanta.q_res(chips)"
			("LOCATION" "R1073")
		)
		("@t6g_mb_lib.t6g(sch_1):page279_i53@pure_quanta.q_res(chips)"
			("LOCATION" "R3584")
		)
		("@t6g_mb_lib.t6g(sch_1):page279_i52@pure_quanta.q_res(chips)"
			("LOCATION" "R3585")
		)
		("@t6g_mb_lib.t6g(sch_1):page279_i48@pure_quanta.sn74lvc1g08dbvr(chips)"
			("LOCATION" "U39")
		)
		("@t6g_mb_lib.t6g(sch_1):page279_i49@pure_quanta.sn74lvc1g08dbvr(chips)"
			("LOCATION" "U40")
		)
		("@t6g_mb_lib.t6g(sch_1):page279_i43@pure_quanta.sn74lvc1g32dbvr(chips)"
			("LOCATION" "U41")
		)
		("@t6g_mb_lib.t6g(sch_1):page279_i28@pure_quanta.sn74lvc1g08dbvr(chips)"
			("LOCATION" "U42")
		)
		("@t6g_mb_lib.t6g(sch_1):page279_i35@pure_quanta.sn74lvc1g32dbvr(chips)"
			("LOCATION" "U76")
		)
		("@t6g_mb_lib.t6g(sch_1):page164_i48@pure_quanta.q_cap_diffbus(chips)"
			("LOCATION" "C198")
		)
		("@t6g_mb_lib.t6g(sch_1):page164_i18@pure_quanta.q_cap_diffbus(chips)"
			("LOCATION" "C200")
		)
		("@t6g_mb_lib.t6g(sch_1):page164_i63@pure_quanta.q_cap_diffbus(chips)"
			("LOCATION" "C375")
		)
		("@t6g_mb_lib.t6g(sch_1):page164_i90@pure_quanta.q_cap_diffbus(chips)"
			("LOCATION" "C378")
		)
		("@t6g_mb_lib.t6g(sch_1):page164_i22@pure_quanta.q_cap_diffbus(chips)"
			("LOCATION" "C705")
		)
		("@t6g_mb_lib.t6g(sch_1):page164_i15@pure_quanta.q_cap_diffbus(chips)"
			("LOCATION" "C2483")
		)
		("@t6g_mb_lib.t6g(sch_1):page164_i14@pure_quanta.q_cap_diffbus(chips)"
			("LOCATION" "C2484")
		)
		("@t6g_mb_lib.t6g(sch_1):page164_i10@pure_quanta.q_cap_diffbus(chips)"
			("LOCATION" "C2485")
		)
		("@t6g_mb_lib.t6g(sch_1):page164_i7@pure_quanta.q_cap_diffbus(chips)"
			("LOCATION" "C2486")
		)
		("@t6g_mb_lib.t6g(sch_1):page164_i3@pure_quanta.q_cap_diffbus(chips)"
			("LOCATION" "C2487")
		)
		("@t6g_mb_lib.t6g(sch_1):page164_i40@pure_quanta.q_cap_diffbus(chips)"
			("LOCATION" "C2488")
		)
		("@t6g_mb_lib.t6g(sch_1):page164_i39@pure_quanta.q_cap_diffbus(chips)"
			("LOCATION" "C2489")
		)
		("@t6g_mb_lib.t6g(sch_1):page164_i38@pure_quanta.q_cap_diffbus(chips)"
			("LOCATION" "C2490")
		)
		("@t6g_mb_lib.t6g(sch_1):page164_i32@pure_quanta.q_cap_diffbus(chips)"
			("LOCATION" "C2491")
		)
		("@t6g_mb_lib.t6g(sch_1):page164_i31@pure_quanta.q_cap_diffbus(chips)"
			("LOCATION" "C2492")
		)
		("@t6g_mb_lib.t6g(sch_1):page164_i25@pure_quanta.q_cap_diffbus(chips)"
			("LOCATION" "C2493")
		)
		("@t6g_mb_lib.t6g(sch_1):page164_i24@pure_quanta.q_cap_diffbus(chips)"
			("LOCATION" "C2494")
		)
		("@t6g_mb_lib.t6g(sch_1):page164_i98@pure_quanta.q_cap_diffbus(chips)"
			("LOCATION" "C2495")
		)
		("@t6g_mb_lib.t6g(sch_1):page164_i72@pure_quanta.q_cap_diffbus(chips)"
			("LOCATION" "C2496")
		)
		("@t6g_mb_lib.t6g(sch_1):page164_i71@pure_quanta.q_cap_diffbus(chips)"
			("LOCATION" "C2497")
		)
		("@t6g_mb_lib.t6g(sch_1):page164_i65@pure_quanta.q_cap_diffbus(chips)"
			("LOCATION" "C2498")
		)
		("@t6g_mb_lib.t6g(sch_1):page164_i64@pure_quanta.q_cap_diffbus(chips)"
			("LOCATION" "C2499")
		)
		("@t6g_mb_lib.t6g(sch_1):page164_i57@pure_quanta.q_cap_diffbus(chips)"
			("LOCATION" "C2500")
		)
		("@t6g_mb_lib.t6g(sch_1):page164_i55@pure_quanta.q_cap_diffbus(chips)"
			("LOCATION" "C2501")
		)
		("@t6g_mb_lib.t6g(sch_1):page164_i89@pure_quanta.q_cap_diffbus(chips)"
			("LOCATION" "C2502")
		)
		("@t6g_mb_lib.t6g(sch_1):page164_i88@pure_quanta.q_cap_diffbus(chips)"
			("LOCATION" "C2503")
		)
		("@t6g_mb_lib.t6g(sch_1):page164_i82@pure_quanta.q_cap_diffbus(chips)"
			("LOCATION" "C2504")
		)
		("@t6g_mb_lib.t6g(sch_1):page164_i81@pure_quanta.q_cap_diffbus(chips)"
			("LOCATION" "C2505")
		)
		("@t6g_mb_lib.t6g(sch_1):page164_i75@pure_quanta.q_cap_diffbus(chips)"
			("LOCATION" "C2506")
		)
		("@t6g_mb_lib.t6g(sch_1):page164_i74@pure_quanta.q_cap_diffbus(chips)"
			("LOCATION" "C2507")
		)
		("@t6g_mb_lib.t6g(sch_1):page164_i23@pure_quanta.q_cap_diffbus(chips)"
			("LOCATION" "C2543")
		)
		("@t6g_mb_lib.t6g(sch_1):page164_i73@pure_quanta.q_cap_diffbus(chips)"
			("LOCATION" "C2556")
		)
		("@t6g_mb_lib.t6g(sch_1):page80_i385@pure_quanta.q_cap(chips)"
			("LOCATION" "C221")
		)
		("@t6g_mb_lib.t6g(sch_1):page80_i388@pure_quanta.q_cap(chips)"
			("LOCATION" "C222")
		)
		("@t6g_mb_lib.t6g(sch_1):page80_i391@pure_quanta.q_cap(chips)"
			("LOCATION" "C223")
		)
		("@t6g_mb_lib.t6g(sch_1):page80_i400@pure_quanta.q_cap(chips)"
			("LOCATION" "C224")
		)
		("@t6g_mb_lib.t6g(sch_1):page80_i403@pure_quanta.q_cap(chips)"
			("LOCATION" "C225")
		)
		("@t6g_mb_lib.t6g(sch_1):page80_i384@pure_quanta.q_cap(chips)"
			("LOCATION" "C226")
		)
		("@t6g_mb_lib.t6g(sch_1):page80_i387@pure_quanta.q_cap(chips)"
			("LOCATION" "C227")
		)
		("@t6g_mb_lib.t6g(sch_1):page80_i390@pure_quanta.q_cap(chips)"
			("LOCATION" "C228")
		)
		("@t6g_mb_lib.t6g(sch_1):page80_i399@pure_quanta.q_cap(chips)"
			("LOCATION" "C229")
		)
		("@t6g_mb_lib.t6g(sch_1):page80_i402@pure_quanta.q_cap(chips)"
			("LOCATION" "C230")
		)
		("@t6g_mb_lib.t6g(sch_1):page80_i380@pure_quanta.q_cap(chips)"
			("LOCATION" "C231")
		)
		("@t6g_mb_lib.t6g(sch_1):page80_i381@pure_quanta.q_cap(chips)"
			("LOCATION" "C232")
		)
		("@t6g_mb_lib.t6g(sch_1):page80_i383@pure_quanta.q_cap(chips)"
			("LOCATION" "C233")
		)
		("@t6g_mb_lib.t6g(sch_1):page80_i394@pure_quanta.q_cap(chips)"
			("LOCATION" "C234")
		)
		("@t6g_mb_lib.t6g(sch_1):page80_i397@pure_quanta.q_cap(chips)"
			("LOCATION" "C235")
		)
		("@t6g_mb_lib.t6g(sch_1):page80_i378@pure_quanta.q_cap(chips)"
			("LOCATION" "C236")
		)
		("@t6g_mb_lib.t6g(sch_1):page80_i379@pure_quanta.q_cap(chips)"
			("LOCATION" "C237")
		)
		("@t6g_mb_lib.t6g(sch_1):page80_i382@pure_quanta.q_cap(chips)"
			("LOCATION" "C238")
		)
		("@t6g_mb_lib.t6g(sch_1):page80_i393@pure_quanta.q_cap(chips)"
			("LOCATION" "C239")
		)
		("@t6g_mb_lib.t6g(sch_1):page80_i395@pure_quanta.q_cap(chips)"
			("LOCATION" "C240")
		)
		("@t6g_mb_lib.t6g(sch_1):page80_i337@pure_quanta.q_cap(chips)"
			("LOCATION" "C241")
		)
		("@t6g_mb_lib.t6g(sch_1):page80_i338@pure_quanta.q_cap(chips)"
			("LOCATION" "C242")
		)
		("@t6g_mb_lib.t6g(sch_1):page80_i340@pure_quanta.q_cap(chips)"
			("LOCATION" "C243")
		)
		("@t6g_mb_lib.t6g(sch_1):page80_i368@pure_quanta.q_cap(chips)"
			("LOCATION" "C244")
		)
		("@t6g_mb_lib.t6g(sch_1):page80_i372@pure_quanta.q_cap(chips)"
			("LOCATION" "C245")
		)
		("@t6g_mb_lib.t6g(sch_1):page80_i335@pure_quanta.q_cap(chips)"
			("LOCATION" "C246")
		)
		("@t6g_mb_lib.t6g(sch_1):page80_i336@pure_quanta.q_cap(chips)"
			("LOCATION" "C247")
		)
		("@t6g_mb_lib.t6g(sch_1):page80_i339@pure_quanta.q_cap(chips)"
			("LOCATION" "C248")
		)
		("@t6g_mb_lib.t6g(sch_1):page80_i367@pure_quanta.q_cap(chips)"
			("LOCATION" "C249")
		)
		("@t6g_mb_lib.t6g(sch_1):page80_i369@pure_quanta.q_cap(chips)"
			("LOCATION" "C250")
		)
		("@t6g_mb_lib.t6g(sch_1):page80_i331@pure_quanta.q_cap(chips)"
			("LOCATION" "C251")
		)
		("@t6g_mb_lib.t6g(sch_1):page80_i332@pure_quanta.q_cap(chips)"
			("LOCATION" "C252")
		)
		("@t6g_mb_lib.t6g(sch_1):page80_i334@pure_quanta.q_cap(chips)"
			("LOCATION" "C253")
		)
		("@t6g_mb_lib.t6g(sch_1):page80_i362@pure_quanta.q_cap(chips)"
			("LOCATION" "C254")
		)
		("@t6g_mb_lib.t6g(sch_1):page80_i365@pure_quanta.q_cap(chips)"
			("LOCATION" "C255")
		)
		("@t6g_mb_lib.t6g(sch_1):page80_i329@pure_quanta.q_cap(chips)"
			("LOCATION" "C256")
		)
		("@t6g_mb_lib.t6g(sch_1):page80_i330@pure_quanta.q_cap(chips)"
			("LOCATION" "C257")
		)
		("@t6g_mb_lib.t6g(sch_1):page80_i333@pure_quanta.q_cap(chips)"
			("LOCATION" "C258")
		)
		("@t6g_mb_lib.t6g(sch_1):page80_i361@pure_quanta.q_cap(chips)"
			("LOCATION" "C259")
		)
		("@t6g_mb_lib.t6g(sch_1):page80_i363@pure_quanta.q_cap(chips)"
			("LOCATION" "C260")
		)
		("@t6g_mb_lib.t6g(sch_1):page80_i319@pure_quanta.q_cap(chips)"
			("LOCATION" "C261")
		)
		("@t6g_mb_lib.t6g(sch_1):page80_i321@pure_quanta.q_cap(chips)"
			("LOCATION" "C262")
		)
		("@t6g_mb_lib.t6g(sch_1):page80_i328@pure_quanta.q_cap(chips)"
			("LOCATION" "C263")
		)
		("@t6g_mb_lib.t6g(sch_1):page80_i351@pure_quanta.q_cap(chips)"
			("LOCATION" "C264")
		)
		("@t6g_mb_lib.t6g(sch_1):page80_i355@pure_quanta.q_cap(chips)"
			("LOCATION" "C265")
		)
		("@t6g_mb_lib.t6g(sch_1):page80_i317@pure_quanta.q_cap(chips)"
			("LOCATION" "C266")
		)
		("@t6g_mb_lib.t6g(sch_1):page80_i320@pure_quanta.q_cap(chips)"
			("LOCATION" "C267")
		)
		("@t6g_mb_lib.t6g(sch_1):page80_i326@pure_quanta.q_cap(chips)"
			("LOCATION" "C268")
		)
		("@t6g_mb_lib.t6g(sch_1):page80_i350@pure_quanta.q_cap(chips)"
			("LOCATION" "C269")
		)
		("@t6g_mb_lib.t6g(sch_1):page80_i352@pure_quanta.q_cap(chips)"
			("LOCATION" "C270")
		)
		("@t6g_mb_lib.t6g(sch_1):page80_i314@pure_quanta.q_cap(chips)"
			("LOCATION" "C271")
		)
		("@t6g_mb_lib.t6g(sch_1):page80_i316@pure_quanta.q_cap(chips)"
			("LOCATION" "C272")
		)
		("@t6g_mb_lib.t6g(sch_1):page80_i323@pure_quanta.q_cap(chips)"
			("LOCATION" "C273")
		)
		("@t6g_mb_lib.t6g(sch_1):page80_i348@pure_quanta.q_cap(chips)"
			("LOCATION" "C274")
		)
		("@t6g_mb_lib.t6g(sch_1):page80_i310@pure_quanta.q_cap(chips)"
			("LOCATION" "C275")
		)
		("@t6g_mb_lib.t6g(sch_1):page80_i311@pure_quanta.q_cap(chips)"
			("LOCATION" "C276")
		)
		("@t6g_mb_lib.t6g(sch_1):page80_i313@pure_quanta.q_cap(chips)"
			("LOCATION" "C277")
		)
		("@t6g_mb_lib.t6g(sch_1):page80_i343@pure_quanta.q_cap(chips)"
			("LOCATION" "C278")
		)
		("@t6g_mb_lib.t6g(sch_1):page80_i308@pure_quanta.q_cap(chips)"
			("LOCATION" "C279")
		)
		("@t6g_mb_lib.t6g(sch_1):page80_i309@pure_quanta.q_cap(chips)"
			("LOCATION" "C280")
		)
		("@t6g_mb_lib.t6g(sch_1):page80_i312@pure_quanta.q_cap(chips)"
			("LOCATION" "C281")
		)
		("@t6g_mb_lib.t6g(sch_1):page80_i341@pure_quanta.q_cap(chips)"
			("LOCATION" "C282")
		)
		("@t6g_mb_lib.t6g(sch_1):page80_i292@pure_quanta.q_cap(chips)"
			("LOCATION" "C283")
		)
		("@t6g_mb_lib.t6g(sch_1):page80_i293@pure_quanta.q_cap(chips)"
			("LOCATION" "C284")
		)
		("@t6g_mb_lib.t6g(sch_1):page80_i295@pure_quanta.q_cap(chips)"
			("LOCATION" "C285")
		)
		("@t6g_mb_lib.t6g(sch_1):page80_i303@pure_quanta.q_cap(chips)"
			("LOCATION" "C286")
		)
		("@t6g_mb_lib.t6g(sch_1):page80_i290@pure_quanta.q_cap(chips)"
			("LOCATION" "C287")
		)
		("@t6g_mb_lib.t6g(sch_1):page80_i291@pure_quanta.q_cap(chips)"
			("LOCATION" "C288")
		)
		("@t6g_mb_lib.t6g(sch_1):page80_i294@pure_quanta.q_cap(chips)"
			("LOCATION" "C289")
		)
		("@t6g_mb_lib.t6g(sch_1):page80_i302@pure_quanta.q_cap(chips)"
			("LOCATION" "C290")
		)
		("@t6g_mb_lib.t6g(sch_1):page80_i286@pure_quanta.q_cap(chips)"
			("LOCATION" "C291")
		)
		("@t6g_mb_lib.t6g(sch_1):page80_i287@pure_quanta.q_cap(chips)"
			("LOCATION" "C292")
		)
		("@t6g_mb_lib.t6g(sch_1):page80_i289@pure_quanta.q_cap(chips)"
			("LOCATION" "C293")
		)
		("@t6g_mb_lib.t6g(sch_1):page80_i300@pure_quanta.q_cap(chips)"
			("LOCATION" "C294")
		)
		("@t6g_mb_lib.t6g(sch_1):page80_i284@pure_quanta.q_cap(chips)"
			("LOCATION" "C295")
		)
		("@t6g_mb_lib.t6g(sch_1):page80_i285@pure_quanta.q_cap(chips)"
			("LOCATION" "C296")
		)
		("@t6g_mb_lib.t6g(sch_1):page80_i288@pure_quanta.q_cap(chips)"
			("LOCATION" "C297")
		)
		("@t6g_mb_lib.t6g(sch_1):page80_i299@pure_quanta.q_cap(chips)"
			("LOCATION" "C298")
		)
		("@t6g_mb_lib.t6g(sch_1):page80_i283@pure_quanta.q_cap(chips)"
			("LOCATION" "C299")
		)
		("@t6g_mb_lib.t6g(sch_1):page80_i282@pure_quanta.q_cap(chips)"
			("LOCATION" "C300")
		)
		("@t6g_mb_lib.t6g(sch_1):page80_i281@pure_quanta.q_cap(chips)"
			("LOCATION" "C301")
		)
		("@t6g_mb_lib.t6g(sch_1):page80_i297@pure_quanta.q_cap(chips)"
			("LOCATION" "C302")
		)
		("@t6g_mb_lib.t6g(sch_1):page80_i275@pure_quanta.q_cap(chips)"
			("LOCATION" "C303")
		)
		("@t6g_mb_lib.t6g(sch_1):page80_i276@pure_quanta.q_cap(chips)"
			("LOCATION" "C304")
		)
		("@t6g_mb_lib.t6g(sch_1):page80_i280@pure_quanta.q_cap(chips)"
			("LOCATION" "C305")
		)
		("@t6g_mb_lib.t6g(sch_1):page80_i296@pure_quanta.q_cap(chips)"
			("LOCATION" "C306")
		)
		("@t6g_mb_lib.t6g(sch_1):page80_i272@pure_quanta.q_cap(chips)"
			("LOCATION" "C307")
		)
		("@t6g_mb_lib.t6g(sch_1):page80_i274@pure_quanta.q_cap(chips)"
			("LOCATION" "C308")
		)
		("@t6g_mb_lib.t6g(sch_1):page80_i278@pure_quanta.q_cap(chips)"
			("LOCATION" "C309")
		)
		("@t6g_mb_lib.t6g(sch_1):page80_i344@pure_quanta.q_cap(chips)"
			("LOCATION" "C310")
		)
		("@t6g_mb_lib.t6g(sch_1):page80_i406@pure_quanta.q_cap(chips)"
			("LOCATION" "C423")
		)
		("@t6g_mb_lib.t6g(sch_1):page80_i412@pure_quanta.q_cap(chips)"
			("LOCATION" "C424")
		)
		("@t6g_mb_lib.t6g(sch_1):page80_i405@pure_quanta.q_cap(chips)"
			("LOCATION" "C425")
		)
		("@t6g_mb_lib.t6g(sch_1):page80_i411@pure_quanta.q_cap(chips)"
			("LOCATION" "C426")
		)
		("@t6g_mb_lib.t6g(sch_1):page80_i398@pure_quanta.q_cap(chips)"
			("LOCATION" "C427")
		)
		("@t6g_mb_lib.t6g(sch_1):page80_i409@pure_quanta.q_cap(chips)"
			("LOCATION" "C428")
		)
		("@t6g_mb_lib.t6g(sch_1):page80_i396@pure_quanta.q_cap(chips)"
			("LOCATION" "C429")
		)
		("@t6g_mb_lib.t6g(sch_1):page80_i408@pure_quanta.q_cap(chips)"
			("LOCATION" "C430")
		)
		("@t6g_mb_lib.t6g(sch_1):page80_i376@pure_quanta.q_cap(chips)"
			("LOCATION" "C431")
		)
		("@t6g_mb_lib.t6g(sch_1):page80_i371@pure_quanta.q_cap(chips)"
			("LOCATION" "C432")
		)
		("@t6g_mb_lib.t6g(sch_1):page80_i375@pure_quanta.q_cap(chips)"
			("LOCATION" "C433")
		)
		("@t6g_mb_lib.t6g(sch_1):page80_i366@pure_quanta.q_cap(chips)"
			("LOCATION" "C434")
		)
		("@t6g_mb_lib.t6g(sch_1):page80_i374@pure_quanta.q_cap(chips)"
			("LOCATION" "C435")
		)
		("@t6g_mb_lib.t6g(sch_1):page80_i364@pure_quanta.q_cap(chips)"
			("LOCATION" "C436")
		)
		("@t6g_mb_lib.t6g(sch_1):page80_i373@pure_quanta.q_cap(chips)"
			("LOCATION" "C437")
		)
		("@t6g_mb_lib.t6g(sch_1):page80_i356@pure_quanta.q_cap(chips)"
			("LOCATION" "C438")
		)
		("@t6g_mb_lib.t6g(sch_1):page80_i360@pure_quanta.q_cap(chips)"
			("LOCATION" "C439")
		)
		("@t6g_mb_lib.t6g(sch_1):page80_i353@pure_quanta.q_cap(chips)"
			("LOCATION" "C440")
		)
		("@t6g_mb_lib.t6g(sch_1):page80_i358@pure_quanta.q_cap(chips)"
			("LOCATION" "C441")
		)
		("@t6g_mb_lib.t6g(sch_1):page80_i271@pure_quanta.q_cap(chips)"
			("LOCATION" "C442")
		)
		("@t6g_mb_lib.t6g(sch_1):page80_i347@pure_quanta.q_cap(chips)"
			("LOCATION" "C443")
		)
		("@t6g_mb_lib.t6g(sch_1):page80_i305@pure_quanta.q_cap(chips)"
			("LOCATION" "C444")
		)
		("@t6g_mb_lib.t6g(sch_1):page80_i304@pure_quanta.q_cap(chips)"
			("LOCATION" "C445")
		)
		("@t6g_mb_lib.t6g(sch_1):page80_i301@pure_quanta.q_cap(chips)"
			("LOCATION" "C446")
		)
		("@t6g_mb_lib.t6g(sch_1):page81_i200@pure_quanta.q_cap(chips)"
			("LOCATION" "C311")
		)
		("@t6g_mb_lib.t6g(sch_1):page81_i202@pure_quanta.q_cap(chips)"
			("LOCATION" "C312")
		)
		("@t6g_mb_lib.t6g(sch_1):page81_i160@pure_quanta.q_cap(chips)"
			("LOCATION" "C313")
		)
		("@t6g_mb_lib.t6g(sch_1):page81_i179@pure_quanta.q_cap(chips)"
			("LOCATION" "C314")
		)
		("@t6g_mb_lib.t6g(sch_1):page81_i190@pure_quanta.q_cap(chips)"
			("LOCATION" "C315")
		)
		("@t6g_mb_lib.t6g(sch_1):page81_i158@pure_quanta.q_cap(chips)"
			("LOCATION" "C316")
		)
		("@t6g_mb_lib.t6g(sch_1):page81_i178@pure_quanta.q_cap(chips)"
			("LOCATION" "C317")
		)
		("@t6g_mb_lib.t6g(sch_1):page81_i189@pure_quanta.q_cap(chips)"
			("LOCATION" "C318")
		)
		("@t6g_mb_lib.t6g(sch_1):page81_i177@pure_quanta.q_cap(chips)"
			("LOCATION" "C320")
		)
		("@t6g_mb_lib.t6g(sch_1):page81_i186@pure_quanta.q_cap(chips)"
			("LOCATION" "C321")
		)
		("@t6g_mb_lib.t6g(sch_1):page81_i176@pure_quanta.q_cap(chips)"
			("LOCATION" "C323")
		)
		("@t6g_mb_lib.t6g(sch_1):page81_i185@pure_quanta.q_cap(chips)"
			("LOCATION" "C324")
		)
		("@t6g_mb_lib.t6g(sch_1):page81_i175@pure_quanta.q_cap(chips)"
			("LOCATION" "C326")
		)
		("@t6g_mb_lib.t6g(sch_1):page81_i184@pure_quanta.q_cap(chips)"
			("LOCATION" "C327")
		)
		("@t6g_mb_lib.t6g(sch_1):page81_i174@pure_quanta.q_cap(chips)"
			("LOCATION" "C329")
		)
		("@t6g_mb_lib.t6g(sch_1):page81_i183@pure_quanta.q_cap(chips)"
			("LOCATION" "C330")
		)
		("@t6g_mb_lib.t6g(sch_1):page81_i173@pure_quanta.q_cap(chips)"
			("LOCATION" "C332")
		)
		("@t6g_mb_lib.t6g(sch_1):page81_i182@pure_quanta.q_cap(chips)"
			("LOCATION" "C333")
		)
		("@t6g_mb_lib.t6g(sch_1):page81_i172@pure_quanta.q_cap(chips)"
			("LOCATION" "C335")
		)
		("@t6g_mb_lib.t6g(sch_1):page81_i181@pure_quanta.q_cap(chips)"
			("LOCATION" "C336")
		)
		("@t6g_mb_lib.t6g(sch_1):page81_i152@pure_quanta.q_cap(chips)"
			("LOCATION" "C337")
		)
		("@t6g_mb_lib.t6g(sch_1):page81_i171@pure_quanta.q_cap(chips)"
			("LOCATION" "C338")
		)
		("@t6g_mb_lib.t6g(sch_1):page81_i180@pure_quanta.q_cap(chips)"
			("LOCATION" "C339")
		)
		("@t6g_mb_lib.t6g(sch_1):page81_i150@pure_quanta.q_cap(chips)"
			("LOCATION" "C340")
		)
		("@t6g_mb_lib.t6g(sch_1):page81_i155@pure_quanta.q_cap(chips)"
			("LOCATION" "C349")
		)
		("@t6g_mb_lib.t6g(sch_1):page81_i154@pure_quanta.q_cap(chips)"
			("LOCATION" "C351")
		)
		("@t6g_mb_lib.t6g(sch_1):page81_i153@pure_quanta.q_cap(chips)"
			("LOCATION" "C353")
		)
		("@t6g_mb_lib.t6g(sch_1):page81_i204@pure_quanta.q_cap(chips)"
			("LOCATION" "C447")
		)
		("@t6g_mb_lib.t6g(sch_1):page81_i206@pure_quanta.q_cap(chips)"
			("LOCATION" "C448")
		)
		("@t6g_mb_lib.t6g(sch_1):page81_i215@pure_quanta.q_cap(chips)"
			("LOCATION" "C449")
		)
		("@t6g_mb_lib.t6g(sch_1):page81_i192@pure_quanta.q_cap(chips)"
			("LOCATION" "C451")
		)
		("@t6g_mb_lib.t6g(sch_1):page81_i195@pure_quanta.q_cap(chips)"
			("LOCATION" "C452")
		)
		("@t6g_mb_lib.t6g(sch_1):page81_i213@pure_quanta.q_cap(chips)"
			("LOCATION" "C453")
		)
		("@t6g_mb_lib.t6g(sch_1):page81_i212@pure_quanta.q_cap(chips)"
			("LOCATION" "C457")
		)
		("@t6g_mb_lib.t6g(sch_1):page81_i211@pure_quanta.q_cap(chips)"
			("LOCATION" "C461")
		)
		("@t6g_mb_lib.t6g(sch_1):page81_i209@pure_quanta.q_cap(chips)"
			("LOCATION" "C465")
		)
		("@t6g_mb_lib.t6g(sch_1):page81_i191@pure_quanta.q_cap(chips)"
			("LOCATION" "C471")
		)
		("@t6g_mb_lib.t6g(sch_1):page81_i187@pure_quanta.q_cap(chips)"
			("LOCATION" "C474")
		)
		("@t6g_mb_lib.t6g(sch_1):page81_i208@pure_quanta.q_cap(chips)"
			("LOCATION" "C478")
		)
		("@t6g_mb_lib.t6g(sch_1):page81_i149@pure_quanta.q_cap(chips)"
			("LOCATION" "C480")
		)
		("@t6g_mb_lib.t6g(sch_1):page81_i148@pure_quanta.q_cap(chips)"
			("LOCATION" "C483")
		)
		("@t6g_mb_lib.t6g(sch_1):page81_i198@pure_quanta.q_cap(chips)"
			("LOCATION" "C488")
		)
		("@t6g_mb_lib.t6g(sch_1):page81_i197@pure_quanta.q_cap(chips)"
			("LOCATION" "C489")
		)
		("@t6g_mb_lib.t6g(sch_1):page81_i193@pure_quanta.q_cap(chips)"
			("LOCATION" "C490")
		)
		("@t6g_mb_lib.t6g(sch_1):page81_i167@pure_quanta.q_cap(chips)"
			("LOCATION" "C1387")
		)
		("@t6g_mb_lib.t6g(sch_1):page81_i170@pure_quanta.q_cap(chips)"
			("LOCATION" "C1388")
		)
		("@t6g_mb_lib.t6g(sch_1):page81_i165@pure_quanta.q_cap(chips)"
			("LOCATION" "C1389")
		)
		("@t6g_mb_lib.t6g(sch_1):page81_i168@pure_quanta.q_cap(chips)"
			("LOCATION" "C1390")
		)
		("@t6g_mb_lib.t6g(sch_1):page81_i164@pure_quanta.q_cap(chips)"
			("LOCATION" "C1391")
		)
		("@t6g_mb_lib.t6g(sch_1):page81_i163@pure_quanta.q_cap(chips)"
			("LOCATION" "C1392")
		)
		("@t6g_mb_lib.t6g(sch_1):page81_i161@pure_quanta.q_cap(chips)"
			("LOCATION" "C1393")
		)
		("@t6g_mb_lib.t6g(sch_1):page82_i129@pure_quanta.q_cap(chips)"
			("LOCATION" "C322")
		)
		("@t6g_mb_lib.t6g(sch_1):page82_i128@pure_quanta.q_cap(chips)"
			("LOCATION" "C325")
		)
		("@t6g_mb_lib.t6g(sch_1):page82_i125@pure_quanta.q_cap(chips)"
			("LOCATION" "C328")
		)
		("@t6g_mb_lib.t6g(sch_1):page82_i124@pure_quanta.q_cap(chips)"
			("LOCATION" "C341")
		)
		("@t6g_mb_lib.t6g(sch_1):page82_i152@pure_quanta.q_cap(chips)"
			("LOCATION" "C342")
		)
		("@t6g_mb_lib.t6g(sch_1):page82_i123@pure_quanta.q_cap(chips)"
			("LOCATION" "C343")
		)
		("@t6g_mb_lib.t6g(sch_1):page82_i151@pure_quanta.q_cap(chips)"
			("LOCATION" "C344")
		)
		("@t6g_mb_lib.t6g(sch_1):page82_i122@pure_quanta.q_cap(chips)"
			("LOCATION" "C345")
		)
		("@t6g_mb_lib.t6g(sch_1):page82_i150@pure_quanta.q_cap(chips)"
			("LOCATION" "C346")
		)
		("@t6g_mb_lib.t6g(sch_1):page82_i120@pure_quanta.q_cap(chips)"
			("LOCATION" "C347")
		)
		("@t6g_mb_lib.t6g(sch_1):page82_i143@pure_quanta.q_cap(chips)"
			("LOCATION" "C348")
		)
		("@t6g_mb_lib.t6g(sch_1):page82_i142@pure_quanta.q_cap(chips)"
			("LOCATION" "C350")
		)
		("@t6g_mb_lib.t6g(sch_1):page82_i141@pure_quanta.q_cap(chips)"
			("LOCATION" "C352")
		)
		("@t6g_mb_lib.t6g(sch_1):page82_i140@pure_quanta.q_cap(chips)"
			("LOCATION" "C354")
		)
		("@t6g_mb_lib.t6g(sch_1):page82_i174@pure_quanta.q_cap(chips)"
			("LOCATION" "C450")
		)
		("@t6g_mb_lib.t6g(sch_1):page82_i172@pure_quanta.q_cap(chips)"
			("LOCATION" "C454")
		)
		("@t6g_mb_lib.t6g(sch_1):page82_i156@pure_quanta.q_cap(chips)"
			("LOCATION" "C455")
		)
		("@t6g_mb_lib.t6g(sch_1):page82_i160@pure_quanta.q_cap(chips)"
			("LOCATION" "C456")
		)
		("@t6g_mb_lib.t6g(sch_1):page82_i171@pure_quanta.q_cap(chips)"
			("LOCATION" "C458")
		)
		("@t6g_mb_lib.t6g(sch_1):page82_i155@pure_quanta.q_cap(chips)"
			("LOCATION" "C459")
		)
		("@t6g_mb_lib.t6g(sch_1):page82_i159@pure_quanta.q_cap(chips)"
			("LOCATION" "C460")
		)
		("@t6g_mb_lib.t6g(sch_1):page82_i170@pure_quanta.q_cap(chips)"
			("LOCATION" "C462")
		)
		("@t6g_mb_lib.t6g(sch_1):page82_i154@pure_quanta.q_cap(chips)"
			("LOCATION" "C463")
		)
		("@t6g_mb_lib.t6g(sch_1):page82_i158@pure_quanta.q_cap(chips)"
			("LOCATION" "C464")
		)
		("@t6g_mb_lib.t6g(sch_1):page82_i168@pure_quanta.q_cap(chips)"
			("LOCATION" "C466")
		)
		("@t6g_mb_lib.t6g(sch_1):page82_i144@pure_quanta.q_cap(chips)"
			("LOCATION" "C467")
		)
		("@t6g_mb_lib.t6g(sch_1):page82_i149@pure_quanta.q_cap(chips)"
			("LOCATION" "C468")
		)
		("@t6g_mb_lib.t6g(sch_1):page82_i167@pure_quanta.q_cap(chips)"
			("LOCATION" "C470")
		)
		("@t6g_mb_lib.t6g(sch_1):page82_i148@pure_quanta.q_cap(chips)"
			("LOCATION" "C472")
		)
		("@t6g_mb_lib.t6g(sch_1):page82_i166@pure_quanta.q_cap(chips)"
			("LOCATION" "C473")
		)
		("@t6g_mb_lib.t6g(sch_1):page82_i146@pure_quanta.q_cap(chips)"
			("LOCATION" "C475")
		)
		("@t6g_mb_lib.t6g(sch_1):page82_i138@pure_quanta.q_cap(chips)"
			("LOCATION" "C476")
		)
		("@t6g_mb_lib.t6g(sch_1):page82_i137@pure_quanta.q_cap(chips)"
			("LOCATION" "C477")
		)
		("@t6g_mb_lib.t6g(sch_1):page82_i136@pure_quanta.q_cap(chips)"
			("LOCATION" "C479")
		)
		("@t6g_mb_lib.t6g(sch_1):page82_i162@pure_quanta.q_cap(chips)"
			("LOCATION" "C481")
		)
		("@t6g_mb_lib.t6g(sch_1):page82_i134@pure_quanta.q_cap(chips)"
			("LOCATION" "C482")
		)
		("@t6g_mb_lib.t6g(sch_1):page82_i163@pure_quanta.q_cap(chips)"
			("LOCATION" "C484")
		)
		("@t6g_mb_lib.t6g(sch_1):page82_i133@pure_quanta.q_cap(chips)"
			("LOCATION" "C485")
		)
		("@t6g_mb_lib.t6g(sch_1):page82_i164@pure_quanta.q_cap(chips)"
			("LOCATION" "C486")
		)
		("@t6g_mb_lib.t6g(sch_1):page82_i165@pure_quanta.q_cap(chips)"
			("LOCATION" "C487")
		)
		("@t6g_mb_lib.t6g(sch_1):page82_i126@pure_quanta.q_cap(chips)"
			("LOCATION" "C1353")
		)
		("@t6g_mb_lib.t6g(sch_1):page82_i132@pure_quanta.q_cap(chips)"
			("LOCATION" "C1403")
		)
		("@t6g_mb_lib.t6g(sch_1):page82_i131@pure_quanta.q_cap(chips)"
			("LOCATION" "C1404")
		)
		("@t6g_mb_lib.t6g(sch_1):page78_i193@pure_quanta.q_cap(chips)"
			("LOCATION" "C355")
		)
		("@t6g_mb_lib.t6g(sch_1):page78_i195@pure_quanta.q_cap(chips)"
			("LOCATION" "C356")
		)
		("@t6g_mb_lib.t6g(sch_1):page78_i178@pure_quanta.q_cap(chips)"
			("LOCATION" "C357")
		)
		("@t6g_mb_lib.t6g(sch_1):page78_i189@pure_quanta.q_cap(chips)"
			("LOCATION" "C358")
		)
		("@t6g_mb_lib.t6g(sch_1):page78_i191@pure_quanta.q_cap(chips)"
			("LOCATION" "C359")
		)
		("@t6g_mb_lib.t6g(sch_1):page78_i162@pure_quanta.q_cap(chips)"
			("LOCATION" "C360")
		)
		("@t6g_mb_lib.t6g(sch_1):page78_i188@pure_quanta.q_cap(chips)"
			("LOCATION" "C361")
		)
		("@t6g_mb_lib.t6g(sch_1):page78_i190@pure_quanta.q_cap(chips)"
			("LOCATION" "C362")
		)
		("@t6g_mb_lib.t6g(sch_1):page78_i153@pure_quanta.q_cap(chips)"
			("LOCATION" "C363")
		)
		("@t6g_mb_lib.t6g(sch_1):page78_i182@pure_quanta.q_cap(chips)"
			("LOCATION" "C364")
		)
		("@t6g_mb_lib.t6g(sch_1):page78_i184@pure_quanta.q_cap(chips)"
			("LOCATION" "C365")
		)
		("@t6g_mb_lib.t6g(sch_1):page78_i181@pure_quanta.q_cap(chips)"
			("LOCATION" "C367")
		)
		("@t6g_mb_lib.t6g(sch_1):page78_i183@pure_quanta.q_cap(chips)"
			("LOCATION" "C368")
		)
		("@t6g_mb_lib.t6g(sch_1):page78_i177@pure_quanta.q_cap(chips)"
			("LOCATION" "C370")
		)
		("@t6g_mb_lib.t6g(sch_1):page78_i180@pure_quanta.q_cap(chips)"
			("LOCATION" "C371")
		)
		("@t6g_mb_lib.t6g(sch_1):page78_i176@pure_quanta.q_cap(chips)"
			("LOCATION" "C373")
		)
		("@t6g_mb_lib.t6g(sch_1):page78_i175@pure_quanta.q_cap(chips)"
			("LOCATION" "C376")
		)
		("@t6g_mb_lib.t6g(sch_1):page78_i166@pure_quanta.q_cap(chips)"
			("LOCATION" "C379")
		)
		("@t6g_mb_lib.t6g(sch_1):page78_i152@pure_quanta.q_cap(chips)"
			("LOCATION" "C381")
		)
		("@t6g_mb_lib.t6g(sch_1):page78_i165@pure_quanta.q_cap(chips)"
			("LOCATION" "C382")
		)
		("@t6g_mb_lib.t6g(sch_1):page78_i150@pure_quanta.q_cap(chips)"
			("LOCATION" "C384")
		)
		("@t6g_mb_lib.t6g(sch_1):page78_i161@pure_quanta.q_cap(chips)"
			("LOCATION" "C385")
		)
		("@t6g_mb_lib.t6g(sch_1):page78_i160@pure_quanta.q_cap(chips)"
			("LOCATION" "C387")
		)
		("@t6g_mb_lib.t6g(sch_1):page78_i168@pure_quanta.q_cap(chips)"
			("LOCATION" "C389")
		)
		("@t6g_mb_lib.t6g(sch_1):page78_i167@pure_quanta.q_cap(chips)"
			("LOCATION" "C391")
		)
		("@t6g_mb_lib.t6g(sch_1):page78_i164@pure_quanta.q_cap(chips)"
			("LOCATION" "C393")
		)
		("@t6g_mb_lib.t6g(sch_1):page78_i170@pure_quanta.q_cap(chips)"
			("LOCATION" "C395")
		)
		("@t6g_mb_lib.t6g(sch_1):page78_i179@pure_quanta.q_cap(chips)"
			("LOCATION" "C397")
		)
		("@t6g_mb_lib.t6g(sch_1):page78_i203@pure_quanta.q_cap(chips)"
			("LOCATION" "C491")
		)
		("@t6g_mb_lib.t6g(sch_1):page78_i205@pure_quanta.q_cap(chips)"
			("LOCATION" "C492")
		)
		("@t6g_mb_lib.t6g(sch_1):page78_i215@pure_quanta.q_cap(chips)"
			("LOCATION" "C493")
		)
		("@t6g_mb_lib.t6g(sch_1):page78_i198@pure_quanta.q_cap(chips)"
			("LOCATION" "C495")
		)
		("@t6g_mb_lib.t6g(sch_1):page78_i200@pure_quanta.q_cap(chips)"
			("LOCATION" "C496")
		)
		("@t6g_mb_lib.t6g(sch_1):page78_i213@pure_quanta.q_cap(chips)"
			("LOCATION" "C497")
		)
		("@t6g_mb_lib.t6g(sch_1):page78_i212@pure_quanta.q_cap(chips)"
			("LOCATION" "C501")
		)
		("@t6g_mb_lib.t6g(sch_1):page78_i210@pure_quanta.q_cap(chips)"
			("LOCATION" "C505")
		)
		("@t6g_mb_lib.t6g(sch_1):page78_i208@pure_quanta.q_cap(chips)"
			("LOCATION" "C509")
		)
		("@t6g_mb_lib.t6g(sch_1):page78_i197@pure_quanta.q_cap(chips)"
			("LOCATION" "C515")
		)
		("@t6g_mb_lib.t6g(sch_1):page78_i185@pure_quanta.q_cap(chips)"
			("LOCATION" "C518")
		)
		("@t6g_mb_lib.t6g(sch_1):page78_i207@pure_quanta.q_cap(chips)"
			("LOCATION" "C522")
		)
		("@t6g_mb_lib.t6g(sch_1):page78_i149@pure_quanta.q_cap(chips)"
			("LOCATION" "C524")
		)
		("@t6g_mb_lib.t6g(sch_1):page78_i148@pure_quanta.q_cap(chips)"
			("LOCATION" "C527")
		)
		("@t6g_mb_lib.t6g(sch_1):page78_i202@pure_quanta.q_cap(chips)"
			("LOCATION" "C532")
		)
		("@t6g_mb_lib.t6g(sch_1):page78_i199@pure_quanta.q_cap(chips)"
			("LOCATION" "C533")
		)
		("@t6g_mb_lib.t6g(sch_1):page78_i187@pure_quanta.q_cap(chips)"
			("LOCATION" "C534")
		)
		("@t6g_mb_lib.t6g(sch_1):page78_i173@pure_quanta.q_cap(chips)"
			("LOCATION" "C1396")
		)
		("@t6g_mb_lib.t6g(sch_1):page78_i172@pure_quanta.q_cap(chips)"
			("LOCATION" "C1397")
		)
		("@t6g_mb_lib.t6g(sch_1):page78_i158@pure_quanta.q_cap(chips)"
			("LOCATION" "C1398")
		)
		("@t6g_mb_lib.t6g(sch_1):page78_i169@pure_quanta.q_cap(chips)"
			("LOCATION" "C1405")
		)
		("@t6g_mb_lib.t6g(sch_1):page78_i156@pure_quanta.q_cap(chips)"
			("LOCATION" "C1406")
		)
		("@t6g_mb_lib.t6g(sch_1):page78_i155@pure_quanta.q_cap(chips)"
			("LOCATION" "C1407")
		)
		("@t6g_mb_lib.t6g(sch_1):page79_i127@pure_quanta.q_cap(chips)"
			("LOCATION" "C366")
		)
		("@t6g_mb_lib.t6g(sch_1):page79_i126@pure_quanta.q_cap(chips)"
			("LOCATION" "C369")
		)
		("@t6g_mb_lib.t6g(sch_1):page79_i125@pure_quanta.q_cap(chips)"
			("LOCATION" "C372")
		)
		("@t6g_mb_lib.t6g(sch_1):page79_i124@pure_quanta.q_cap(chips)"
			("LOCATION" "C374")
		)
		("@t6g_mb_lib.t6g(sch_1):page79_i123@pure_quanta.q_cap(chips)"
			("LOCATION" "C377")
		)
		("@t6g_mb_lib.t6g(sch_1):page79_i122@pure_quanta.q_cap(chips)"
			("LOCATION" "C380")
		)
		("@t6g_mb_lib.t6g(sch_1):page79_i121@pure_quanta.q_cap(chips)"
			("LOCATION" "C383")
		)
		("@t6g_mb_lib.t6g(sch_1):page79_i153@pure_quanta.q_cap(chips)"
			("LOCATION" "C386")
		)
		("@t6g_mb_lib.t6g(sch_1):page79_i152@pure_quanta.q_cap(chips)"
			("LOCATION" "C388")
		)
		("@t6g_mb_lib.t6g(sch_1):page79_i150@pure_quanta.q_cap(chips)"
			("LOCATION" "C390")
		)
		("@t6g_mb_lib.t6g(sch_1):page79_i131@pure_quanta.q_cap(chips)"
			("LOCATION" "C392")
		)
		("@t6g_mb_lib.t6g(sch_1):page79_i130@pure_quanta.q_cap(chips)"
			("LOCATION" "C394")
		)
		("@t6g_mb_lib.t6g(sch_1):page79_i129@pure_quanta.q_cap(chips)"
			("LOCATION" "C396")
		)
		("@t6g_mb_lib.t6g(sch_1):page79_i128@pure_quanta.q_cap(chips)"
			("LOCATION" "C398")
		)
		("@t6g_mb_lib.t6g(sch_1):page79_i174@pure_quanta.q_cap(chips)"
			("LOCATION" "C494")
		)
		("@t6g_mb_lib.t6g(sch_1):page79_i173@pure_quanta.q_cap(chips)"
			("LOCATION" "C498")
		)
		("@t6g_mb_lib.t6g(sch_1):page79_i157@pure_quanta.q_cap(chips)"
			("LOCATION" "C499")
		)
		("@t6g_mb_lib.t6g(sch_1):page79_i166@pure_quanta.q_cap(chips)"
			("LOCATION" "C500")
		)
		("@t6g_mb_lib.t6g(sch_1):page79_i172@pure_quanta.q_cap(chips)"
			("LOCATION" "C502")
		)
		("@t6g_mb_lib.t6g(sch_1):page79_i155@pure_quanta.q_cap(chips)"
			("LOCATION" "C503")
		)
		("@t6g_mb_lib.t6g(sch_1):page79_i165@pure_quanta.q_cap(chips)"
			("LOCATION" "C504")
		)
		("@t6g_mb_lib.t6g(sch_1):page79_i149@pure_quanta.q_cap(chips)"
			("LOCATION" "C506")
		)
		("@t6g_mb_lib.t6g(sch_1):page79_i154@pure_quanta.q_cap(chips)"
			("LOCATION" "C507")
		)
		("@t6g_mb_lib.t6g(sch_1):page79_i164@pure_quanta.q_cap(chips)"
			("LOCATION" "C508")
		)
		("@t6g_mb_lib.t6g(sch_1):page79_i148@pure_quanta.q_cap(chips)"
			("LOCATION" "C510")
		)
		("@t6g_mb_lib.t6g(sch_1):page79_i132@pure_quanta.q_cap(chips)"
			("LOCATION" "C511")
		)
		("@t6g_mb_lib.t6g(sch_1):page79_i143@pure_quanta.q_cap(chips)"
			("LOCATION" "C512")
		)
		("@t6g_mb_lib.t6g(sch_1):page79_i147@pure_quanta.q_cap(chips)"
			("LOCATION" "C514")
		)
		("@t6g_mb_lib.t6g(sch_1):page79_i142@pure_quanta.q_cap(chips)"
			("LOCATION" "C516")
		)
		("@t6g_mb_lib.t6g(sch_1):page79_i146@pure_quanta.q_cap(chips)"
			("LOCATION" "C517")
		)
		("@t6g_mb_lib.t6g(sch_1):page79_i140@pure_quanta.q_cap(chips)"
			("LOCATION" "C519")
		)
		("@t6g_mb_lib.t6g(sch_1):page79_i139@pure_quanta.q_cap(chips)"
			("LOCATION" "C520")
		)
		("@t6g_mb_lib.t6g(sch_1):page79_i138@pure_quanta.q_cap(chips)"
			("LOCATION" "C521")
		)
		("@t6g_mb_lib.t6g(sch_1):page79_i137@pure_quanta.q_cap(chips)"
			("LOCATION" "C523")
		)
		("@t6g_mb_lib.t6g(sch_1):page79_i170@pure_quanta.q_cap(chips)"
			("LOCATION" "C525")
		)
		("@t6g_mb_lib.t6g(sch_1):page79_i136@pure_quanta.q_cap(chips)"
			("LOCATION" "C526")
		)
		("@t6g_mb_lib.t6g(sch_1):page79_i169@pure_quanta.q_cap(chips)"
			("LOCATION" "C528")
		)
		("@t6g_mb_lib.t6g(sch_1):page79_i134@pure_quanta.q_cap(chips)"
			("LOCATION" "C529")
		)
		("@t6g_mb_lib.t6g(sch_1):page79_i168@pure_quanta.q_cap(chips)"
			("LOCATION" "C530")
		)
		("@t6g_mb_lib.t6g(sch_1):page79_i144@pure_quanta.q_cap(chips)"
			("LOCATION" "C531")
		)
		("@t6g_mb_lib.t6g(sch_1):page79_i159@pure_quanta.q_cap(chips)"
			("LOCATION" "C1362")
		)
		("@t6g_mb_lib.t6g(sch_1):page79_i162@pure_quanta.q_cap(chips)"
			("LOCATION" "C1399")
		)
		("@t6g_mb_lib.t6g(sch_1):page79_i161@pure_quanta.q_cap(chips)"
			("LOCATION" "C1400")
		)
		("@t6g_mb_lib.t6g(sch_1):page250_i48@pure_quanta.q_cap(chips)"
			("LOCATION" "C469")
		)
		("@t6g_mb_lib.t6g(sch_1):page250_i9@pure_quanta.q_cap(chips)"
			("LOCATION" "C568")
		)
		("@t6g_mb_lib.t6g(sch_1):page250_i10@pure_quanta.q_cap(chips)"
			("LOCATION" "C569")
		)
		("@t6g_mb_lib.t6g(sch_1):page250_i35@pure_quanta.q_cap(chips)"
			("LOCATION" "C570")
		)
		("@t6g_mb_lib.t6g(sch_1):page250_i25@pure_quanta.q_cap(chips)"
			("LOCATION" "C571")
		)
		("@t6g_mb_lib.t6g(sch_1):page250_i61@pure_quanta.q_cap(chips)"
			("LOCATION" "C576")
		)
		("@t6g_mb_lib.t6g(sch_1):page250_i53@pure_quanta.q_cap(chips)"
			("LOCATION" "C577")
		)
		("@t6g_mb_lib.t6g(sch_1):page250_i98@pure_quanta.q_cap(chips)"
			("LOCATION" "C580")
		)
		("@t6g_mb_lib.t6g(sch_1):page250_i100@pure_quanta.q_cap(chips)"
			("LOCATION" "C581")
		)
		("@t6g_mb_lib.t6g(sch_1):page250_i103@pure_quanta.q_cap(chips)"
			("LOCATION" "C582")
		)
		("@t6g_mb_lib.t6g(sch_1):page250_i79@pure_quanta.q_cap(chips)"
			("LOCATION" "C583")
		)
		("@t6g_mb_lib.t6g(sch_1):page250_i70@pure_quanta.q_cap(chips)"
			("LOCATION" "C584")
		)
		("@t6g_mb_lib.t6g(sch_1):page250_i89@pure_quanta.q_cap(chips)"
			("LOCATION" "C680")
		)
		("@t6g_mb_lib.t6g(sch_1):page250_i127@pure_quanta.q_cap(chips)"
			("LOCATION" "C681")
		)
		("@t6g_mb_lib.t6g(sch_1):page250_i134@pure_quanta.q_cap(chips)"
			("LOCATION" "C682")
		)
		("@t6g_mb_lib.t6g(sch_1):page250_i143@pure_quanta.q_cap(chips)"
			("LOCATION" "C683")
		)
		("@t6g_mb_lib.t6g(sch_1):page250_i159@pure_quanta.q_cap(chips)"
			("LOCATION" "C684")
		)
		("@t6g_mb_lib.t6g(sch_1):page250_i165@pure_quanta.q_cap(chips)"
			("LOCATION" "C685")
		)
		("@t6g_mb_lib.t6g(sch_1):page250_i149@pure_quanta.q_cap(chips)"
			("LOCATION" "C686")
		)
		("@t6g_mb_lib.t6g(sch_1):page250_i11@pure_quanta.q_res(chips)"
			("LOCATION" "R883")
		)
		("@t6g_mb_lib.t6g(sch_1):page250_i17@pure_quanta.q_res(chips)"
			("LOCATION" "R885")
		)
		("@t6g_mb_lib.t6g(sch_1):page250_i29@pure_quanta.q_res(chips)"
			("LOCATION" "R886")
		)
		("@t6g_mb_lib.t6g(sch_1):page250_i37@pure_quanta.q_res(chips)"
			("LOCATION" "R889")
		)
		("@t6g_mb_lib.t6g(sch_1):page250_i45@pure_quanta.q_res(chips)"
			("LOCATION" "R977")
		)
		("@t6g_mb_lib.t6g(sch_1):page250_i46@pure_quanta.q_res(chips)"
			("LOCATION" "R978")
		)
		("@t6g_mb_lib.t6g(sch_1):page250_i67@pure_quanta.q_res(chips)"
			("LOCATION" "R980")
		)
		("@t6g_mb_lib.t6g(sch_1):page250_i65@pure_quanta.q_res(chips)"
			("LOCATION" "R981")
		)
		("@t6g_mb_lib.t6g(sch_1):page250_i59@pure_quanta.q_res(chips)"
			("LOCATION" "R982")
		)
		("@t6g_mb_lib.t6g(sch_1):page250_i57@pure_quanta.q_res(chips)"
			("LOCATION" "R983")
		)
		("@t6g_mb_lib.t6g(sch_1):page250_i106@pure_quanta.q_res(chips)"
			("LOCATION" "R984")
		)
		("@t6g_mb_lib.t6g(sch_1):page250_i107@pure_quanta.q_res(chips)"
			("LOCATION" "R985")
		)
		("@t6g_mb_lib.t6g(sch_1):page250_i110@pure_quanta.q_res(chips)"
			("LOCATION" "R989")
		)
		("@t6g_mb_lib.t6g(sch_1):page250_i111@pure_quanta.q_res(chips)"
			("LOCATION" "R990")
		)
		("@t6g_mb_lib.t6g(sch_1):page250_i114@pure_quanta.q_res(chips)"
			("LOCATION" "R991")
		)
		("@t6g_mb_lib.t6g(sch_1):page250_i115@pure_quanta.q_res(chips)"
			("LOCATION" "R992")
		)
		("@t6g_mb_lib.t6g(sch_1):page250_i76@pure_quanta.q_res(chips)"
			("LOCATION" "R993")
		)
		("@t6g_mb_lib.t6g(sch_1):page250_i77@pure_quanta.q_res(chips)"
			("LOCATION" "R994")
		)
		("@t6g_mb_lib.t6g(sch_1):page250_i86@pure_quanta.q_res(chips)"
			("LOCATION" "R995")
		)
		("@t6g_mb_lib.t6g(sch_1):page250_i95@pure_quanta.q_res(chips)"
			("LOCATION" "R996")
		)
		("@t6g_mb_lib.t6g(sch_1):page250_i93@pure_quanta.q_res(chips)"
			("LOCATION" "R1010")
		)
		("@t6g_mb_lib.t6g(sch_1):page250_i128@pure_quanta.q_res(chips)"
			("LOCATION" "R1011")
		)
		("@t6g_mb_lib.t6g(sch_1):page250_i129@pure_quanta.q_res(chips)"
			("LOCATION" "R1012")
		)
		("@t6g_mb_lib.t6g(sch_1):page250_i132@pure_quanta.q_res(chips)"
			("LOCATION" "R1013")
		)
		("@t6g_mb_lib.t6g(sch_1):page250_i136@pure_quanta.q_res(chips)"
			("LOCATION" "R1014")
		)
		("@t6g_mb_lib.t6g(sch_1):page250_i141@pure_quanta.q_res(chips)"
			("LOCATION" "R1015")
		)
		("@t6g_mb_lib.t6g(sch_1):page250_i146@pure_quanta.q_res(chips)"
			("LOCATION" "R1016")
		)
		("@t6g_mb_lib.t6g(sch_1):page250_i152@pure_quanta.q_res(chips)"
			("LOCATION" "R1017")
		)
		("@t6g_mb_lib.t6g(sch_1):page250_i153@pure_quanta.q_res(chips)"
			("LOCATION" "R1018")
		)
		("@t6g_mb_lib.t6g(sch_1):page250_i156@pure_quanta.q_res(chips)"
			("LOCATION" "R1019")
		)
		("@t6g_mb_lib.t6g(sch_1):page250_i162@pure_quanta.q_res(chips)"
			("LOCATION" "R1031")
		)
		("@t6g_mb_lib.t6g(sch_1):page250_i179@pure_quanta.q_res(chips)"
			("LOCATION" "R3764")
		)
		("@t6g_mb_lib.t6g(sch_1):page250_i185@pure_quanta.q_res(chips)"
			("LOCATION" "R3765")
		)
		("@t6g_mb_lib.t6g(sch_1):page250_i206@pure_quanta.q_res(chips)"
			("LOCATION" "R3857")
		)
		("@t6g_mb_lib.t6g(sch_1):page250_i207@pure_quanta.q_res(chips)"
			("LOCATION" "R3858")
		)
		("@t6g_mb_lib.t6g(sch_1):page250_i1@pure_quanta.ads7830ipwr(chips)"
			("LOCATION" "U34")
		)
		("@t6g_mb_lib.t6g(sch_1):page250_i21@pure_quanta.ads7830ipwr(chips)"
			("LOCATION" "U35")
		)
		("@t6g_mb_lib.t6g(sch_1):page281_i217@pure_quanta.q_capp(chips)"
			("LOCATION" "C538")
		)
		("@t6g_mb_lib.t6g(sch_1):page281_i284@pure_quanta.q_capp(chips)"
			("LOCATION" "C547")
		)
		("@t6g_mb_lib.t6g(sch_1):page281_i216@pure_quanta.q_cap(chips)"
			("LOCATION" "C548")
		)
		("@t6g_mb_lib.t6g(sch_1):page281_i282@pure_quanta.q_cap(chips)"
			("LOCATION" "C553")
		)
		("@t6g_mb_lib.t6g(sch_1):page281_i214@pure_quanta.q_cap(chips)"
			("LOCATION" "C564")
		)
		("@t6g_mb_lib.t6g(sch_1):page281_i281@pure_quanta.q_cap(chips)"
			("LOCATION" "C565")
		)
		("@t6g_mb_lib.t6g(sch_1):page281_i331@pure_quanta.q_diode(chips)"
			("LOCATION" "D45")
		)
		("@t6g_mb_lib.t6g(sch_1):page281_i343@pure_quanta.q_diode(chips)"
			("LOCATION" "D46")
		)
		("@t6g_mb_lib.t6g(sch_1):page281_i358@pure_quanta.conn50_10147875001lf(chips)"
			("LOCATION" "J100")
		)
		("@t6g_mb_lib.t6g(sch_1):page281_i357@pure_quanta.conn50_10147875001lf(chips)"
			("LOCATION" "J101")
		)
		("@t6g_mb_lib.t6g(sch_1):page281_i335@pure_quanta.q_res(chips)"
			("LOCATION" "R1276")
		)
		("@t6g_mb_lib.t6g(sch_1):page281_i332@pure_quanta.q_res(chips)"
			("LOCATION" "R1277")
		)
		("@t6g_mb_lib.t6g(sch_1):page281_i348@pure_quanta.q_res(chips)"
			("LOCATION" "R1278")
		)
		("@t6g_mb_lib.t6g(sch_1):page281_i344@pure_quanta.q_res(chips)"
			("LOCATION" "R1279")
		)
		("@t6g_mb_lib.t6g(sch_1):page281_i320@pure_quanta.q_res(chips)"
			("LOCATION" "R1280")
		)
		("@t6g_mb_lib.t6g(sch_1):page281_i350@pure_quanta.q_res(chips)"
			("LOCATION" "R1281")
		)
		("@t6g_mb_lib.t6g(sch_1):page281_i311@pure_quanta.q_res(chips)"
			("LOCATION" "R3586")
		)
		("@t6g_mb_lib.t6g(sch_1):page281_i309@pure_quanta.q_res(chips)"
			("LOCATION" "R3587")
		)
		("@t6g_mb_lib.t6g(sch_1):page281_i304@pure_quanta.q_res(chips)"
			("LOCATION" "R3588")
		)
		("@t6g_mb_lib.t6g(sch_1):page281_i307@pure_quanta.q_res(chips)"
			("LOCATION" "R3589")
		)
		("@t6g_mb_lib.t6g(sch_1):page199_i136@pure_quanta.q_cap(chips)"
			("LOCATION" "C539")
		)
		("@t6g_mb_lib.t6g(sch_1):page199_i141@pure_quanta.q_cap(chips)"
			("LOCATION" "C540")
		)
		("@t6g_mb_lib.t6g(sch_1):page199_i135@pure_quanta.q_cap(chips)"
			("LOCATION" "C541")
		)
		("@t6g_mb_lib.t6g(sch_1):page199_i140@pure_quanta.q_cap(chips)"
			("LOCATION" "C542")
		)
		("@t6g_mb_lib.t6g(sch_1):page199_i126@pure_quanta.q_cap(chips)"
			("LOCATION" "C543")
		)
		("@t6g_mb_lib.t6g(sch_1):page199_i112@pure_quanta.q_cap(chips)"
			("LOCATION" "C544")
		)
		("@t6g_mb_lib.t6g(sch_1):page199_i148@pure_quanta.q_res(chips)"
			("LOCATION" "R738")
		)
		("@t6g_mb_lib.t6g(sch_1):page199_i147@pure_quanta.q_res(chips)"
			("LOCATION" "R739")
		)
		("@t6g_mb_lib.t6g(sch_1):page199_i119@pure_quanta.q_res(chips)"
			("LOCATION" "R741")
		)
		("@t6g_mb_lib.t6g(sch_1):page199_i121@pure_quanta.q_res(chips)"
			("LOCATION" "R742")
		)
		("@t6g_mb_lib.t6g(sch_1):page199_i116@pure_quanta.q_res(chips)"
			("LOCATION" "R743")
		)
		("@t6g_mb_lib.t6g(sch_1):page199_i118@pure_quanta.q_res(chips)"
			("LOCATION" "R744")
		)
		("@t6g_mb_lib.t6g(sch_1):page199_i124@pure_quanta.q_res(chips)"
			("LOCATION" "R745")
		)
		("@t6g_mb_lib.t6g(sch_1):page199_i149@pure_quanta.q_res(chips)"
			("LOCATION" "R2312")
		)
		("@t6g_mb_lib.t6g(sch_1):page199_i146@pure_quanta.q_res(chips)"
			("LOCATION" "R2313")
		)
		("@t6g_mb_lib.t6g(sch_1):page199_i106@pure_quanta.nc7sz66m5x(chips)"
			("LOCATION" "U16")
		)
		("@t6g_mb_lib.t6g(sch_1):page199_i132@pure_quanta.nc7sb3157(chips)"
			("LOCATION" "U21")
		)
		("@t6g_mb_lib.t6g(sch_1):page199_i144@pure_quanta.nc7sb3157(chips)"
			("LOCATION" "U22")
		)
		("@t6g_mb_lib.t6g(sch_1):page199_i128@pure_quanta.\\74lvc1g02gw\\(chips)"
			("LOCATION" "U181")
		)
		("@t6g_mb_lib.t6g(sch_1):page198_i103@pure_quanta.q_cap(chips)"
			("LOCATION" "C545")
		)
		("@t6g_mb_lib.t6g(sch_1):page198_i105@pure_quanta.q_cap(chips)"
			("LOCATION" "C546")
		)
		("@t6g_mb_lib.t6g(sch_1):page198_i119@pure_quanta.q_res(chips)"
			("LOCATION" "R2267")
		)
		("@t6g_mb_lib.t6g(sch_1):page198_i131@pure_quanta.q_res(chips)"
			("LOCATION" "R2274")
		)
		("@t6g_mb_lib.t6g(sch_1):page198_i133@pure_quanta.q_res(chips)"
			("LOCATION" "R2276")
		)
		("@t6g_mb_lib.t6g(sch_1):page198_i132@pure_quanta.q_res(chips)"
			("LOCATION" "R2277")
		)
		("@t6g_mb_lib.t6g(sch_1):page198_i134@pure_quanta.q_res(chips)"
			("LOCATION" "R2278")
		)
		("@t6g_mb_lib.t6g(sch_1):page198_i135@pure_quanta.q_res(chips)"
			("LOCATION" "R2279")
		)
		("@t6g_mb_lib.t6g(sch_1):page198_i113@pure_quanta.q_res(chips)"
			("LOCATION" "R2280")
		)
		("@t6g_mb_lib.t6g(sch_1):page198_i94@pure_quanta.q_res(chips)"
			("LOCATION" "R2281")
		)
		("@t6g_mb_lib.t6g(sch_1):page198_i101@pure_quanta.q_res(chips)"
			("LOCATION" "R2285")
		)
		("@t6g_mb_lib.t6g(sch_1):page198_i109@pure_quanta.q_res(chips)"
			("LOCATION" "R2288")
		)
		("@t6g_mb_lib.t6g(sch_1):page198_i108@pure_quanta.q_res(chips)"
			("LOCATION" "R2293")
		)
		("@t6g_mb_lib.t6g(sch_1):page198_i99@pure_quanta.q_res(chips)"
			("LOCATION" "R2294")
		)
		("@t6g_mb_lib.t6g(sch_1):page198_i107@pure_quanta.q_res(chips)"
			("LOCATION" "R2308")
		)
		("@t6g_mb_lib.t6g(sch_1):page198_i98@pure_quanta.q_res(chips)"
			("LOCATION" "R2309")
		)
		("@t6g_mb_lib.t6g(sch_1):page198_i93@pure_quanta.q_res(chips)"
			("LOCATION" "R2310")
		)
		("@t6g_mb_lib.t6g(sch_1):page198_i88@pure_quanta.q_res(chips)"
			("LOCATION" "R2311")
		)
		("@t6g_mb_lib.t6g(sch_1):page198_i118@pure_quanta.\\74cbtlv3126pw\\(chips)"
			("LOCATION" "U17")
		)
		("@t6g_mb_lib.t6g(sch_1):page198_i121@pure_quanta.\\74cbtlv3126pw\\(chips)"
			("LOCATION" "U18")
		)
		("@t6g_mb_lib.t6g(sch_1):page197_i238@pure_quanta.q_cap(chips)"
			("LOCATION" "C549")
		)
		("@t6g_mb_lib.t6g(sch_1):page197_i217@pure_quanta.q_cap(chips)"
			("LOCATION" "C550")
		)
		("@t6g_mb_lib.t6g(sch_1):page197_i222@pure_quanta.q_cap(chips)"
			("LOCATION" "C551")
		)
		("@t6g_mb_lib.t6g(sch_1):page197_i206@pure_quanta.q_cap(chips)"
			("LOCATION" "C552")
		)
		("@t6g_mb_lib.t6g(sch_1):page197_i243@pure_quanta.q_cap(chips)"
			("LOCATION" "C1105")
		)
		("@t6g_mb_lib.t6g(sch_1):page197_i239@pure_quanta.q_cap(chips)"
			("LOCATION" "C1170")
		)
		("@t6g_mb_lib.t6g(sch_1):page197_i191@pure_quanta.sconn60_qsh03001ldaktr(chips)"
			("LOCATION" "J42")
		)
		("@t6g_mb_lib.t6g(sch_1):page197_i227@pure_quanta.q_res(chips)"
			("LOCATION" "R771")
		)
		("@t6g_mb_lib.t6g(sch_1):page197_i226@pure_quanta.q_res(chips)"
			("LOCATION" "R772")
		)
		("@t6g_mb_lib.t6g(sch_1):page197_i233@pure_quanta.q_res(chips)"
			("LOCATION" "R773")
		)
		("@t6g_mb_lib.t6g(sch_1):page197_i236@pure_quanta.q_res(chips)"
			("LOCATION" "R774")
		)
		("@t6g_mb_lib.t6g(sch_1):page197_i211@pure_quanta.q_res(chips)"
			("LOCATION" "R775")
		)
		("@t6g_mb_lib.t6g(sch_1):page197_i212@pure_quanta.q_res(chips)"
			("LOCATION" "R776")
		)
		("@t6g_mb_lib.t6g(sch_1):page197_i215@pure_quanta.q_res(chips)"
			("LOCATION" "R777")
		)
		("@t6g_mb_lib.t6g(sch_1):page197_i214@pure_quanta.q_res(chips)"
			("LOCATION" "R778")
		)
		("@t6g_mb_lib.t6g(sch_1):page197_i204@pure_quanta.q_res(chips)"
			("LOCATION" "R780")
		)
		("@t6g_mb_lib.t6g(sch_1):page197_i262@pure_quanta.q_res(chips)"
			("LOCATION" "R1605")
		)
		("@t6g_mb_lib.t6g(sch_1):page197_i263@pure_quanta.q_res(chips)"
			("LOCATION" "R1607")
		)
		("@t6g_mb_lib.t6g(sch_1):page197_i264@pure_quanta.q_res(chips)"
			("LOCATION" "R1608")
		)
		("@t6g_mb_lib.t6g(sch_1):page197_i276@pure_quanta.q_res(chips)"
			("LOCATION" "R1609")
		)
		("@t6g_mb_lib.t6g(sch_1):page197_i232@pure_quanta.q_res(chips)"
			("LOCATION" "R1610")
		)
		("@t6g_mb_lib.t6g(sch_1):page197_i230@pure_quanta.q_res(chips)"
			("LOCATION" "R1611")
		)
		("@t6g_mb_lib.t6g(sch_1):page197_i225@pure_quanta.q_res(chips)"
			("LOCATION" "R1612")
		)
		("@t6g_mb_lib.t6g(sch_1):page197_i228@pure_quanta.q_res(chips)"
			("LOCATION" "R1613")
		)
		("@t6g_mb_lib.t6g(sch_1):page197_i205@pure_quanta.q_res(chips)"
			("LOCATION" "R1614")
		)
		("@t6g_mb_lib.t6g(sch_1):page197_i201@pure_quanta.q_res(chips)"
			("LOCATION" "R1615")
		)
		("@t6g_mb_lib.t6g(sch_1):page197_i284@pure_quanta.q_res(chips)"
			("LOCATION" "R3825")
		)
		("@t6g_mb_lib.t6g(sch_1):page245_i8@pure_quanta.q_cap(chips)"
			("LOCATION" "C554")
		)
		("@t6g_mb_lib.t6g(sch_1):page245_i7@pure_quanta.q_cap(chips)"
			("LOCATION" "C563")
		)
		("@t6g_mb_lib.t6g(sch_1):page245_i3@pure_quanta.conn10_g2100ht0038071(chips)"
			("LOCATION" "J43")
		)
		("@t6g_mb_lib.t6g(sch_1):page245_i30@pure_quanta.q_res(chips)"
			("LOCATION" "R803")
		)
		("@t6g_mb_lib.t6g(sch_1):page245_i31@pure_quanta.q_res(chips)"
			("LOCATION" "R804")
		)
		("@t6g_mb_lib.t6g(sch_1):page245_i32@pure_quanta.q_res(chips)"
			("LOCATION" "R805")
		)
		("@t6g_mb_lib.t6g(sch_1):page245_i33@pure_quanta.q_res(chips)"
			("LOCATION" "R806")
		)
		("@t6g_mb_lib.t6g(sch_1):page245_i21@pure_quanta.q_res(chips)"
			("LOCATION" "R919")
		)
		("@t6g_mb_lib.t6g(sch_1):page245_i22@pure_quanta.q_res(chips)"
			("LOCATION" "R920")
		)
		("@t6g_mb_lib.t6g(sch_1):page245_i27@pure_quanta.q_res(chips)"
			("LOCATION" "R927")
		)
		("@t6g_mb_lib.t6g(sch_1):page245_i26@pure_quanta.q_res(chips)"
			("LOCATION" "R928")
		)
		("@t6g_mb_lib.t6g(sch_1):page245_i25@pure_quanta.q_res(chips)"
			("LOCATION" "R929")
		)
		("@t6g_mb_lib.t6g(sch_1):page245_i28@pure_quanta.q_res(chips)"
			("LOCATION" "R930")
		)
		("@t6g_mb_lib.t6g(sch_1):page245_i4@pure_quanta.q_res(chips)"
			("LOCATION" "R931")
		)
		("@t6g_mb_lib.t6g(sch_1):page245_i5@pure_quanta.q_res(chips)"
			("LOCATION" "R1743")
		)
		("@t6g_mb_lib.t6g(sch_1):page85_i48@pure_quanta.q_cap(chips)"
			("LOCATION" "C555")
		)
		("@t6g_mb_lib.t6g(sch_1):page85_i78@pure_quanta.q_cap(chips)"
			("LOCATION" "C556")
		)
		("@t6g_mb_lib.t6g(sch_1):page85_i54@pure_quanta.q_cap(chips)"
			("LOCATION" "C557")
		)
		("@t6g_mb_lib.t6g(sch_1):page85_i62@pure_quanta.q_cap(chips)"
			("LOCATION" "C558")
		)
		("@t6g_mb_lib.t6g(sch_1):page85_i88@pure_quanta.q_res(chips)"
			("LOCATION" "R847")
		)
		("@t6g_mb_lib.t6g(sch_1):page85_i87@pure_quanta.q_res(chips)"
			("LOCATION" "R848")
		)
		("@t6g_mb_lib.t6g(sch_1):page85_i90@pure_quanta.q_res(chips)"
			("LOCATION" "R849")
		)
		("@t6g_mb_lib.t6g(sch_1):page85_i89@pure_quanta.q_res(chips)"
			("LOCATION" "R850")
		)
		("@t6g_mb_lib.t6g(sch_1):page85_i91@pure_quanta.q_res(chips)"
			("LOCATION" "R851")
		)
		("@t6g_mb_lib.t6g(sch_1):page85_i92@pure_quanta.q_res(chips)"
			("LOCATION" "R852")
		)
		("@t6g_mb_lib.t6g(sch_1):page85_i94@pure_quanta.q_res(chips)"
			("LOCATION" "R853")
		)
		("@t6g_mb_lib.t6g(sch_1):page85_i93@pure_quanta.q_res(chips)"
			("LOCATION" "R854")
		)
		("@t6g_mb_lib.t6g(sch_1):page85_i96@pure_quanta.q_res(chips)"
			("LOCATION" "R855")
		)
		("@t6g_mb_lib.t6g(sch_1):page85_i98@pure_quanta.q_res(chips)"
			("LOCATION" "R856")
		)
		("@t6g_mb_lib.t6g(sch_1):page85_i97@pure_quanta.q_res(chips)"
			("LOCATION" "R857")
		)
		("@t6g_mb_lib.t6g(sch_1):page85_i99@pure_quanta.q_res(chips)"
			("LOCATION" "R858")
		)
		("@t6g_mb_lib.t6g(sch_1):page85_i113@pure_quanta.q_res(chips)"
			("LOCATION" "R859")
		)
		("@t6g_mb_lib.t6g(sch_1):page85_i118@pure_quanta.q_res(chips)"
			("LOCATION" "R860")
		)
		("@t6g_mb_lib.t6g(sch_1):page85_i119@pure_quanta.q_res(chips)"
			("LOCATION" "R861")
		)
		("@t6g_mb_lib.t6g(sch_1):page85_i120@pure_quanta.q_res(chips)"
			("LOCATION" "R862")
		)
		("@t6g_mb_lib.t6g(sch_1):page85_i47@pure_quanta.q_res(chips)"
			("LOCATION" "R863")
		)
		("@t6g_mb_lib.t6g(sch_1):page85_i64@pure_quanta.q_res(chips)"
			("LOCATION" "R864")
		)
		("@t6g_mb_lib.t6g(sch_1):page85_i74@pure_quanta.q_res(chips)"
			("LOCATION" "R865")
		)
		("@t6g_mb_lib.t6g(sch_1):page85_i75@pure_quanta.q_res(chips)"
			("LOCATION" "R866")
		)
		("@t6g_mb_lib.t6g(sch_1):page85_i67@pure_quanta.q_res(chips)"
			("LOCATION" "R867")
		)
		("@t6g_mb_lib.t6g(sch_1):page85_i68@pure_quanta.q_res(chips)"
			("LOCATION" "R868")
		)
		("@t6g_mb_lib.t6g(sch_1):page85_i69@pure_quanta.q_res(chips)"
			("LOCATION" "R870")
		)
		("@t6g_mb_lib.t6g(sch_1):page85_i80@pure_quanta.q_res(chips)"
			("LOCATION" "R871")
		)
		("@t6g_mb_lib.t6g(sch_1):page85_i81@pure_quanta.q_res(chips)"
			("LOCATION" "R872")
		)
		("@t6g_mb_lib.t6g(sch_1):page85_i82@pure_quanta.q_res(chips)"
			("LOCATION" "R873")
		)
		("@t6g_mb_lib.t6g(sch_1):page85_i83@pure_quanta.q_res(chips)"
			("LOCATION" "R874")
		)
		("@t6g_mb_lib.t6g(sch_1):page85_i66@pure_quanta.q_res(chips)"
			("LOCATION" "R875")
		)
		("@t6g_mb_lib.t6g(sch_1):page85_i79@pure_quanta.q_res(chips)"
			("LOCATION" "R876")
		)
		("@t6g_mb_lib.t6g(sch_1):page85_i104@pure_quanta.q_res(chips)"
			("LOCATION" "R932")
		)
		("@t6g_mb_lib.t6g(sch_1):page85_i114@pure_quanta.q_res(chips)"
			("LOCATION" "R933")
		)
		("@t6g_mb_lib.t6g(sch_1):page85_i103@pure_quanta.q_res(chips)"
			("LOCATION" "R934")
		)
		("@t6g_mb_lib.t6g(sch_1):page85_i117@pure_quanta.q_res(chips)"
			("LOCATION" "R935")
		)
		("@t6g_mb_lib.t6g(sch_1):page85_i102@pure_quanta.q_res(chips)"
			("LOCATION" "R936")
		)
		("@t6g_mb_lib.t6g(sch_1):page85_i116@pure_quanta.q_res(chips)"
			("LOCATION" "R937")
		)
		("@t6g_mb_lib.t6g(sch_1):page85_i100@pure_quanta.q_res(chips)"
			("LOCATION" "R938")
		)
		("@t6g_mb_lib.t6g(sch_1):page85_i115@pure_quanta.q_res(chips)"
			("LOCATION" "R939")
		)
		("@t6g_mb_lib.t6g(sch_1):page85_i70@pure_quanta.q_res(chips)"
			("LOCATION" "R2036")
		)
		("@t6g_mb_lib.t6g(sch_1):page85_i72@pure_quanta.gtl2014pw(chips)"
			("LOCATION" "U25")
		)
		("@t6g_mb_lib.t6g(sch_1):page85_i85@pure_quanta.gtl2014pw(chips)"
			("LOCATION" "U26")
		)
		("@t6g_mb_lib.t6g(sch_1):page225_i13@pure_quanta.q_cap(chips)"
			("LOCATION" "C559")
		)
		("@t6g_mb_lib.t6g(sch_1):page225_i29@pure_quanta.q_cap(chips)"
			("LOCATION" "C560")
		)
		("@t6g_mb_lib.t6g(sch_1):page225_i11@pure_quanta.q_cap(chips)"
			("LOCATION" "C561")
		)
		("@t6g_mb_lib.t6g(sch_1):page225_i24@pure_quanta.q_cap(chips)"
			("LOCATION" "C562")
		)
		("@t6g_mb_lib.t6g(sch_1):page225_i19@pure_quanta.q_res(chips)"
			("LOCATION" "R909")
		)
		("@t6g_mb_lib.t6g(sch_1):page225_i17@pure_quanta.q_res(chips)"
			("LOCATION" "R910")
		)
		("@t6g_mb_lib.t6g(sch_1):page225_i15@pure_quanta.q_res(chips)"
			("LOCATION" "R911")
		)
		("@t6g_mb_lib.t6g(sch_1):page225_i18@pure_quanta.q_res(chips)"
			("LOCATION" "R960")
		)
		("@t6g_mb_lib.t6g(sch_1):page225_i35@pure_quanta.q_res(chips)"
			("LOCATION" "R961")
		)
		("@t6g_mb_lib.t6g(sch_1):page225_i36@pure_quanta.q_res(chips)"
			("LOCATION" "R962")
		)
		("@t6g_mb_lib.t6g(sch_1):page225_i34@pure_quanta.q_res(chips)"
			("LOCATION" "R963")
		)
		("@t6g_mb_lib.t6g(sch_1):page225_i32@pure_quanta.q_res(chips)"
			("LOCATION" "R964")
		)
		("@t6g_mb_lib.t6g(sch_1):page225_i8@pure_quanta.q_res(chips)"
			("LOCATION" "R965")
		)
		("@t6g_mb_lib.t6g(sch_1):page225_i22@pure_quanta.q_res(chips)"
			("LOCATION" "R966")
		)
		("@t6g_mb_lib.t6g(sch_1):page225_i7@pure_quanta.q_res(chips)"
			("LOCATION" "R967")
		)
		("@t6g_mb_lib.t6g(sch_1):page225_i21@pure_quanta.q_res(chips)"
			("LOCATION" "R968")
		)
		("@t6g_mb_lib.t6g(sch_1):page225_i43@pure_quanta.q_res(chips)"
			("LOCATION" "R3762")
		)
		("@t6g_mb_lib.t6g(sch_1):page225_i41@pure_quanta.q_res(chips)"
			("LOCATION" "R3763")
		)
		("@t6g_mb_lib.t6g(sch_1):page225_i46@pure_quanta.q_res(chips)"
			("LOCATION" "R3826")
		)
		("@t6g_mb_lib.t6g(sch_1):page225_i45@pure_quanta.q_res(chips)"
			("LOCATION" "R3827")
		)
		("@t6g_mb_lib.t6g(sch_1):page225_i26@pure_quanta.pca9617adp(chips)"
			("LOCATION" "U28")
		)
		("@t6g_mb_lib.t6g(sch_1):page225_i1@pure_quanta.pca9617adp(chips)"
			("LOCATION" "U29")
		)
		("@t6g_mb_lib.t6g(sch_1):page267_i130@pure_quanta.q_cap(chips)"
			("LOCATION" "C566")
		)
		("@t6g_mb_lib.t6g(sch_1):page267_i177@pure_quanta.q_cap(chips)"
			("LOCATION" "C901")
		)
		("@t6g_mb_lib.t6g(sch_1):page267_i178@pure_quanta.q_cap(chips)"
			("LOCATION" "C902")
		)
		("@t6g_mb_lib.t6g(sch_1):page267_i61@pure_quanta.q_cap(chips)"
			("LOCATION" "C2695")
		)
		("@t6g_mb_lib.t6g(sch_1):page267_i65@pure_quanta.q_cap(chips)"
			("LOCATION" "C2696")
		)
		("@t6g_mb_lib.t6g(sch_1):page267_i45@pure_quanta.q_cap(chips)"
			("LOCATION" "C2697")
		)
		("@t6g_mb_lib.t6g(sch_1):page267_i46@pure_quanta.q_cap(chips)"
			("LOCATION" "C2698")
		)
		("@t6g_mb_lib.t6g(sch_1):page267_i44@pure_quanta.q_cap(chips)"
			("LOCATION" "C2700")
		)
		("@t6g_mb_lib.t6g(sch_1):page267_i40@pure_quanta.q_cap(chips)"
			("LOCATION" "C2701")
		)
		("@t6g_mb_lib.t6g(sch_1):page267_i174@pure_quanta.q_cap(chips)"
			("LOCATION" "C2703")
		)
		("@t6g_mb_lib.t6g(sch_1):page267_i173@pure_quanta.q_cap(chips)"
			("LOCATION" "C2704")
		)
		("@t6g_mb_lib.t6g(sch_1):page267_i82@pure_quanta.q_cap(chips)"
			("LOCATION" "C2705")
		)
		("@t6g_mb_lib.t6g(sch_1):page267_i80@pure_quanta.q_cap(chips)"
			("LOCATION" "C2706")
		)
		("@t6g_mb_lib.t6g(sch_1):page267_i47@pure_quanta.q_cap(chips)"
			("LOCATION" "C2816")
		)
		("@t6g_mb_lib.t6g(sch_1):page267_i133@pure_quanta.q_res(chips)"
			("LOCATION" "R428")
		)
		("@t6g_mb_lib.t6g(sch_1):page267_i136@pure_quanta.q_res(chips)"
			("LOCATION" "R536")
		)
		("@t6g_mb_lib.t6g(sch_1):page267_i135@pure_quanta.q_res(chips)"
			("LOCATION" "R537")
		)
		("@t6g_mb_lib.t6g(sch_1):page267_i123@pure_quanta.q_res(chips)"
			("LOCATION" "R538")
		)
		("@t6g_mb_lib.t6g(sch_1):page267_i126@pure_quanta.q_res(chips)"
			("LOCATION" "R539")
		)
		("@t6g_mb_lib.t6g(sch_1):page267_i121@pure_quanta.q_res(chips)"
			("LOCATION" "R540")
		)
		("@t6g_mb_lib.t6g(sch_1):page267_i125@pure_quanta.q_res(chips)"
			("LOCATION" "R602")
		)
		("@t6g_mb_lib.t6g(sch_1):page267_i120@pure_quanta.q_res(chips)"
			("LOCATION" "R603")
		)
		("@t6g_mb_lib.t6g(sch_1):page267_i124@pure_quanta.q_res(chips)"
			("LOCATION" "R606")
		)
		("@t6g_mb_lib.t6g(sch_1):page267_i152@pure_quanta.q_res(chips)"
			("LOCATION" "R1032")
		)
		("@t6g_mb_lib.t6g(sch_1):page267_i153@pure_quanta.q_res(chips)"
			("LOCATION" "R1033")
		)
		("@t6g_mb_lib.t6g(sch_1):page267_i56@pure_quanta.q_res(chips)"
			("LOCATION" "R1142")
		)
		("@t6g_mb_lib.t6g(sch_1):page267_i55@pure_quanta.q_res(chips)"
			("LOCATION" "R1143")
		)
		("@t6g_mb_lib.t6g(sch_1):page267_i18@pure_quanta.q_res(chips)"
			("LOCATION" "R1144")
		)
		("@t6g_mb_lib.t6g(sch_1):page267_i20@pure_quanta.q_res(chips)"
			("LOCATION" "R1145")
		)
		("@t6g_mb_lib.t6g(sch_1):page267_i59@pure_quanta.q_res(chips)"
			("LOCATION" "R2148")
		)
		("@t6g_mb_lib.t6g(sch_1):page267_i58@pure_quanta.q_res(chips)"
			("LOCATION" "R2149")
		)
		("@t6g_mb_lib.t6g(sch_1):page267_i63@pure_quanta.q_res(chips)"
			("LOCATION" "R2150")
		)
		("@t6g_mb_lib.t6g(sch_1):page267_i48@pure_quanta.q_res(chips)"
			("LOCATION" "R2151")
		)
		("@t6g_mb_lib.t6g(sch_1):page267_i49@pure_quanta.q_res(chips)"
			("LOCATION" "R2152")
		)
		("@t6g_mb_lib.t6g(sch_1):page267_i43@pure_quanta.q_res(chips)"
			("LOCATION" "R2154")
		)
		("@t6g_mb_lib.t6g(sch_1):page267_i10@pure_quanta.q_res(chips)"
			("LOCATION" "R2156")
		)
		("@t6g_mb_lib.t6g(sch_1):page267_i25@pure_quanta.q_res(chips)"
			("LOCATION" "R2158")
		)
		("@t6g_mb_lib.t6g(sch_1):page267_i29@pure_quanta.q_res(chips)"
			("LOCATION" "R2159")
		)
		("@t6g_mb_lib.t6g(sch_1):page267_i23@pure_quanta.q_res(chips)"
			("LOCATION" "R2161")
		)
		("@t6g_mb_lib.t6g(sch_1):page267_i26@pure_quanta.q_res(chips)"
			("LOCATION" "R2162")
		)
		("@t6g_mb_lib.t6g(sch_1):page267_i149@pure_quanta.m24128bwmn6tp(chips)"
			("LOCATION" "U190")
		)
		("@t6g_mb_lib.t6g(sch_1):page267_i37@pure_quanta.cyusb330468ltxi(chips)"
			("LOCATION" "U204")
		)
		("@t6g_mb_lib.t6g(sch_1):page267_i60@pure_quanta.x_4s_exs00acs00468(chips)"
			("LOCATION" "Y12")
		)
		("@t6g_mb_lib.t6g(sch_1):page278_i176@pure_quanta.q_cap(chips)"
			("LOCATION" "C567")
		)
		("@t6g_mb_lib.t6g(sch_1):page278_i241@pure_quanta.q_cap(chips)"
			("LOCATION" "C2893")
		)
		("@t6g_mb_lib.t6g(sch_1):page278_i282@pure_quanta.conn3_210hp1030br1(chips)"
			("LOCATION" "JP33")
		)
		("@t6g_mb_lib.t6g(sch_1):page278_i185@pure_quanta.q_res(chips)"
			("LOCATION" "R838")
		)
		("@t6g_mb_lib.t6g(sch_1):page278_i216@pure_quanta.q_res(chips)"
			("LOCATION" "R839")
		)
		("@t6g_mb_lib.t6g(sch_1):page278_i184@pure_quanta.q_res(chips)"
			("LOCATION" "R840")
		)
		("@t6g_mb_lib.t6g(sch_1):page278_i214@pure_quanta.q_res(chips)"
			("LOCATION" "R841")
		)
		("@t6g_mb_lib.t6g(sch_1):page278_i182@pure_quanta.q_res(chips)"
			("LOCATION" "R842")
		)
		("@t6g_mb_lib.t6g(sch_1):page278_i213@pure_quanta.q_res(chips)"
			("LOCATION" "R843")
		)
		("@t6g_mb_lib.t6g(sch_1):page278_i193@pure_quanta.q_res(chips)"
			("LOCATION" "R844")
		)
		("@t6g_mb_lib.t6g(sch_1):page278_i192@pure_quanta.q_res(chips)"
			("LOCATION" "R845")
		)
		("@t6g_mb_lib.t6g(sch_1):page278_i203@pure_quanta.q_res(chips)"
			("LOCATION" "R846")
		)
		("@t6g_mb_lib.t6g(sch_1):page278_i204@pure_quanta.q_res(chips)"
			("LOCATION" "R877")
		)
		("@t6g_mb_lib.t6g(sch_1):page278_i205@pure_quanta.q_res(chips)"
			("LOCATION" "R949")
		)
		("@t6g_mb_lib.t6g(sch_1):page278_i206@pure_quanta.q_res(chips)"
			("LOCATION" "R950")
		)
		("@t6g_mb_lib.t6g(sch_1):page278_i207@pure_quanta.q_res(chips)"
			("LOCATION" "R951")
		)
		("@t6g_mb_lib.t6g(sch_1):page278_i175@pure_quanta.q_res(chips)"
			("LOCATION" "R952")
		)
		("@t6g_mb_lib.t6g(sch_1):page278_i195@pure_quanta.q_res(chips)"
			("LOCATION" "R954")
		)
		("@t6g_mb_lib.t6g(sch_1):page278_i194@pure_quanta.q_res(chips)"
			("LOCATION" "R955")
		)
		("@t6g_mb_lib.t6g(sch_1):page278_i196@pure_quanta.q_res(chips)"
			("LOCATION" "R956")
		)
		("@t6g_mb_lib.t6g(sch_1):page278_i223@pure_quanta.q_res(chips)"
			("LOCATION" "R3640")
		)
		("@t6g_mb_lib.t6g(sch_1):page278_i224@pure_quanta.q_res(chips)"
			("LOCATION" "R3641")
		)
		("@t6g_mb_lib.t6g(sch_1):page278_i226@pure_quanta.q_res(chips)"
			("LOCATION" "R3642")
		)
		("@t6g_mb_lib.t6g(sch_1):page278_i225@pure_quanta.q_res(chips)"
			("LOCATION" "R3643")
		)
		("@t6g_mb_lib.t6g(sch_1):page278_i228@pure_quanta.q_res(chips)"
			("LOCATION" "R3644")
		)
		("@t6g_mb_lib.t6g(sch_1):page278_i227@pure_quanta.q_res(chips)"
			("LOCATION" "R3645")
		)
		("@t6g_mb_lib.t6g(sch_1):page278_i229@pure_quanta.q_res(chips)"
			("LOCATION" "R3646")
		)
		("@t6g_mb_lib.t6g(sch_1):page278_i230@pure_quanta.q_res(chips)"
			("LOCATION" "R3647")
		)
		("@t6g_mb_lib.t6g(sch_1):page278_i243@pure_quanta.q_res(chips)"
			("LOCATION" "R3649")
		)
		("@t6g_mb_lib.t6g(sch_1):page278_i250@pure_quanta.q_res(chips)"
			("LOCATION" "R3668")
		)
		("@t6g_mb_lib.t6g(sch_1):page278_i249@pure_quanta.q_res(chips)"
			("LOCATION" "R3669")
		)
		("@t6g_mb_lib.t6g(sch_1):page278_i258@pure_quanta.q_res(chips)"
			("LOCATION" "R3679")
		)
		("@t6g_mb_lib.t6g(sch_1):page278_i261@pure_quanta.q_res(chips)"
			("LOCATION" "R3680")
		)
		("@t6g_mb_lib.t6g(sch_1):page278_i257@pure_quanta.q_res(chips)"
			("LOCATION" "R3681")
		)
		("@t6g_mb_lib.t6g(sch_1):page278_i259@pure_quanta.q_res(chips)"
			("LOCATION" "R3682")
		)
		("@t6g_mb_lib.t6g(sch_1):page278_i255@pure_quanta.q_res(chips)"
			("LOCATION" "R3683")
		)
		("@t6g_mb_lib.t6g(sch_1):page278_i256@pure_quanta.q_res(chips)"
			("LOCATION" "R3684")
		)
		("@t6g_mb_lib.t6g(sch_1):page278_i276@pure_quanta.q_res(chips)"
			("LOCATION" "R3685")
		)
		("@t6g_mb_lib.t6g(sch_1):page278_i277@pure_quanta.q_res(chips)"
			("LOCATION" "R3686")
		)
		("@t6g_mb_lib.t6g(sch_1):page278_i278@pure_quanta.q_res(chips)"
			("LOCATION" "R3687")
		)
		("@t6g_mb_lib.t6g(sch_1):page278_i279@pure_quanta.q_res(chips)"
			("LOCATION" "R3688")
		)
		("@t6g_mb_lib.t6g(sch_1):page278_i275@pure_quanta.q_res(chips)"
			("LOCATION" "R3689")
		)
		("@t6g_mb_lib.t6g(sch_1):page278_i274@pure_quanta.q_res(chips)"
			("LOCATION" "R3690")
		)
		("@t6g_mb_lib.t6g(sch_1):page278_i273@pure_quanta.q_res(chips)"
			("LOCATION" "R3691")
		)
		("@t6g_mb_lib.t6g(sch_1):page278_i272@pure_quanta.q_res(chips)"
			("LOCATION" "R3692")
		)
		("@t6g_mb_lib.t6g(sch_1):page278_i199@pure_quanta.pca9546apwr(chips)"
			("LOCATION" "U20")
		)
		("@t6g_mb_lib.t6g(sch_1):page278_i238@pure_quanta.pca9546apwr(chips)"
			("LOCATION" "U195")
		)
		("@t6g_mb_lib.t6g(sch_1):page145_i110@pure_quanta.q_cap(chips)"
			("LOCATION" "C574")
		)
		("@t6g_mb_lib.t6g(sch_1):page145_i91@pure_quanta.q_cap(chips)"
			("LOCATION" "C575")
		)
		("@t6g_mb_lib.t6g(sch_1):page145_i36@pure_quanta.q_cap(chips)"
			("LOCATION" "C1298")
		)
		("@t6g_mb_lib.t6g(sch_1):page145_i29@pure_quanta.q_cap(chips)"
			("LOCATION" "C2439")
		)
		("@t6g_mb_lib.t6g(sch_1):page145_i94@pure_quanta.q_res(chips)"
			("LOCATION" "R1920")
		)
		("@t6g_mb_lib.t6g(sch_1):page145_i73@pure_quanta.q_res(chips)"
			("LOCATION" "R1943")
		)
		("@t6g_mb_lib.t6g(sch_1):page145_i41@pure_quanta.q_res(chips)"
			("LOCATION" "R1944")
		)
		("@t6g_mb_lib.t6g(sch_1):page145_i40@pure_quanta.q_res(chips)"
			("LOCATION" "R1945")
		)
		("@t6g_mb_lib.t6g(sch_1):page145_i63@pure_quanta.q_res(chips)"
			("LOCATION" "R1946")
		)
		("@t6g_mb_lib.t6g(sch_1):page145_i64@pure_quanta.q_res(chips)"
			("LOCATION" "R1947")
		)
		("@t6g_mb_lib.t6g(sch_1):page145_i65@pure_quanta.q_res(chips)"
			("LOCATION" "R1955")
		)
		("@t6g_mb_lib.t6g(sch_1):page145_i27@pure_quanta.q_res(chips)"
			("LOCATION" "R1983")
		)
		("@t6g_mb_lib.t6g(sch_1):page145_i78@pure_quanta.q_res(chips)"
			("LOCATION" "R2416")
		)
		("@t6g_mb_lib.t6g(sch_1):page145_i76@pure_quanta.q_res(chips)"
			("LOCATION" "R2418")
		)
		("@t6g_mb_lib.t6g(sch_1):page145_i79@pure_quanta.q_res(chips)"
			("LOCATION" "R2419")
		)
		("@t6g_mb_lib.t6g(sch_1):page145_i77@pure_quanta.q_res(chips)"
			("LOCATION" "R2433")
		)
		("@t6g_mb_lib.t6g(sch_1):page145_i89@pure_quanta.q_res(chips)"
			("LOCATION" "R2434")
		)
		("@t6g_mb_lib.t6g(sch_1):page145_i82@pure_quanta.q_res(chips)"
			("LOCATION" "R2436")
		)
		("@t6g_mb_lib.t6g(sch_1):page145_i95@pure_quanta.q_res(chips)"
			("LOCATION" "R2438")
		)
		("@t6g_mb_lib.t6g(sch_1):page145_i96@pure_quanta.q_res(chips)"
			("LOCATION" "R2439")
		)
		("@t6g_mb_lib.t6g(sch_1):page145_i112@pure_quanta.q_res(chips)"
			("LOCATION" "R2746")
		)
		("@t6g_mb_lib.t6g(sch_1):page145_i115@pure_quanta.mosfet_n(chips)"
			("LOCATION" "U44")
		)
		("@t6g_mb_lib.t6g(sch_1):page145_i106@pure_quanta.sn74lvc1g08dbvr(chips)"
			("LOCATION" "U45")
		)
		("@t6g_mb_lib.t6g(sch_1):page145_i97@pure_quanta.pca9555pw(chips)"
			("LOCATION" "U46")
		)
		("@t6g_mb_lib.t6g(sch_1):page145_i68@pure_quanta.\\74cbtlv3126pw\\(chips)"
			("LOCATION" "U175")
		)
		("@t6g_mb_lib.t6g(sch_1):page145_i35@pure_quanta.\\74lvc1g126gw\\(chips)"
			("LOCATION" "U178")
		)
		("@t6g_mb_lib.t6g(sch_1):page142_i91@pure_quanta.q_cap(chips)"
			("LOCATION" "C578")
		)
		("@t6g_mb_lib.t6g(sch_1):page142_i77@pure_quanta.q_cap(chips)"
			("LOCATION" "C579")
		)
		("@t6g_mb_lib.t6g(sch_1):page142_i2@pure_quanta.q_cap(chips)"
			("LOCATION" "C2408")
		)
		("@t6g_mb_lib.t6g(sch_1):page142_i26@pure_quanta.q_cap(chips)"
			("LOCATION" "C2411")
		)
		("@t6g_mb_lib.t6g(sch_1):page142_i21@pure_quanta.q_cap(chips)"
			("LOCATION" "C2412")
		)
		("@t6g_mb_lib.t6g(sch_1):page142_i12@pure_quanta.osc4_sit1602ai2233e50000000d(chips)"
			("LOCATION" "OSC3")
		)
		("@t6g_mb_lib.t6g(sch_1):page142_i6@pure_quanta.q_res(chips)"
			("LOCATION" "R1732")
		)
		("@t6g_mb_lib.t6g(sch_1):page142_i1@pure_quanta.q_res(chips)"
			("LOCATION" "R1733")
		)
		("@t6g_mb_lib.t6g(sch_1):page142_i15@pure_quanta.q_res(chips)"
			("LOCATION" "R1734")
		)
		("@t6g_mb_lib.t6g(sch_1):page142_i37@pure_quanta.q_res(chips)"
			("LOCATION" "R1752")
		)
		("@t6g_mb_lib.t6g(sch_1):page142_i5@pure_quanta.q_res(chips)"
			("LOCATION" "R1824")
		)
		("@t6g_mb_lib.t6g(sch_1):page142_i62@pure_quanta.q_res(chips)"
			("LOCATION" "R2011")
		)
		("@t6g_mb_lib.t6g(sch_1):page142_i61@pure_quanta.q_res(chips)"
			("LOCATION" "R2012")
		)
		("@t6g_mb_lib.t6g(sch_1):page142_i68@pure_quanta.q_res(chips)"
			("LOCATION" "R2013")
		)
		("@t6g_mb_lib.t6g(sch_1):page142_i64@pure_quanta.q_res(chips)"
			("LOCATION" "R2014")
		)
		("@t6g_mb_lib.t6g(sch_1):page142_i69@pure_quanta.q_res(chips)"
			("LOCATION" "R2015")
		)
		("@t6g_mb_lib.t6g(sch_1):page142_i67@pure_quanta.q_res(chips)"
			("LOCATION" "R2016")
		)
		("@t6g_mb_lib.t6g(sch_1):page142_i74@pure_quanta.q_res(chips)"
			("LOCATION" "R2017")
		)
		("@t6g_mb_lib.t6g(sch_1):page142_i55@pure_quanta.q_res(chips)"
			("LOCATION" "R2023")
		)
		("@t6g_mb_lib.t6g(sch_1):page142_i56@pure_quanta.q_res(chips)"
			("LOCATION" "R2035")
		)
		("@t6g_mb_lib.t6g(sch_1):page142_i87@pure_quanta.q_res(chips)"
			("LOCATION" "R2603")
		)
		("@t6g_mb_lib.t6g(sch_1):page142_i86@pure_quanta.q_res(chips)"
			("LOCATION" "R2645")
		)
		("@t6g_mb_lib.t6g(sch_1):page142_i95@pure_quanta.q_res(chips)"
			("LOCATION" "R2745")
		)
		("@t6g_mb_lib.t6g(sch_1):page142_i97@pure_quanta.mosfet_n(chips)"
			("LOCATION" "U49")
		)
		("@t6g_mb_lib.t6g(sch_1):page142_i88@pure_quanta.sn74lvc1g08dbvr(chips)"
			("LOCATION" "U50")
		)
		("@t6g_mb_lib.t6g(sch_1):page142_i75@pure_quanta.pca9555pw(chips)"
			("LOCATION" "U51")
		)
		("@t6g_mb_lib.t6g(sch_1):page142_i51@pure_quanta.\\74lvc1g126gw\\(chips)"
			("LOCATION" "U168")
		)
		("@t6g_mb_lib.t6g(sch_1):page142_i17@pure_quanta.pi6cv304le(chips)"
			("LOCATION" "U169")
		)
		("@t6g_mb_lib.t6g(sch_1):page160_i165@pure_quanta.q_cap_diffbus(chips)"
			("LOCATION" "C606")
		)
		("@t6g_mb_lib.t6g(sch_1):page160_i168@pure_quanta.q_cap_diffbus(chips)"
			("LOCATION" "C607")
		)
		("@t6g_mb_lib.t6g(sch_1):page160_i170@pure_quanta.q_cap_diffbus(chips)"
			("LOCATION" "C608")
		)
		("@t6g_mb_lib.t6g(sch_1):page160_i172@pure_quanta.q_cap_diffbus(chips)"
			("LOCATION" "C612")
		)
		("@t6g_mb_lib.t6g(sch_1):page160_i173@pure_quanta.q_cap_diffbus(chips)"
			("LOCATION" "C613")
		)
		("@t6g_mb_lib.t6g(sch_1):page160_i176@pure_quanta.q_cap_diffbus(chips)"
			("LOCATION" "C614")
		)
		("@t6g_mb_lib.t6g(sch_1):page160_i178@pure_quanta.q_cap_diffbus(chips)"
			("LOCATION" "C615")
		)
		("@t6g_mb_lib.t6g(sch_1):page160_i180@pure_quanta.q_cap_diffbus(chips)"
			("LOCATION" "C616")
		)
		("@t6g_mb_lib.t6g(sch_1):page160_i166@pure_quanta.q_cap_diffbus(chips)"
			("LOCATION" "C617")
		)
		("@t6g_mb_lib.t6g(sch_1):page160_i167@pure_quanta.q_cap_diffbus(chips)"
			("LOCATION" "C618")
		)
		("@t6g_mb_lib.t6g(sch_1):page160_i169@pure_quanta.q_cap_diffbus(chips)"
			("LOCATION" "C619")
		)
		("@t6g_mb_lib.t6g(sch_1):page160_i171@pure_quanta.q_cap_diffbus(chips)"
			("LOCATION" "C620")
		)
		("@t6g_mb_lib.t6g(sch_1):page160_i174@pure_quanta.q_cap_diffbus(chips)"
			("LOCATION" "C621")
		)
		("@t6g_mb_lib.t6g(sch_1):page160_i175@pure_quanta.q_cap_diffbus(chips)"
			("LOCATION" "C622")
		)
		("@t6g_mb_lib.t6g(sch_1):page160_i177@pure_quanta.q_cap_diffbus(chips)"
			("LOCATION" "C623")
		)
		("@t6g_mb_lib.t6g(sch_1):page160_i179@pure_quanta.q_cap_diffbus(chips)"
			("LOCATION" "C624")
		)
		("@t6g_mb_lib.t6g(sch_1):page160_i183@pure_quanta.q_cap_diffbus(chips)"
			("LOCATION" "C625")
		)
		("@t6g_mb_lib.t6g(sch_1):page160_i184@pure_quanta.q_cap_diffbus(chips)"
			("LOCATION" "C626")
		)
		("@t6g_mb_lib.t6g(sch_1):page160_i190@pure_quanta.q_cap_diffbus(chips)"
			("LOCATION" "C627")
		)
		("@t6g_mb_lib.t6g(sch_1):page160_i191@pure_quanta.q_cap_diffbus(chips)"
			("LOCATION" "C628")
		)
		("@t6g_mb_lib.t6g(sch_1):page160_i192@pure_quanta.q_cap_diffbus(chips)"
			("LOCATION" "C629")
		)
		("@t6g_mb_lib.t6g(sch_1):page160_i193@pure_quanta.q_cap_diffbus(chips)"
			("LOCATION" "C630")
		)
		("@t6g_mb_lib.t6g(sch_1):page160_i194@pure_quanta.q_cap_diffbus(chips)"
			("LOCATION" "C631")
		)
		("@t6g_mb_lib.t6g(sch_1):page160_i196@pure_quanta.q_cap_diffbus(chips)"
			("LOCATION" "C632")
		)
		("@t6g_mb_lib.t6g(sch_1):page160_i181@pure_quanta.q_cap_diffbus(chips)"
			("LOCATION" "C633")
		)
		("@t6g_mb_lib.t6g(sch_1):page160_i182@pure_quanta.q_cap_diffbus(chips)"
			("LOCATION" "C634")
		)
		("@t6g_mb_lib.t6g(sch_1):page160_i185@pure_quanta.q_cap_diffbus(chips)"
			("LOCATION" "C635")
		)
		("@t6g_mb_lib.t6g(sch_1):page160_i186@pure_quanta.q_cap_diffbus(chips)"
			("LOCATION" "C636")
		)
		("@t6g_mb_lib.t6g(sch_1):page160_i187@pure_quanta.q_cap_diffbus(chips)"
			("LOCATION" "C637")
		)
		("@t6g_mb_lib.t6g(sch_1):page160_i188@pure_quanta.q_cap_diffbus(chips)"
			("LOCATION" "C638")
		)
		("@t6g_mb_lib.t6g(sch_1):page160_i189@pure_quanta.q_cap_diffbus(chips)"
			("LOCATION" "C639")
		)
		("@t6g_mb_lib.t6g(sch_1):page160_i195@pure_quanta.q_cap_diffbus(chips)"
			("LOCATION" "C640")
		)
		("@t6g_mb_lib.t6g(sch_1):page178_i701@pure_quanta.q_cap(chips)"
			("LOCATION" "C643")
		)
		("@t6g_mb_lib.t6g(sch_1):page178_i702@pure_quanta.q_cap(chips)"
			("LOCATION" "C644")
		)
		("@t6g_mb_lib.t6g(sch_1):page178_i569@pure_quanta.q_res(chips)"
			("LOCATION" "R495")
		)
		("@t6g_mb_lib.t6g(sch_1):page178_i672@pure_quanta.emmitsburg_rev0p9(chips)"
			("LOCATION" "U8")
		)
		("@t6g_mb_lib.t6g(sch_1):page258_i91@pure_quanta.q_cap(chips)"
			("LOCATION" "C649")
		)
		("@t6g_mb_lib.t6g(sch_1):page258_i80@pure_quanta.q_cap(chips)"
			("LOCATION" "C2531")
		)
		("@t6g_mb_lib.t6g(sch_1):page258_i98@pure_quanta.q_cap(chips)"
			("LOCATION" "C2532")
		)
		("@t6g_mb_lib.t6g(sch_1):page258_i84@pure_quanta.q_cap(chips)"
			("LOCATION" "C2533")
		)
		("@t6g_mb_lib.t6g(sch_1):page258_i76@pure_quanta.sbr15u30sp513(chips)"
			("LOCATION" "D14")
		)
		("@t6g_mb_lib.t6g(sch_1):page258_i75@pure_quanta.sbr15u30sp513(chips)"
			("LOCATION" "D26")
		)
		("@t6g_mb_lib.t6g(sch_1):page258_i78@pure_quanta.sbr15u30sp513(chips)"
			("LOCATION" "D30")
		)
		("@t6g_mb_lib.t6g(sch_1):page258_i65@pure_quanta.mosfet_pch_1d3s(chips)"
			("LOCATION" "Q25")
		)
		("@t6g_mb_lib.t6g(sch_1):page258_i74@pure_quanta.mosfet_pch_1d3s(chips)"
			("LOCATION" "Q26")
		)
		("@t6g_mb_lib.t6g(sch_1):page258_i101@pure_quanta.mosfet_nch_dual(chips)"
			("LOCATION" "Q48")
		)
		("@t6g_mb_lib.t6g(sch_1):page258_i68@pure_quanta.mosfet_nch_dual(chips)"
			("LOCATION" "Q48")
		)
		("@t6g_mb_lib.t6g(sch_1):page258_i96@pure_quanta.mosfet_pch_1d3s(chips)"
			("LOCATION" "Q84")
		)
		("@t6g_mb_lib.t6g(sch_1):page258_i72@pure_quanta.q_res(chips)"
			("LOCATION" "R137")
		)
		("@t6g_mb_lib.t6g(sch_1):page258_i93@pure_quanta.q_res(chips)"
			("LOCATION" "R138")
		)
		("@t6g_mb_lib.t6g(sch_1):page258_i71@pure_quanta.q_res(chips)"
			("LOCATION" "R1020")
		)
		("@t6g_mb_lib.t6g(sch_1):page258_i81@pure_quanta.q_res(chips)"
			("LOCATION" "R1021")
		)
		("@t6g_mb_lib.t6g(sch_1):page258_i97@pure_quanta.q_res(chips)"
			("LOCATION" "R1022")
		)
		("@t6g_mb_lib.t6g(sch_1):page258_i70@pure_quanta.q_res(chips)"
			("LOCATION" "R1297")
		)
		("@t6g_mb_lib.t6g(sch_1):page258_i85@pure_quanta.q_res(chips)"
			("LOCATION" "R1301")
		)
		("@t6g_mb_lib.t6g(sch_1):page258_i86@pure_quanta.q_res(chips)"
			("LOCATION" "R2392")
		)
		("@t6g_mb_lib.t6g(sch_1):page258_i89@pure_quanta.q_res(chips)"
			("LOCATION" "R2672")
		)
		("@t6g_mb_lib.t6g(sch_1):page258_i88@pure_quanta.mosfet_nch_gds_esd_protected(chips)"
			("LOCATION" "U79")
		)
		("@t6g_mb_lib.t6g(sch_1):page283_i27@pure_quanta.q_cap(chips)"
			("LOCATION" "C650")
		)
		("@t6g_mb_lib.t6g(sch_1):page283_i30@pure_quanta.q_cap(chips)"
			("LOCATION" "C651")
		)
		("@t6g_mb_lib.t6g(sch_1):page283_i36@pure_quanta.q_cap(chips)"
			("LOCATION" "C652")
		)
		("@t6g_mb_lib.t6g(sch_1):page283_i46@pure_quanta.q_cap(chips)"
			("LOCATION" "C653")
		)
		("@t6g_mb_lib.t6g(sch_1):page283_i48@pure_quanta.q_cap(chips)"
			("LOCATION" "C655")
		)
		("@t6g_mb_lib.t6g(sch_1):page283_i22@pure_quanta.q_cap(chips)"
			("LOCATION" "C1886")
		)
		("@t6g_mb_lib.t6g(sch_1):page283_i4@pure_quanta.q_cap(chips)"
			("LOCATION" "C1887")
		)
		("@t6g_mb_lib.t6g(sch_1):page283_i28@pure_quanta.q_cap(chips)"
			("LOCATION" "C2538")
		)
		("@t6g_mb_lib.t6g(sch_1):page283_i61@pure_quanta.q_cap(chips)"
			("LOCATION" "C2539")
		)
		("@t6g_mb_lib.t6g(sch_1):page283_i37@pure_quanta.q_cap(chips)"
			("LOCATION" "C2540")
		)
		("@t6g_mb_lib.t6g(sch_1):page283_i55@pure_quanta.q_cap(chips)"
			("LOCATION" "C2541")
		)
		("@t6g_mb_lib.t6g(sch_1):page283_i56@pure_quanta.q_cap(chips)"
			("LOCATION" "C2542")
		)
		("@t6g_mb_lib.t6g(sch_1):page283_i44@pure_quanta.q_cap(chips)"
			("LOCATION" "C4027")
		)
		("@t6g_mb_lib.t6g(sch_1):page283_i15@pure_quanta.bat547f(chips)"
			("LOCATION" "D5")
		)
		("@t6g_mb_lib.t6g(sch_1):page283_i18@pure_quanta.mosfet_nch_dual(chips)"
			("LOCATION" "Q27")
		)
		("@t6g_mb_lib.t6g(sch_1):page283_i10@pure_quanta.mosfet_nch_dual(chips)"
			("LOCATION" "Q29")
		)
		("@t6g_mb_lib.t6g(sch_1):page283_i63@pure_quanta.mosfet_nch_1d3s(chips)"
			("LOCATION" "Q53")
		)
		("@t6g_mb_lib.t6g(sch_1):page283_i64@pure_quanta.mosfet_nch_1d3s(chips)"
			("LOCATION" "Q54")
		)
		("@t6g_mb_lib.t6g(sch_1):page283_i7@pure_quanta.q_res(chips)"
			("LOCATION" "R1026")
		)
		("@t6g_mb_lib.t6g(sch_1):page283_i11@pure_quanta.q_res(chips)"
			("LOCATION" "R1027")
		)
		("@t6g_mb_lib.t6g(sch_1):page283_i13@pure_quanta.q_res(chips)"
			("LOCATION" "R1028")
		)
		("@t6g_mb_lib.t6g(sch_1):page283_i32@pure_quanta.q_res(chips)"
			("LOCATION" "R1029")
		)
		("@t6g_mb_lib.t6g(sch_1):page283_i51@pure_quanta.q_res(chips)"
			("LOCATION" "R1030")
		)
		("@t6g_mb_lib.t6g(sch_1):page283_i8@pure_quanta.q_res(chips)"
			("LOCATION" "R1256")
		)
		("@t6g_mb_lib.t6g(sch_1):page283_i24@pure_quanta.q_res(chips)"
			("LOCATION" "R1260")
		)
		("@t6g_mb_lib.t6g(sch_1):page283_i45@pure_quanta.q_res(chips)"
			("LOCATION" "R2115")
		)
		("@t6g_mb_lib.t6g(sch_1):page283_i42@pure_quanta.q_res(chips)"
			("LOCATION" "R2116")
		)
		("@t6g_mb_lib.t6g(sch_1):page283_i6@pure_quanta.rt9818c44gv(chips)"
			("LOCATION" "U184")
		)
		("@t6g_mb_lib.t6g(sch_1):page283_i59@pure_quanta.slg55221120010vtr(chips)"
			("LOCATION" "U185")
		)
		("@t6g_mb_lib.t6g(sch_1):page269_i88@pure_quanta.q_cap(chips)"
			("LOCATION" "C700")
		)
		("@t6g_mb_lib.t6g(sch_1):page269_i90@pure_quanta.q_cap(chips)"
			("LOCATION" "C701")
		)
		("@t6g_mb_lib.t6g(sch_1):page269_i109@pure_quanta.q_cap(chips)"
			("LOCATION" "C702")
		)
		("@t6g_mb_lib.t6g(sch_1):page269_i100@pure_quanta.q_cap(chips)"
			("LOCATION" "C703")
		)
		("@t6g_mb_lib.t6g(sch_1):page269_i122@pure_quanta.q_cap(chips)"
			("LOCATION" "C711")
		)
		("@t6g_mb_lib.t6g(sch_1):page269_i123@pure_quanta.q_cap(chips)"
			("LOCATION" "C712")
		)
		("@t6g_mb_lib.t6g(sch_1):page269_i129@pure_quanta.q_cap(chips)"
			("LOCATION" "C713")
		)
		("@t6g_mb_lib.t6g(sch_1):page269_i128@pure_quanta.q_cap(chips)"
			("LOCATION" "C714")
		)
		("@t6g_mb_lib.t6g(sch_1):page269_i137@pure_quanta.q_cap(chips)"
			("LOCATION" "C2811")
		)
		("@t6g_mb_lib.t6g(sch_1):page269_i136@pure_quanta.q_cap(chips)"
			("LOCATION" "C2812")
		)
		("@t6g_mb_lib.t6g(sch_1):page269_i141@pure_quanta.q_cap(chips)"
			("LOCATION" "C2813")
		)
		("@t6g_mb_lib.t6g(sch_1):page269_i142@pure_quanta.q_cap(chips)"
			("LOCATION" "C2814")
		)
		("@t6g_mb_lib.t6g(sch_1):page269_i39@pure_quanta.q_res(chips)"
			("LOCATION" "R1041")
		)
		("@t6g_mb_lib.t6g(sch_1):page269_i36@pure_quanta.q_res(chips)"
			("LOCATION" "R1042")
		)
		("@t6g_mb_lib.t6g(sch_1):page269_i19@pure_quanta.q_res(chips)"
			("LOCATION" "R1043")
		)
		("@t6g_mb_lib.t6g(sch_1):page269_i16@pure_quanta.q_res(chips)"
			("LOCATION" "R1044")
		)
		("@t6g_mb_lib.t6g(sch_1):page269_i40@pure_quanta.q_res(chips)"
			("LOCATION" "R1045")
		)
		("@t6g_mb_lib.t6g(sch_1):page269_i37@pure_quanta.q_res(chips)"
			("LOCATION" "R1046")
		)
		("@t6g_mb_lib.t6g(sch_1):page269_i21@pure_quanta.q_res(chips)"
			("LOCATION" "R1047")
		)
		("@t6g_mb_lib.t6g(sch_1):page269_i17@pure_quanta.q_res(chips)"
			("LOCATION" "R1048")
		)
		("@t6g_mb_lib.t6g(sch_1):page269_i41@pure_quanta.q_res(chips)"
			("LOCATION" "R1049")
		)
		("@t6g_mb_lib.t6g(sch_1):page269_i38@pure_quanta.q_res(chips)"
			("LOCATION" "R1050")
		)
		("@t6g_mb_lib.t6g(sch_1):page269_i22@pure_quanta.q_res(chips)"
			("LOCATION" "R1051")
		)
		("@t6g_mb_lib.t6g(sch_1):page269_i18@pure_quanta.q_res(chips)"
			("LOCATION" "R1052")
		)
		("@t6g_mb_lib.t6g(sch_1):page269_i46@pure_quanta.q_res(chips)"
			("LOCATION" "R1053")
		)
		("@t6g_mb_lib.t6g(sch_1):page269_i43@pure_quanta.q_res(chips)"
			("LOCATION" "R1054")
		)
		("@t6g_mb_lib.t6g(sch_1):page269_i26@pure_quanta.q_res(chips)"
			("LOCATION" "R1055")
		)
		("@t6g_mb_lib.t6g(sch_1):page269_i23@pure_quanta.q_res(chips)"
			("LOCATION" "R1056")
		)
		("@t6g_mb_lib.t6g(sch_1):page269_i47@pure_quanta.q_res(chips)"
			("LOCATION" "R1057")
		)
		("@t6g_mb_lib.t6g(sch_1):page269_i44@pure_quanta.q_res(chips)"
			("LOCATION" "R1058")
		)
		("@t6g_mb_lib.t6g(sch_1):page269_i27@pure_quanta.q_res(chips)"
			("LOCATION" "R1059")
		)
		("@t6g_mb_lib.t6g(sch_1):page269_i24@pure_quanta.q_res(chips)"
			("LOCATION" "R1060")
		)
		("@t6g_mb_lib.t6g(sch_1):page269_i48@pure_quanta.q_res(chips)"
			("LOCATION" "R1061")
		)
		("@t6g_mb_lib.t6g(sch_1):page269_i45@pure_quanta.q_res(chips)"
			("LOCATION" "R1062")
		)
		("@t6g_mb_lib.t6g(sch_1):page269_i28@pure_quanta.q_res(chips)"
			("LOCATION" "R1063")
		)
		("@t6g_mb_lib.t6g(sch_1):page269_i25@pure_quanta.q_res(chips)"
			("LOCATION" "R1064")
		)
		("@t6g_mb_lib.t6g(sch_1):page269_i83@pure_quanta.q_res(chips)"
			("LOCATION" "R1065")
		)
		("@t6g_mb_lib.t6g(sch_1):page269_i71@pure_quanta.q_res(chips)"
			("LOCATION" "R1066")
		)
		("@t6g_mb_lib.t6g(sch_1):page269_i86@pure_quanta.sn65lvpe502arger(chips)"
			("LOCATION" "U36")
		)
		("@t6g_mb_lib.t6g(sch_1):page269_i73@pure_quanta.sn65lvpe502arger(chips)"
			("LOCATION" "U37")
		)
		("@t6g_mb_lib.t6g(sch_1):page252_i143@pure_quanta.q_cap(chips)"
			("LOCATION" "C709")
		)
		("@t6g_mb_lib.t6g(sch_1):page252_i144@pure_quanta.q_cap(chips)"
			("LOCATION" "C710")
		)
		("@t6g_mb_lib.t6g(sch_1):page252_i148@pure_quanta.q_cap(chips)"
			("LOCATION" "PC71")
		)
		("@t6g_mb_lib.t6g(sch_1):page252_i127@pure_quanta.q_capp(chips)"
			("LOCATION" "PC566")
		)
		("@t6g_mb_lib.t6g(sch_1):page252_i117@pure_quanta.q_cap(chips)"
			("LOCATION" "PC567")
		)
		("@t6g_mb_lib.t6g(sch_1):page252_i107@pure_quanta.q_cap(chips)"
			("LOCATION" "PC568")
		)
		("@t6g_mb_lib.t6g(sch_1):page252_i99@pure_quanta.q_cap(chips)"
			("LOCATION" "PC569")
		)
		("@t6g_mb_lib.t6g(sch_1):page252_i115@pure_quanta.q_cap(chips)"
			("LOCATION" "PC570")
		)
		("@t6g_mb_lib.t6g(sch_1):page252_i114@pure_quanta.q_cap(chips)"
			("LOCATION" "PC571")
		)
		("@t6g_mb_lib.t6g(sch_1):page252_i113@pure_quanta.q_cap(chips)"
			("LOCATION" "PC576")
		)
		("@t6g_mb_lib.t6g(sch_1):page252_i89@pure_quanta.q_cap(chips)"
			("LOCATION" "PC577")
		)
		("@t6g_mb_lib.t6g(sch_1):page252_i112@pure_quanta.q_cap(chips)"
			("LOCATION" "PC581")
		)
		("@t6g_mb_lib.t6g(sch_1):page252_i149@pure_quanta.q_cap(chips)"
			("LOCATION" "PC591")
		)
		("@t6g_mb_lib.t6g(sch_1):page252_i96@pure_quanta.q_capp(chips)"
			("LOCATION" "PC1866")
		)
		("@t6g_mb_lib.t6g(sch_1):page252_i95@pure_quanta.q_capp(chips)"
			("LOCATION" "PC1867")
		)
		("@t6g_mb_lib.t6g(sch_1):page252_i94@pure_quanta.q_cap(chips)"
			("LOCATION" "PC1868")
		)
		("@t6g_mb_lib.t6g(sch_1):page252_i92@pure_quanta.q_cap(chips)"
			("LOCATION" "PC1869")
		)
		("@t6g_mb_lib.t6g(sch_1):page252_i146@pure_quanta.q_inductor(chips)"
			("LOCATION" "PL45")
		)
		("@t6g_mb_lib.t6g(sch_1):page252_i97@pure_quanta.q_inductor(chips)"
			("LOCATION" "PL66")
		)
		("@t6g_mb_lib.t6g(sch_1):page252_i102@pure_quanta.q_res(chips)"
			("LOCATION" "PR73")
		)
		("@t6g_mb_lib.t6g(sch_1):page252_i137@pure_quanta.q_res(chips)"
			("LOCATION" "PR389")
		)
		("@t6g_mb_lib.t6g(sch_1):page252_i100@pure_quanta.q_res(chips)"
			("LOCATION" "PR830")
		)
		("@t6g_mb_lib.t6g(sch_1):page252_i98@pure_quanta.q_res(chips)"
			("LOCATION" "PR831")
		)
		("@t6g_mb_lib.t6g(sch_1):page252_i123@pure_quanta.q_res(chips)"
			("LOCATION" "PR832")
		)
		("@t6g_mb_lib.t6g(sch_1):page252_i121@pure_quanta.q_res(chips)"
			("LOCATION" "PR833")
		)
		("@t6g_mb_lib.t6g(sch_1):page252_i119@pure_quanta.q_res(chips)"
			("LOCATION" "PR834")
		)
		("@t6g_mb_lib.t6g(sch_1):page252_i104@pure_quanta.q_res(chips)"
			("LOCATION" "PR835")
		)
		("@t6g_mb_lib.t6g(sch_1):page252_i141@pure_quanta.q_res(chips)"
			("LOCATION" "PR836")
		)
		("@t6g_mb_lib.t6g(sch_1):page252_i130@pure_quanta.ncp3284mntxg(chips)"
			("LOCATION" "PU9")
		)
		("@t6g_mb_lib.t6g(sch_1):page202_i537@pure_quanta.q_cap(chips)"
			("LOCATION" "C726")
		)
		("@t6g_mb_lib.t6g(sch_1):page202_i538@pure_quanta.q_cap(chips)"
			("LOCATION" "C727")
		)
		("@t6g_mb_lib.t6g(sch_1):page202_i536@pure_quanta.q_cap(chips)"
			("LOCATION" "C728")
		)
		("@t6g_mb_lib.t6g(sch_1):page202_i535@pure_quanta.q_cap(chips)"
			("LOCATION" "C729")
		)
		("@t6g_mb_lib.t6g(sch_1):page202_i515@pure_quanta.q_cap(chips)"
			("LOCATION" "C730")
		)
		("@t6g_mb_lib.t6g(sch_1):page202_i514@pure_quanta.q_cap(chips)"
			("LOCATION" "C731")
		)
		("@t6g_mb_lib.t6g(sch_1):page202_i512@pure_quanta.q_cap(chips)"
			("LOCATION" "C732")
		)
		("@t6g_mb_lib.t6g(sch_1):page202_i513@pure_quanta.q_cap(chips)"
			("LOCATION" "C733")
		)
		("@t6g_mb_lib.t6g(sch_1):page202_i560@pure_quanta.q_cap(chips)"
			("LOCATION" "C1173")
		)
		("@t6g_mb_lib.t6g(sch_1):page202_i562@pure_quanta.q_cap(chips)"
			("LOCATION" "C1174")
		)
		("@t6g_mb_lib.t6g(sch_1):page202_i565@pure_quanta.q_cap(chips)"
			("LOCATION" "C1175")
		)
		("@t6g_mb_lib.t6g(sch_1):page202_i577@pure_quanta.q_cap(chips)"
			("LOCATION" "C2527")
		)
		("@t6g_mb_lib.t6g(sch_1):page202_i578@pure_quanta.q_cap(chips)"
			("LOCATION" "C2528")
		)
		("@t6g_mb_lib.t6g(sch_1):page202_i580@pure_quanta.q_cap(chips)"
			("LOCATION" "C2529")
		)
		("@t6g_mb_lib.t6g(sch_1):page202_i588@pure_quanta.q_diode(chips)"
			("LOCATION" "D102")
		)
		("@t6g_mb_lib.t6g(sch_1):page202_i589@pure_quanta.q_diode(chips)"
			("LOCATION" "D103")
		)
		("@t6g_mb_lib.t6g(sch_1):page202_i581@pure_quanta.sconn75k_517650752c012(chips)"
			("LOCATION" "J65")
		)
		("@t6g_mb_lib.t6g(sch_1):page202_i520@pure_quanta.sconn75k_517650752c012(chips)"
			("LOCATION" "J66")
		)
		("@t6g_mb_lib.t6g(sch_1):page202_i545@pure_quanta.q_res(chips)"
			("LOCATION" "R482")
		)
		("@t6g_mb_lib.t6g(sch_1):page202_i553@pure_quanta.q_res(chips)"
			("LOCATION" "R483")
		)
		("@t6g_mb_lib.t6g(sch_1):page202_i546@pure_quanta.q_res(chips)"
			("LOCATION" "R484")
		)
		("@t6g_mb_lib.t6g(sch_1):page202_i544@pure_quanta.q_res(chips)"
			("LOCATION" "R485")
		)
		("@t6g_mb_lib.t6g(sch_1):page202_i554@pure_quanta.q_res(chips)"
			("LOCATION" "R486")
		)
		("@t6g_mb_lib.t6g(sch_1):page202_i563@pure_quanta.q_res(chips)"
			("LOCATION" "R487")
		)
		("@t6g_mb_lib.t6g(sch_1):page202_i569@pure_quanta.q_res(chips)"
			("LOCATION" "R503")
		)
		("@t6g_mb_lib.t6g(sch_1):page202_i567@pure_quanta.q_res(chips)"
			("LOCATION" "R694")
		)
		("@t6g_mb_lib.t6g(sch_1):page202_i570@pure_quanta.q_res(chips)"
			("LOCATION" "R769")
		)
		("@t6g_mb_lib.t6g(sch_1):page202_i568@pure_quanta.q_res(chips)"
			("LOCATION" "R869")
		)
		("@t6g_mb_lib.t6g(sch_1):page202_i508@pure_quanta.q_res(chips)"
			("LOCATION" "R1699")
		)
		("@t6g_mb_lib.t6g(sch_1):page202_i551@pure_quanta.q_res(chips)"
			("LOCATION" "R1706")
		)
		("@t6g_mb_lib.t6g(sch_1):page202_i550@pure_quanta.q_res(chips)"
			("LOCATION" "R1707")
		)
		("@t6g_mb_lib.t6g(sch_1):page202_i549@pure_quanta.q_res(chips)"
			("LOCATION" "R1708")
		)
		("@t6g_mb_lib.t6g(sch_1):page202_i542@pure_quanta.q_res(chips)"
			("LOCATION" "R1709")
		)
		("@t6g_mb_lib.t6g(sch_1):page202_i517@pure_quanta.q_res(chips)"
			("LOCATION" "R1718")
		)
		("@t6g_mb_lib.t6g(sch_1):page202_i501@pure_quanta.q_res(chips)"
			("LOCATION" "R2705")
		)
		("@t6g_mb_lib.t6g(sch_1):page202_i598@pure_quanta.q_res(chips)"
			("LOCATION" "R3835")
		)
		("@t6g_mb_lib.t6g(sch_1):page202_i600@pure_quanta.q_res(chips)"
			("LOCATION" "R3836")
		)
		("@t6g_mb_lib.t6g(sch_1):page202_i599@pure_quanta.q_res(chips)"
			("LOCATION" "R3837")
		)
		("@t6g_mb_lib.t6g(sch_1):page202_i587@pure_quanta.q_res(chips)"
			("LOCATION" "R4580")
		)
		("@t6g_mb_lib.t6g(sch_1):page202_i583@pure_quanta.q_res(chips)"
			("LOCATION" "R4581")
		)
		("@t6g_mb_lib.t6g(sch_1):page264_i64@pure_quanta.q_cap(chips)"
			("LOCATION" "C807")
		)
		("@t6g_mb_lib.t6g(sch_1):page264_i84@pure_quanta.q_cap(chips)"
			("LOCATION" "C808")
		)
		("@t6g_mb_lib.t6g(sch_1):page264_i81@pure_quanta.q_cap(chips)"
			("LOCATION" "C809")
		)
		("@t6g_mb_lib.t6g(sch_1):page264_i85@pure_quanta.q_cap(chips)"
			("LOCATION" "C810")
		)
		("@t6g_mb_lib.t6g(sch_1):page264_i24@pure_quanta.q_cap(chips)"
			("LOCATION" "C933")
		)
		("@t6g_mb_lib.t6g(sch_1):page264_i60@pure_quanta.q_cap(chips)"
			("LOCATION" "C2396")
		)
		("@t6g_mb_lib.t6g(sch_1):page264_i74@pure_quanta.q_cap(chips)"
			("LOCATION" "C2399")
		)
		("@t6g_mb_lib.t6g(sch_1):page264_i72@pure_quanta.q_cap(chips)"
			("LOCATION" "C2401")
		)
		("@t6g_mb_lib.t6g(sch_1):page264_i75@pure_quanta.q_cap(chips)"
			("LOCATION" "C2402")
		)
		("@t6g_mb_lib.t6g(sch_1):page264_i18@pure_quanta.q_inductor4p_12(chips)"
			("LOCATION" "L81")
		)
		("@t6g_mb_lib.t6g(sch_1):page264_i34@pure_quanta.q_inductor4p_12(chips)"
			("LOCATION" "L82")
		)
		("@t6g_mb_lib.t6g(sch_1):page264_i66@pure_quanta.q_res(chips)"
			("LOCATION" "R979")
		)
		("@t6g_mb_lib.t6g(sch_1):page264_i33@pure_quanta.q_res(chips)"
			("LOCATION" "R1158")
		)
		("@t6g_mb_lib.t6g(sch_1):page264_i30@pure_quanta.q_res(chips)"
			("LOCATION" "R1159")
		)
		("@t6g_mb_lib.t6g(sch_1):page264_i22@pure_quanta.q_res(chips)"
			("LOCATION" "R1160")
		)
		("@t6g_mb_lib.t6g(sch_1):page264_i27@pure_quanta.q_res(chips)"
			("LOCATION" "R1161")
		)
		("@t6g_mb_lib.t6g(sch_1):page264_i62@pure_quanta.q_res(chips)"
			("LOCATION" "R2393")
		)
		("@t6g_mb_lib.t6g(sch_1):page264_i67@pure_quanta.tusb211irwbr(chips)"
			("LOCATION" "U83")
		)
		("@t6g_mb_lib.t6g(sch_1):page264_i25@pure_quanta.ip4220cz6(chips)"
			("LOCATION" "U91")
		)
		("@t6g_mb_lib.t6g(sch_1):page264_i63@pure_quanta.tusb211irwbr(chips)"
			("LOCATION" "U201")
		)
		("@t6g_mb_lib.t6g(sch_1):page280_i254@pure_quanta.q_cap(chips)"
			("LOCATION" "C811")
		)
		("@t6g_mb_lib.t6g(sch_1):page280_i248@pure_quanta.q_cap(chips)"
			("LOCATION" "C812")
		)
		("@t6g_mb_lib.t6g(sch_1):page280_i177@pure_quanta.mosfet_nch_dual(chips)"
			("LOCATION" "Q85")
		)
		("@t6g_mb_lib.t6g(sch_1):page280_i176@pure_quanta.mosfet_nch_dual(chips)"
			("LOCATION" "Q85")
		)
		("@t6g_mb_lib.t6g(sch_1):page280_i227@pure_quanta.mosfet_nch_dual(chips)"
			("LOCATION" "Q93")
		)
		("@t6g_mb_lib.t6g(sch_1):page280_i209@pure_quanta.mosfet_nch_dual(chips)"
			("LOCATION" "Q93")
		)
		("@t6g_mb_lib.t6g(sch_1):page280_i236@pure_quanta.mosfet_nch_dual(chips)"
			("LOCATION" "Q183")
		)
		("@t6g_mb_lib.t6g(sch_1):page280_i239@pure_quanta.mosfet_nch_dual(chips)"
			("LOCATION" "Q183")
		)
		("@t6g_mb_lib.t6g(sch_1):page280_i173@pure_quanta.q_res(chips)"
			("LOCATION" "R521")
		)
		("@t6g_mb_lib.t6g(sch_1):page280_i174@pure_quanta.q_res(chips)"
			("LOCATION" "R522")
		)
		("@t6g_mb_lib.t6g(sch_1):page280_i325@pure_quanta.q_res(chips)"
			("LOCATION" "R533")
		)
		("@t6g_mb_lib.t6g(sch_1):page280_i315@pure_quanta.q_res(chips)"
			("LOCATION" "R534")
		)
		("@t6g_mb_lib.t6g(sch_1):page280_i324@pure_quanta.q_res(chips)"
			("LOCATION" "R535")
		)
		("@t6g_mb_lib.t6g(sch_1):page280_i314@pure_quanta.q_res(chips)"
			("LOCATION" "R542")
		)
		("@t6g_mb_lib.t6g(sch_1):page280_i255@pure_quanta.q_res(chips)"
			("LOCATION" "R566")
		)
		("@t6g_mb_lib.t6g(sch_1):page280_i253@pure_quanta.q_res(chips)"
			("LOCATION" "R573")
		)
		("@t6g_mb_lib.t6g(sch_1):page280_i235@pure_quanta.q_res(chips)"
			("LOCATION" "R575")
		)
		("@t6g_mb_lib.t6g(sch_1):page280_i233@pure_quanta.q_res(chips)"
			("LOCATION" "R605")
		)
		("@t6g_mb_lib.t6g(sch_1):page280_i241@pure_quanta.q_res(chips)"
			("LOCATION" "R631")
		)
		("@t6g_mb_lib.t6g(sch_1):page280_i171@pure_quanta.q_res(chips)"
			("LOCATION" "R1537")
		)
		("@t6g_mb_lib.t6g(sch_1):page280_i172@pure_quanta.q_res(chips)"
			("LOCATION" "R1538")
		)
		("@t6g_mb_lib.t6g(sch_1):page280_i166@pure_quanta.q_res(chips)"
			("LOCATION" "R2847")
		)
		("@t6g_mb_lib.t6g(sch_1):page280_i170@pure_quanta.q_res(chips)"
			("LOCATION" "R2848")
		)
		("@t6g_mb_lib.t6g(sch_1):page280_i208@pure_quanta.q_res(chips)"
			("LOCATION" "R3493")
		)
		("@t6g_mb_lib.t6g(sch_1):page280_i211@pure_quanta.q_res(chips)"
			("LOCATION" "R3494")
		)
		("@t6g_mb_lib.t6g(sch_1):page280_i229@pure_quanta.q_res(chips)"
			("LOCATION" "R3546")
		)
		("@t6g_mb_lib.t6g(sch_1):page280_i231@pure_quanta.q_res(chips)"
			("LOCATION" "R3547")
		)
		("@t6g_mb_lib.t6g(sch_1):page280_i247@pure_quanta.\\74lvc1g02gw\\(chips)"
			("LOCATION" "U13")
		)
		("@t6g_mb_lib.t6g(sch_1):page148_i18@pure_quanta.q_cap(chips)"
			("LOCATION" "C887")
		)
		("@t6g_mb_lib.t6g(sch_1):page148_i45@pure_quanta.q_cap(chips)"
			("LOCATION" "C888")
		)
		("@t6g_mb_lib.t6g(sch_1):page148_i83@pure_quanta.q_cap(chips)"
			("LOCATION" "C889")
		)
		("@t6g_mb_lib.t6g(sch_1):page148_i86@pure_quanta.q_cap(chips)"
			("LOCATION" "C890")
		)
		("@t6g_mb_lib.t6g(sch_1):page148_i78@pure_quanta.q_cap(chips)"
			("LOCATION" "C891")
		)
		("@t6g_mb_lib.t6g(sch_1):page148_i80@pure_quanta.q_cap(chips)"
			("LOCATION" "C896")
		)
		("@t6g_mb_lib.t6g(sch_1):page148_i51@pure_quanta.q_cap(chips)"
			("LOCATION" "C897")
		)
		("@t6g_mb_lib.t6g(sch_1):page148_i19@pure_quanta.q_diode(chips)"
			("LOCATION" "D29")
		)
		("@t6g_mb_lib.t6g(sch_1):page148_i27@pure_quanta.q_diode(chips)"
			("LOCATION" "D31")
		)
		("@t6g_mb_lib.t6g(sch_1):page148_i28@pure_quanta.q_diode(chips)"
			("LOCATION" "D32")
		)
		("@t6g_mb_lib.t6g(sch_1):page148_i21@pure_quanta.q_diode(chips)"
			("LOCATION" "D33")
		)
		("@t6g_mb_lib.t6g(sch_1):page148_i22@pure_quanta.q_diode(chips)"
			("LOCATION" "D34")
		)
		("@t6g_mb_lib.t6g(sch_1):page148_i52@pure_quanta.mosfet_nch_dual(chips)"
			("LOCATION" "Q30")
		)
		("@t6g_mb_lib.t6g(sch_1):page148_i33@pure_quanta.mosfet_nch_dual(chips)"
			("LOCATION" "Q30")
		)
		("@t6g_mb_lib.t6g(sch_1):page148_i92@pure_quanta.mosfet_nch_dual(chips)"
			("LOCATION" "Q31")
		)
		("@t6g_mb_lib.t6g(sch_1):page148_i94@pure_quanta.mosfet_nch_dual(chips)"
			("LOCATION" "Q31")
		)
		("@t6g_mb_lib.t6g(sch_1):page148_i37@pure_quanta.mosfet_nch_dual(chips)"
			("LOCATION" "Q32")
		)
		("@t6g_mb_lib.t6g(sch_1):page148_i36@pure_quanta.mosfet_nch_dual(chips)"
			("LOCATION" "Q32")
		)
		("@t6g_mb_lib.t6g(sch_1):page148_i64@pure_quanta.q_res(chips)"
			("LOCATION" "R106")
		)
		("@t6g_mb_lib.t6g(sch_1):page148_i63@pure_quanta.q_res(chips)"
			("LOCATION" "R1112")
		)
		("@t6g_mb_lib.t6g(sch_1):page148_i62@pure_quanta.q_res(chips)"
			("LOCATION" "R1113")
		)
		("@t6g_mb_lib.t6g(sch_1):page148_i69@pure_quanta.q_res(chips)"
			("LOCATION" "R1114")
		)
		("@t6g_mb_lib.t6g(sch_1):page148_i61@pure_quanta.q_res(chips)"
			("LOCATION" "R1115")
		)
		("@t6g_mb_lib.t6g(sch_1):page148_i81@pure_quanta.q_res(chips)"
			("LOCATION" "R1116")
		)
		("@t6g_mb_lib.t6g(sch_1):page148_i29@pure_quanta.q_res(chips)"
			("LOCATION" "R1117")
		)
		("@t6g_mb_lib.t6g(sch_1):page148_i100@pure_quanta.q_res(chips)"
			("LOCATION" "R1118")
		)
		("@t6g_mb_lib.t6g(sch_1):page148_i97@pure_quanta.q_res(chips)"
			("LOCATION" "R1119")
		)
		("@t6g_mb_lib.t6g(sch_1):page148_i60@pure_quanta.q_res(chips)"
			("LOCATION" "R1120")
		)
		("@t6g_mb_lib.t6g(sch_1):page148_i59@pure_quanta.q_res(chips)"
			("LOCATION" "R1121")
		)
		("@t6g_mb_lib.t6g(sch_1):page148_i56@pure_quanta.q_res(chips)"
			("LOCATION" "R1122")
		)
		("@t6g_mb_lib.t6g(sch_1):page148_i55@pure_quanta.q_res(chips)"
			("LOCATION" "R1123")
		)
		("@t6g_mb_lib.t6g(sch_1):page148_i26@pure_quanta.q_res(chips)"
			("LOCATION" "R1124")
		)
		("@t6g_mb_lib.t6g(sch_1):page148_i39@pure_quanta.q_res(chips)"
			("LOCATION" "R1125")
		)
		("@t6g_mb_lib.t6g(sch_1):page148_i42@pure_quanta.q_res(chips)"
			("LOCATION" "R1126")
		)
		("@t6g_mb_lib.t6g(sch_1):page148_i57@pure_quanta.q_res(chips)"
			("LOCATION" "R1127")
		)
		("@t6g_mb_lib.t6g(sch_1):page148_i16@pure_quanta.q_res(chips)"
			("LOCATION" "R1128")
		)
		("@t6g_mb_lib.t6g(sch_1):page148_i23@pure_quanta.q_res(chips)"
			("LOCATION" "R1129")
		)
		("@t6g_mb_lib.t6g(sch_1):page148_i90@pure_quanta.q_res(chips)"
			("LOCATION" "R1131")
		)
		("@t6g_mb_lib.t6g(sch_1):page148_i98@pure_quanta.q_res(chips)"
			("LOCATION" "R1132")
		)
		("@t6g_mb_lib.t6g(sch_1):page148_i82@pure_quanta.q_res(chips)"
			("LOCATION" "R1136")
		)
		("@t6g_mb_lib.t6g(sch_1):page148_i125@pure_quanta.q_res(chips)"
			("LOCATION" "R2747")
		)
		("@t6g_mb_lib.t6g(sch_1):page148_i128@pure_quanta.q_res(chips)"
			("LOCATION" "R2748")
		)
		("@t6g_mb_lib.t6g(sch_1):page148_i124@pure_quanta.q_res(chips)"
			("LOCATION" "R2749")
		)
		("@t6g_mb_lib.t6g(sch_1):page148_i126@pure_quanta.q_res(chips)"
			("LOCATION" "R2750")
		)
		("@t6g_mb_lib.t6g(sch_1):page148_i135@pure_quanta.q_res(chips)"
			("LOCATION" "R3791")
		)
		("@t6g_mb_lib.t6g(sch_1):page148_i134@pure_quanta.q_res(chips)"
			("LOCATION" "R3792")
		)
		("@t6g_mb_lib.t6g(sch_1):page148_i88@pure_quanta.tps3808g18dbvr(chips)"
			("LOCATION" "U4")
		)
		("@t6g_mb_lib.t6g(sch_1):page148_i49@pure_quanta.sn74lvc2g07dckr(chips)"
			("LOCATION" "U82")
		)
		("@t6g_mb_lib.t6g(sch_1):page148_i47@pure_quanta.sn74lvc1g17dckr(chips)"
			("LOCATION" "U84")
		)
		("@t6g_mb_lib.t6g(sch_1):page234_i76@pure_quanta.q_cap(chips)"
			("LOCATION" "C1046")
		)
		("@t6g_mb_lib.t6g(sch_1):page234_i64@pure_quanta.q_cap(chips)"
			("LOCATION" "C1047")
		)
		("@t6g_mb_lib.t6g(sch_1):page234_i74@pure_quanta.q_cap(chips)"
			("LOCATION" "C1048")
		)
		("@t6g_mb_lib.t6g(sch_1):page234_i67@pure_quanta.q_cap(chips)"
			("LOCATION" "C2530")
		)
		("@t6g_mb_lib.t6g(sch_1):page234_i85@pure_quanta.q_res(chips)"
			("LOCATION" "R1339")
		)
		("@t6g_mb_lib.t6g(sch_1):page234_i86@pure_quanta.q_res(chips)"
			("LOCATION" "R1340")
		)
		("@t6g_mb_lib.t6g(sch_1):page234_i92@pure_quanta.q_res(chips)"
			("LOCATION" "R1341")
		)
		("@t6g_mb_lib.t6g(sch_1):page234_i93@pure_quanta.q_res(chips)"
			("LOCATION" "R1342")
		)
		("@t6g_mb_lib.t6g(sch_1):page234_i84@pure_quanta.q_res(chips)"
			("LOCATION" "R1343")
		)
		("@t6g_mb_lib.t6g(sch_1):page234_i91@pure_quanta.q_res(chips)"
			("LOCATION" "R1345")
		)
		("@t6g_mb_lib.t6g(sch_1):page234_i83@pure_quanta.q_res(chips)"
			("LOCATION" "R1346")
		)
		("@t6g_mb_lib.t6g(sch_1):page234_i90@pure_quanta.q_res(chips)"
			("LOCATION" "R1347")
		)
		("@t6g_mb_lib.t6g(sch_1):page234_i69@pure_quanta.q_res(chips)"
			("LOCATION" "R1348")
		)
		("@t6g_mb_lib.t6g(sch_1):page234_i71@pure_quanta.q_res(chips)"
			("LOCATION" "R1349")
		)
		("@t6g_mb_lib.t6g(sch_1):page234_i80@pure_quanta.q_res(chips)"
			("LOCATION" "R1350")
		)
		("@t6g_mb_lib.t6g(sch_1):page234_i81@pure_quanta.q_res(chips)"
			("LOCATION" "R1351")
		)
		("@t6g_mb_lib.t6g(sch_1):page234_i55@pure_quanta.q_res(chips)"
			("LOCATION" "R1356")
		)
		("@t6g_mb_lib.t6g(sch_1):page234_i45@pure_quanta.q_res(chips)"
			("LOCATION" "R1648")
		)
		("@t6g_mb_lib.t6g(sch_1):page234_i54@pure_quanta.q_res(chips)"
			("LOCATION" "R1759")
		)
		("@t6g_mb_lib.t6g(sch_1):page234_i53@pure_quanta.q_res(chips)"
			("LOCATION" "R1760")
		)
		("@t6g_mb_lib.t6g(sch_1):page234_i62@pure_quanta.q_res(chips)"
			("LOCATION" "R1829")
		)
		("@t6g_mb_lib.t6g(sch_1):page234_i61@pure_quanta.q_res(chips)"
			("LOCATION" "R1830")
		)
		("@t6g_mb_lib.t6g(sch_1):page234_i99@pure_quanta.q_res(chips)"
			("LOCATION" "R2646")
		)
		("@t6g_mb_lib.t6g(sch_1):page234_i101@pure_quanta.q_res(chips)"
			("LOCATION" "R2648")
		)
		("@t6g_mb_lib.t6g(sch_1):page234_i98@pure_quanta.q_res(chips)"
			("LOCATION" "R2649")
		)
		("@t6g_mb_lib.t6g(sch_1):page234_i100@pure_quanta.q_res(chips)"
			("LOCATION" "R2650")
		)
		("@t6g_mb_lib.t6g(sch_1):page234_i96@pure_quanta.pca9617adp(chips)"
			("LOCATION" "U117")
		)
		("@t6g_mb_lib.t6g(sch_1):page234_i97@pure_quanta.pca9617adp(chips)"
			("LOCATION" "U119")
		)
		("@t6g_mb_lib.t6g(sch_1):page205_i401@pure_quanta.q_cap(chips)"
			("LOCATION" "C1057")
		)
		("@t6g_mb_lib.t6g(sch_1):page205_i406@pure_quanta.q_cap(chips)"
			("LOCATION" "C1058")
		)
		("@t6g_mb_lib.t6g(sch_1):page205_i409@pure_quanta.q_cap(chips)"
			("LOCATION" "C2249")
		)
		("@t6g_mb_lib.t6g(sch_1):page205_i385@pure_quanta.q_res(chips)"
			("LOCATION" "R384")
		)
		("@t6g_mb_lib.t6g(sch_1):page205_i397@pure_quanta.q_res(chips)"
			("LOCATION" "R385")
		)
		("@t6g_mb_lib.t6g(sch_1):page205_i394@pure_quanta.q_res(chips)"
			("LOCATION" "R386")
		)
		("@t6g_mb_lib.t6g(sch_1):page205_i398@pure_quanta.q_res(chips)"
			("LOCATION" "R387")
		)
		("@t6g_mb_lib.t6g(sch_1):page205_i424@pure_quanta.q_res(chips)"
			("LOCATION" "R388")
		)
		("@t6g_mb_lib.t6g(sch_1):page205_i446@pure_quanta.q_res(chips)"
			("LOCATION" "R448")
		)
		("@t6g_mb_lib.t6g(sch_1):page205_i407@pure_quanta.q_res(chips)"
			("LOCATION" "R454")
		)
		("@t6g_mb_lib.t6g(sch_1):page205_i445@pure_quanta.q_res(chips)"
			("LOCATION" "R456")
		)
		("@t6g_mb_lib.t6g(sch_1):page205_i389@pure_quanta.q_res(chips)"
			("LOCATION" "R562")
		)
		("@t6g_mb_lib.t6g(sch_1):page205_i390@pure_quanta.q_res(chips)"
			("LOCATION" "R912")
		)
		("@t6g_mb_lib.t6g(sch_1):page205_i386@pure_quanta.q_res(chips)"
			("LOCATION" "R953")
		)
		("@t6g_mb_lib.t6g(sch_1):page205_i391@pure_quanta.q_res(chips)"
			("LOCATION" "R1194")
		)
		("@t6g_mb_lib.t6g(sch_1):page205_i387@pure_quanta.q_res(chips)"
			("LOCATION" "R1196")
		)
		("@t6g_mb_lib.t6g(sch_1):page205_i392@pure_quanta.q_res(chips)"
			("LOCATION" "R1204")
		)
		("@t6g_mb_lib.t6g(sch_1):page205_i388@pure_quanta.q_res(chips)"
			("LOCATION" "R1267")
		)
		("@t6g_mb_lib.t6g(sch_1):page205_i393@pure_quanta.q_res(chips)"
			("LOCATION" "R1390")
		)
		("@t6g_mb_lib.t6g(sch_1):page205_i426@pure_quanta.q_res(chips)"
			("LOCATION" "R1483")
		)
		("@t6g_mb_lib.t6g(sch_1):page205_i425@pure_quanta.q_res(chips)"
			("LOCATION" "R1484")
		)
		("@t6g_mb_lib.t6g(sch_1):page205_i395@pure_quanta.q_res(chips)"
			("LOCATION" "R1500")
		)
		("@t6g_mb_lib.t6g(sch_1):page205_i396@pure_quanta.q_res(chips)"
			("LOCATION" "R1502")
		)
		("@t6g_mb_lib.t6g(sch_1):page205_i403@pure_quanta.q_res(chips)"
			("LOCATION" "R3164")
		)
		("@t6g_mb_lib.t6g(sch_1):page205_i411@pure_quanta.q_res(chips)"
			("LOCATION" "R3165")
		)
		("@t6g_mb_lib.t6g(sch_1):page205_i470@pure_quanta.q_res(chips)"
			("LOCATION" "R3794")
		)
		("@t6g_mb_lib.t6g(sch_1):page205_i471@pure_quanta.q_res(chips)"
			("LOCATION" "R3795")
		)
		("@t6g_mb_lib.t6g(sch_1):page205_i467@pure_quanta.\\9sq440nqqi8\\(chips)"
			("LOCATION" "U23")
		)
		("@t6g_mb_lib.t6g(sch_1):page205_i443@pure_quanta.\\9sq440nqqi8\\(chips)"
			("LOCATION" "U23")
		)
		("@t6g_mb_lib.t6g(sch_1):page205_i402@pure_quanta.q_xtal_4p_13(chips)"
			("LOCATION" "Y2")
		)
		("@t6g_mb_lib.t6g(sch_1):page222_i85@pure_quanta.q_cap(chips)"
			("LOCATION" "C1059")
		)
		("@t6g_mb_lib.t6g(sch_1):page222_i77@pure_quanta.q_res(chips)"
			("LOCATION" "R87")
		)
		("@t6g_mb_lib.t6g(sch_1):page222_i78@pure_quanta.q_res(chips)"
			("LOCATION" "R318")
		)
		("@t6g_mb_lib.t6g(sch_1):page222_i117@pure_quanta.q_res(chips)"
			("LOCATION" "R679")
		)
		("@t6g_mb_lib.t6g(sch_1):page222_i116@pure_quanta.q_res(chips)"
			("LOCATION" "R680")
		)
		("@t6g_mb_lib.t6g(sch_1):page222_i114@pure_quanta.q_res(chips)"
			("LOCATION" "R681")
		)
		("@t6g_mb_lib.t6g(sch_1):page222_i89@pure_quanta.q_res(chips)"
			("LOCATION" "R682")
		)
		("@t6g_mb_lib.t6g(sch_1):page222_i90@pure_quanta.q_res(chips)"
			("LOCATION" "R683")
		)
		("@t6g_mb_lib.t6g(sch_1):page222_i91@pure_quanta.q_res(chips)"
			("LOCATION" "R684")
		)
		("@t6g_mb_lib.t6g(sch_1):page222_i92@pure_quanta.q_res(chips)"
			("LOCATION" "R685")
		)
		("@t6g_mb_lib.t6g(sch_1):page222_i113@pure_quanta.q_res(chips)"
			("LOCATION" "R686")
		)
		("@t6g_mb_lib.t6g(sch_1):page222_i111@pure_quanta.q_res(chips)"
			("LOCATION" "R687")
		)
		("@t6g_mb_lib.t6g(sch_1):page222_i112@pure_quanta.q_res(chips)"
			("LOCATION" "R688")
		)
		("@t6g_mb_lib.t6g(sch_1):page222_i121@pure_quanta.q_res(chips)"
			("LOCATION" "R689")
		)
		("@t6g_mb_lib.t6g(sch_1):page222_i120@pure_quanta.q_res(chips)"
			("LOCATION" "R690")
		)
		("@t6g_mb_lib.t6g(sch_1):page222_i81@pure_quanta.q_res(chips)"
			("LOCATION" "R691")
		)
		("@t6g_mb_lib.t6g(sch_1):page222_i80@pure_quanta.q_res(chips)"
			("LOCATION" "R692")
		)
		("@t6g_mb_lib.t6g(sch_1):page222_i82@pure_quanta.q_res(chips)"
			("LOCATION" "R693")
		)
		("@t6g_mb_lib.t6g(sch_1):page222_i93@pure_quanta.q_res(chips)"
			("LOCATION" "R1435")
		)
		("@t6g_mb_lib.t6g(sch_1):page222_i83@pure_quanta.q_res(chips)"
			("LOCATION" "R1436")
		)
		("@t6g_mb_lib.t6g(sch_1):page222_i103@pure_quanta.q_res(chips)"
			("LOCATION" "R1821")
		)
		("@t6g_mb_lib.t6g(sch_1):page222_i106@pure_quanta.idtqs3vh257qg(chips)"
			("LOCATION" "U132")
		)
		("@t6g_mb_lib.t6g(sch_1):page224_i69@pure_quanta.q_cap(chips)"
			("LOCATION" "C1060")
		)
		("@t6g_mb_lib.t6g(sch_1):page224_i82@pure_quanta.q_res(chips)"
			("LOCATION" "R661")
		)
		("@t6g_mb_lib.t6g(sch_1):page224_i99@pure_quanta.q_res(chips)"
			("LOCATION" "R662")
		)
		("@t6g_mb_lib.t6g(sch_1):page224_i98@pure_quanta.q_res(chips)"
			("LOCATION" "R663")
		)
		("@t6g_mb_lib.t6g(sch_1):page224_i96@pure_quanta.q_res(chips)"
			("LOCATION" "R664")
		)
		("@t6g_mb_lib.t6g(sch_1):page224_i72@pure_quanta.q_res(chips)"
			("LOCATION" "R666")
		)
		("@t6g_mb_lib.t6g(sch_1):page224_i95@pure_quanta.q_res(chips)"
			("LOCATION" "R669")
		)
		("@t6g_mb_lib.t6g(sch_1):page224_i91@pure_quanta.q_res(chips)"
			("LOCATION" "R670")
		)
		("@t6g_mb_lib.t6g(sch_1):page224_i92@pure_quanta.q_res(chips)"
			("LOCATION" "R671")
		)
		("@t6g_mb_lib.t6g(sch_1):page224_i93@pure_quanta.q_res(chips)"
			("LOCATION" "R672")
		)
		("@t6g_mb_lib.t6g(sch_1):page224_i94@pure_quanta.q_res(chips)"
			("LOCATION" "R673")
		)
		("@t6g_mb_lib.t6g(sch_1):page224_i63@pure_quanta.q_res(chips)"
			("LOCATION" "R674")
		)
		("@t6g_mb_lib.t6g(sch_1):page224_i64@pure_quanta.q_res(chips)"
			("LOCATION" "R675")
		)
		("@t6g_mb_lib.t6g(sch_1):page224_i65@pure_quanta.q_res(chips)"
			("LOCATION" "R676")
		)
		("@t6g_mb_lib.t6g(sch_1):page224_i71@pure_quanta.q_res(chips)"
			("LOCATION" "R1437")
		)
		("@t6g_mb_lib.t6g(sch_1):page224_i73@pure_quanta.q_res(chips)"
			("LOCATION" "R1438")
		)
		("@t6g_mb_lib.t6g(sch_1):page224_i74@pure_quanta.q_res(chips)"
			("LOCATION" "R1439")
		)
		("@t6g_mb_lib.t6g(sch_1):page224_i66@pure_quanta.q_res(chips)"
			("LOCATION" "R1440")
		)
		("@t6g_mb_lib.t6g(sch_1):page224_i86@pure_quanta.idtqs3vh257qg(chips)"
			("LOCATION" "U133")
		)
		("@t6g_mb_lib.t6g(sch_1):page236_i27@pure_quanta.q_cap(chips)"
			("LOCATION" "C1061")
		)
		("@t6g_mb_lib.t6g(sch_1):page236_i25@pure_quanta.q_cap(chips)"
			("LOCATION" "C1062")
		)
		("@t6g_mb_lib.t6g(sch_1):page236_i7@pure_quanta.q_cap(chips)"
			("LOCATION" "C1292")
		)
		("@t6g_mb_lib.t6g(sch_1):page236_i11@pure_quanta.q_cap(chips)"
			("LOCATION" "C1293")
		)
		("@t6g_mb_lib.t6g(sch_1):page236_i30@pure_quanta.q_res(chips)"
			("LOCATION" "R1365")
		)
		("@t6g_mb_lib.t6g(sch_1):page236_i36@pure_quanta.q_res(chips)"
			("LOCATION" "R1370")
		)
		("@t6g_mb_lib.t6g(sch_1):page236_i23@pure_quanta.q_res(chips)"
			("LOCATION" "R1371")
		)
		("@t6g_mb_lib.t6g(sch_1):page236_i38@pure_quanta.q_res(chips)"
			("LOCATION" "R1372")
		)
		("@t6g_mb_lib.t6g(sch_1):page236_i18@pure_quanta.q_res(chips)"
			("LOCATION" "R1373")
		)
		("@t6g_mb_lib.t6g(sch_1):page236_i17@pure_quanta.q_res(chips)"
			("LOCATION" "R1374")
		)
		("@t6g_mb_lib.t6g(sch_1):page236_i12@pure_quanta.q_res(chips)"
			("LOCATION" "R1375")
		)
		("@t6g_mb_lib.t6g(sch_1):page236_i4@pure_quanta.q_res(chips)"
			("LOCATION" "R1441")
		)
		("@t6g_mb_lib.t6g(sch_1):page236_i5@pure_quanta.q_res(chips)"
			("LOCATION" "R1442")
		)
		("@t6g_mb_lib.t6g(sch_1):page236_i28@pure_quanta.nc7sb3157(chips)"
			("LOCATION" "U122")
		)
		("@t6g_mb_lib.t6g(sch_1):page236_i13@pure_quanta.mosfet_n(chips)"
			("LOCATION" "U123")
		)
		("@t6g_mb_lib.t6g(sch_1):page236_i1@pure_quanta.\\74cbtlv3126pw\\(chips)"
			("LOCATION" "U125")
		)
		("@t6g_mb_lib.t6g(sch_1):page237_i81@pure_quanta.q_cap(chips)"
			("LOCATION" "C1063")
		)
		("@t6g_mb_lib.t6g(sch_1):page237_i76@pure_quanta.q_cap(chips)"
			("LOCATION" "C1070")
		)
		("@t6g_mb_lib.t6g(sch_1):page237_i40@pure_quanta.q_cap(chips)"
			("LOCATION" "C1074")
		)
		("@t6g_mb_lib.t6g(sch_1):page237_i70@pure_quanta.q_cap(chips)"
			("LOCATION" "C1291")
		)
		("@t6g_mb_lib.t6g(sch_1):page237_i82@pure_quanta.q_res(chips)"
			("LOCATION" "R480")
		)
		("@t6g_mb_lib.t6g(sch_1):page237_i83@pure_quanta.q_res(chips)"
			("LOCATION" "R481")
		)
		("@t6g_mb_lib.t6g(sch_1):page237_i91@pure_quanta.q_res(chips)"
			("LOCATION" "R1366")
		)
		("@t6g_mb_lib.t6g(sch_1):page237_i92@pure_quanta.q_res(chips)"
			("LOCATION" "R1367")
		)
		("@t6g_mb_lib.t6g(sch_1):page237_i90@pure_quanta.q_res(chips)"
			("LOCATION" "R1368")
		)
		("@t6g_mb_lib.t6g(sch_1):page237_i89@pure_quanta.q_res(chips)"
			("LOCATION" "R1369")
		)
		("@t6g_mb_lib.t6g(sch_1):page237_i66@pure_quanta.q_res(chips)"
			("LOCATION" "R1376")
		)
		("@t6g_mb_lib.t6g(sch_1):page237_i53@pure_quanta.q_res(chips)"
			("LOCATION" "R1377")
		)
		("@t6g_mb_lib.t6g(sch_1):page237_i68@pure_quanta.q_res(chips)"
			("LOCATION" "R1378")
		)
		("@t6g_mb_lib.t6g(sch_1):page237_i57@pure_quanta.q_res(chips)"
			("LOCATION" "R1379")
		)
		("@t6g_mb_lib.t6g(sch_1):page237_i62@pure_quanta.q_res(chips)"
			("LOCATION" "R1380")
		)
		("@t6g_mb_lib.t6g(sch_1):page237_i45@pure_quanta.q_res(chips)"
			("LOCATION" "R1381")
		)
		("@t6g_mb_lib.t6g(sch_1):page237_i59@pure_quanta.q_res(chips)"
			("LOCATION" "R1382")
		)
		("@t6g_mb_lib.t6g(sch_1):page237_i43@pure_quanta.q_res(chips)"
			("LOCATION" "R1383")
		)
		("@t6g_mb_lib.t6g(sch_1):page237_i84@pure_quanta.q_res(chips)"
			("LOCATION" "R1443")
		)
		("@t6g_mb_lib.t6g(sch_1):page237_i67@pure_quanta.q_res(chips)"
			("LOCATION" "R1444")
		)
		("@t6g_mb_lib.t6g(sch_1):page237_i54@pure_quanta.q_res(chips)"
			("LOCATION" "R1446")
		)
		("@t6g_mb_lib.t6g(sch_1):page237_i55@pure_quanta.q_res(chips)"
			("LOCATION" "R1447")
		)
		("@t6g_mb_lib.t6g(sch_1):page237_i65@pure_quanta.q_res(chips)"
			("LOCATION" "R1448")
		)
		("@t6g_mb_lib.t6g(sch_1):page237_i52@pure_quanta.q_res(chips)"
			("LOCATION" "R1449")
		)
		("@t6g_mb_lib.t6g(sch_1):page237_i109@pure_quanta.q_res(chips)"
			("LOCATION" "R1813")
		)
		("@t6g_mb_lib.t6g(sch_1):page237_i110@pure_quanta.q_res(chips)"
			("LOCATION" "R1814")
		)
		("@t6g_mb_lib.t6g(sch_1):page237_i64@pure_quanta.q_res(chips)"
			("LOCATION" "R1831")
		)
		("@t6g_mb_lib.t6g(sch_1):page237_i56@pure_quanta.q_res(chips)"
			("LOCATION" "R1832")
		)
		("@t6g_mb_lib.t6g(sch_1):page237_i35@pure_quanta.ts3a24157rser(chips)"
			("LOCATION" "U126")
		)
		("@t6g_mb_lib.t6g(sch_1):page237_i100@pure_quanta.ts3a24157rser(chips)"
			("LOCATION" "U127")
		)
		("@t6g_mb_lib.t6g(sch_1):page237_i115@pure_quanta.gtl2014pw(chips)"
			("LOCATION" "U142")
		)
		("@t6g_mb_lib.t6g(sch_1):page237_i116@pure_quanta.gtl2014pw(chips)"
			("LOCATION" "U143")
		)
		("@t6g_mb_lib.t6g(sch_1):page274_i363@pure_quanta.q_cap(chips)"
			("LOCATION" "C1075")
		)
		("@t6g_mb_lib.t6g(sch_1):page274_i372@pure_quanta.conn3_210hp1030br1(chips)"
			("LOCATION" "JP31")
		)
		("@t6g_mb_lib.t6g(sch_1):page274_i378@pure_quanta.q_res(chips)"
			("LOCATION" "R641")
		)
		("@t6g_mb_lib.t6g(sch_1):page274_i380@pure_quanta.q_res(chips)"
			("LOCATION" "R642")
		)
		("@t6g_mb_lib.t6g(sch_1):page274_i377@pure_quanta.q_res(chips)"
			("LOCATION" "R643")
		)
		("@t6g_mb_lib.t6g(sch_1):page274_i379@pure_quanta.q_res(chips)"
			("LOCATION" "R644")
		)
		("@t6g_mb_lib.t6g(sch_1):page274_i367@pure_quanta.q_res(chips)"
			("LOCATION" "R647")
		)
		("@t6g_mb_lib.t6g(sch_1):page274_i58@pure_quanta.q_res(chips)"
			("LOCATION" "R659")
		)
		("@t6g_mb_lib.t6g(sch_1):page274_i57@pure_quanta.q_res(chips)"
			("LOCATION" "R660")
		)
		("@t6g_mb_lib.t6g(sch_1):page274_i365@pure_quanta.q_res(chips)"
			("LOCATION" "R1459")
		)
		("@t6g_mb_lib.t6g(sch_1):page274_i56@pure_quanta.q_res(chips)"
			("LOCATION" "R1460")
		)
		("@t6g_mb_lib.t6g(sch_1):page274_i55@pure_quanta.q_res(chips)"
			("LOCATION" "R1461")
		)
		("@t6g_mb_lib.t6g(sch_1):page274_i385@pure_quanta.q_res(chips)"
			("LOCATION" "R1462")
		)
		("@t6g_mb_lib.t6g(sch_1):page274_i51@pure_quanta.q_res(chips)"
			("LOCATION" "R1468")
		)
		("@t6g_mb_lib.t6g(sch_1):page274_i49@pure_quanta.q_res(chips)"
			("LOCATION" "R1469")
		)
		("@t6g_mb_lib.t6g(sch_1):page274_i50@pure_quanta.q_res(chips)"
			("LOCATION" "R1470")
		)
		("@t6g_mb_lib.t6g(sch_1):page274_i345@pure_quanta.q_res(chips)"
			("LOCATION" "R1471")
		)
		("@t6g_mb_lib.t6g(sch_1):page274_i344@pure_quanta.q_res(chips)"
			("LOCATION" "R1472")
		)
		("@t6g_mb_lib.t6g(sch_1):page274_i45@pure_quanta.q_res(chips)"
			("LOCATION" "R1473")
		)
		("@t6g_mb_lib.t6g(sch_1):page274_i46@pure_quanta.q_res(chips)"
			("LOCATION" "R1474")
		)
		("@t6g_mb_lib.t6g(sch_1):page274_i44@pure_quanta.q_res(chips)"
			("LOCATION" "R1475")
		)
		("@t6g_mb_lib.t6g(sch_1):page274_i43@pure_quanta.q_res(chips)"
			("LOCATION" "R1476")
		)
		("@t6g_mb_lib.t6g(sch_1):page274_i368@pure_quanta.q_res(chips)"
			("LOCATION" "R1714")
		)
		("@t6g_mb_lib.t6g(sch_1):page274_i346@pure_quanta.q_res(chips)"
			("LOCATION" "R2697")
		)
		("@t6g_mb_lib.t6g(sch_1):page274_i52@pure_quanta.q_res(chips)"
			("LOCATION" "R2703")
		)
		("@t6g_mb_lib.t6g(sch_1):page274_i325@pure_quanta.q_res(chips)"
			("LOCATION" "R3624")
		)
		("@t6g_mb_lib.t6g(sch_1):page274_i324@pure_quanta.q_res(chips)"
			("LOCATION" "R3625")
		)
		("@t6g_mb_lib.t6g(sch_1):page274_i327@pure_quanta.q_res(chips)"
			("LOCATION" "R3626")
		)
		("@t6g_mb_lib.t6g(sch_1):page274_i326@pure_quanta.q_res(chips)"
			("LOCATION" "R3627")
		)
		("@t6g_mb_lib.t6g(sch_1):page274_i331@pure_quanta.q_res(chips)"
			("LOCATION" "R3630")
		)
		("@t6g_mb_lib.t6g(sch_1):page274_i330@pure_quanta.q_res(chips)"
			("LOCATION" "R3631")
		)
		("@t6g_mb_lib.t6g(sch_1):page274_i333@pure_quanta.q_res(chips)"
			("LOCATION" "R3632")
		)
		("@t6g_mb_lib.t6g(sch_1):page274_i332@pure_quanta.q_res(chips)"
			("LOCATION" "R3633")
		)
		("@t6g_mb_lib.t6g(sch_1):page274_i336@pure_quanta.q_res(chips)"
			("LOCATION" "R3636")
		)
		("@t6g_mb_lib.t6g(sch_1):page274_i337@pure_quanta.q_res(chips)"
			("LOCATION" "R3637")
		)
		("@t6g_mb_lib.t6g(sch_1):page274_i339@pure_quanta.q_res(chips)"
			("LOCATION" "R3638")
		)
		("@t6g_mb_lib.t6g(sch_1):page274_i338@pure_quanta.q_res(chips)"
			("LOCATION" "R3639")
		)
		("@t6g_mb_lib.t6g(sch_1):page274_i360@pure_quanta.pca9848pw(chips)"
			("LOCATION" "U10")
		)
		("@t6g_mb_lib.t6g(sch_1):page147_i51@pure_quanta.q_cap(chips)"
			("LOCATION" "C1094")
		)
		("@t6g_mb_lib.t6g(sch_1):page147_i43@pure_quanta.q_cap(chips)"
			("LOCATION" "C1095")
		)
		("@t6g_mb_lib.t6g(sch_1):page147_i56@pure_quanta.q_cap(chips)"
			("LOCATION" "C1241")
		)
		("@t6g_mb_lib.t6g(sch_1):page147_i103@pure_quanta.mosfet_nch_dual(chips)"
			("LOCATION" "Q171")
		)
		("@t6g_mb_lib.t6g(sch_1):page147_i101@pure_quanta.mosfet_nch_dual(chips)"
			("LOCATION" "Q171")
		)
		("@t6g_mb_lib.t6g(sch_1):page147_i99@pure_quanta.mosfet_nch_dual(chips)"
			("LOCATION" "Q172")
		)
		("@t6g_mb_lib.t6g(sch_1):page147_i97@pure_quanta.mosfet_nch_dual(chips)"
			("LOCATION" "Q172")
		)
		("@t6g_mb_lib.t6g(sch_1):page147_i20@pure_quanta.q_res(chips)"
			("LOCATION" "R923")
		)
		("@t6g_mb_lib.t6g(sch_1):page147_i78@pure_quanta.q_res(chips)"
			("LOCATION" "R1513")
		)
		("@t6g_mb_lib.t6g(sch_1):page147_i79@pure_quanta.q_res(chips)"
			("LOCATION" "R1514")
		)
		("@t6g_mb_lib.t6g(sch_1):page147_i77@pure_quanta.q_res(chips)"
			("LOCATION" "R1515")
		)
		("@t6g_mb_lib.t6g(sch_1):page147_i76@pure_quanta.q_res(chips)"
			("LOCATION" "R1516")
		)
		("@t6g_mb_lib.t6g(sch_1):page147_i75@pure_quanta.q_res(chips)"
			("LOCATION" "R1517")
		)
		("@t6g_mb_lib.t6g(sch_1):page147_i74@pure_quanta.q_res(chips)"
			("LOCATION" "R1518")
		)
		("@t6g_mb_lib.t6g(sch_1):page147_i73@pure_quanta.q_res(chips)"
			("LOCATION" "R1519")
		)
		("@t6g_mb_lib.t6g(sch_1):page147_i82@pure_quanta.q_res(chips)"
			("LOCATION" "R1520")
		)
		("@t6g_mb_lib.t6g(sch_1):page147_i81@pure_quanta.q_res(chips)"
			("LOCATION" "R1521")
		)
		("@t6g_mb_lib.t6g(sch_1):page147_i80@pure_quanta.q_res(chips)"
			("LOCATION" "R1522")
		)
		("@t6g_mb_lib.t6g(sch_1):page147_i69@pure_quanta.q_res(chips)"
			("LOCATION" "R1523")
		)
		("@t6g_mb_lib.t6g(sch_1):page147_i67@pure_quanta.q_res(chips)"
			("LOCATION" "R1524")
		)
		("@t6g_mb_lib.t6g(sch_1):page147_i65@pure_quanta.q_res(chips)"
			("LOCATION" "R1527")
		)
		("@t6g_mb_lib.t6g(sch_1):page147_i66@pure_quanta.q_res(chips)"
			("LOCATION" "R1528")
		)
		("@t6g_mb_lib.t6g(sch_1):page147_i93@pure_quanta.q_res(chips)"
			("LOCATION" "R1903")
		)
		("@t6g_mb_lib.t6g(sch_1):page147_i94@pure_quanta.q_res(chips)"
			("LOCATION" "R1904")
		)
		("@t6g_mb_lib.t6g(sch_1):page147_i92@pure_quanta.q_res(chips)"
			("LOCATION" "R1985")
		)
		("@t6g_mb_lib.t6g(sch_1):page147_i100@pure_quanta.q_res(chips)"
			("LOCATION" "R4663")
		)
		("@t6g_mb_lib.t6g(sch_1):page147_i30@pure_quanta.\\74cbtlv3126pw\\(chips)"
			("LOCATION" "U148")
		)
		("@t6g_mb_lib.t6g(sch_1):page147_i50@pure_quanta.\\74cbtlv3126pw\\(chips)"
			("LOCATION" "U149")
		)
		("@t6g_mb_lib.t6g(sch_1):page147_i41@pure_quanta.\\74cbtlv3126pw\\(chips)"
			("LOCATION" "U150")
		)
		("@t6g_mb_lib.t6g(sch_1):page268_i77@pure_quanta.q_cap(chips)"
			("LOCATION" "C1101")
		)
		("@t6g_mb_lib.t6g(sch_1):page268_i153@pure_quanta.q_cap(chips)"
			("LOCATION" "C1825")
		)
		("@t6g_mb_lib.t6g(sch_1):page268_i143@pure_quanta.q_cap(chips)"
			("LOCATION" "C2092")
		)
		("@t6g_mb_lib.t6g(sch_1):page268_i145@pure_quanta.q_cap(chips)"
			("LOCATION" "C2103")
		)
		("@t6g_mb_lib.t6g(sch_1):page268_i148@pure_quanta.q_cap(chips)"
			("LOCATION" "C2104")
		)
		("@t6g_mb_lib.t6g(sch_1):page268_i146@pure_quanta.q_cap(chips)"
			("LOCATION" "C2105")
		)
		("@t6g_mb_lib.t6g(sch_1):page268_i142@pure_quanta.q_capp(chips)"
			("LOCATION" "C2106")
		)
		("@t6g_mb_lib.t6g(sch_1):page268_i140@pure_quanta.q_capp(chips)"
			("LOCATION" "C2107")
		)
		("@t6g_mb_lib.t6g(sch_1):page268_i150@pure_quanta.q_capp(chips)"
			("LOCATION" "C2889")
		)
		("@t6g_mb_lib.t6g(sch_1):page268_i156@pure_quanta.q_cap(chips)"
			("LOCATION" "C2890")
		)
		("@t6g_mb_lib.t6g(sch_1):page268_i155@pure_quanta.q_cap(chips)"
			("LOCATION" "C2898")
		)
		("@t6g_mb_lib.t6g(sch_1):page268_i157@pure_quanta.sconn38_u10dh3830002t(chips)"
			("LOCATION" "J219")
		)
		("@t6g_mb_lib.t6g(sch_1):page268_i70@pure_quanta.q_res(chips)"
			("LOCATION" "R1566")
		)
		("@t6g_mb_lib.t6g(sch_1):page268_i67@pure_quanta.q_res(chips)"
			("LOCATION" "R1567")
		)
		("@t6g_mb_lib.t6g(sch_1):page268_i66@pure_quanta.q_res(chips)"
			("LOCATION" "R2394")
		)
		("@t6g_mb_lib.t6g(sch_1):page268_i72@pure_quanta.q_res(chips)"
			("LOCATION" "R2395")
		)
		("@t6g_mb_lib.t6g(sch_1):page268_i63@pure_quanta.tps2062cdr(chips)"
			("LOCATION" "U202")
		)
		("@t6g_mb_lib.t6g(sch_1):page180_i645@pure_quanta.q_cap(chips)"
			("LOCATION" "C1104")
		)
		("@t6g_mb_lib.t6g(sch_1):page180_i615@pure_quanta.q_cap(chips)"
			("LOCATION" "C1229")
		)
		("@t6g_mb_lib.t6g(sch_1):page180_i609@pure_quanta.q_cap(chips)"
			("LOCATION" "C1230")
		)
		("@t6g_mb_lib.t6g(sch_1):page180_i614@pure_quanta.q_res(chips)"
			("LOCATION" "R9")
		)
		("@t6g_mb_lib.t6g(sch_1):page180_i619@pure_quanta.q_res(chips)"
			("LOCATION" "R433")
		)
		("@t6g_mb_lib.t6g(sch_1):page180_i628@pure_quanta.q_res(chips)"
			("LOCATION" "R830")
		)
		("@t6g_mb_lib.t6g(sch_1):page180_i631@pure_quanta.q_res(chips)"
			("LOCATION" "R831")
		)
		("@t6g_mb_lib.t6g(sch_1):page180_i635@pure_quanta.q_res(chips)"
			("LOCATION" "R832")
		)
		("@t6g_mb_lib.t6g(sch_1):page180_i634@pure_quanta.q_res(chips)"
			("LOCATION" "R833")
		)
		("@t6g_mb_lib.t6g(sch_1):page180_i648@pure_quanta.q_res(chips)"
			("LOCATION" "R1268")
		)
		("@t6g_mb_lib.t6g(sch_1):page180_i649@pure_quanta.q_res(chips)"
			("LOCATION" "R1269")
		)
		("@t6g_mb_lib.t6g(sch_1):page180_i532@pure_quanta.q_res(chips)"
			("LOCATION" "R1581")
		)
		("@t6g_mb_lib.t6g(sch_1):page180_i531@pure_quanta.q_res(chips)"
			("LOCATION" "R1582")
		)
		("@t6g_mb_lib.t6g(sch_1):page180_i533@pure_quanta.q_res(chips)"
			("LOCATION" "R1583")
		)
		("@t6g_mb_lib.t6g(sch_1):page180_i512@pure_quanta.q_res(chips)"
			("LOCATION" "R1592")
		)
		("@t6g_mb_lib.t6g(sch_1):page180_i514@pure_quanta.q_res(chips)"
			("LOCATION" "R1593")
		)
		("@t6g_mb_lib.t6g(sch_1):page180_i508@pure_quanta.q_res(chips)"
			("LOCATION" "R1595")
		)
		("@t6g_mb_lib.t6g(sch_1):page180_i509@pure_quanta.q_res(chips)"
			("LOCATION" "R1596")
		)
		("@t6g_mb_lib.t6g(sch_1):page180_i525@pure_quanta.q_res(chips)"
			("LOCATION" "R1597")
		)
		("@t6g_mb_lib.t6g(sch_1):page180_i526@pure_quanta.q_res(chips)"
			("LOCATION" "R1598")
		)
		("@t6g_mb_lib.t6g(sch_1):page180_i527@pure_quanta.q_res(chips)"
			("LOCATION" "R1599")
		)
		("@t6g_mb_lib.t6g(sch_1):page180_i511@pure_quanta.q_res(chips)"
			("LOCATION" "R1600")
		)
		("@t6g_mb_lib.t6g(sch_1):page180_i507@pure_quanta.q_res(chips)"
			("LOCATION" "R1601")
		)
		("@t6g_mb_lib.t6g(sch_1):page180_i528@pure_quanta.q_res(chips)"
			("LOCATION" "R1602")
		)
		("@t6g_mb_lib.t6g(sch_1):page180_i529@pure_quanta.q_res(chips)"
			("LOCATION" "R1603")
		)
		("@t6g_mb_lib.t6g(sch_1):page180_i530@pure_quanta.q_res(chips)"
			("LOCATION" "R1604")
		)
		("@t6g_mb_lib.t6g(sch_1):page180_i606@pure_quanta.q_res(chips)"
			("LOCATION" "R1696")
		)
		("@t6g_mb_lib.t6g(sch_1):page180_i602@pure_quanta.q_res(chips)"
			("LOCATION" "R1697")
		)
		("@t6g_mb_lib.t6g(sch_1):page180_i515@pure_quanta.q_res(chips)"
			("LOCATION" "R1827")
		)
		("@t6g_mb_lib.t6g(sch_1):page180_i524@pure_quanta.q_res(chips)"
			("LOCATION" "R1828")
		)
		("@t6g_mb_lib.t6g(sch_1):page180_i597@pure_quanta.q_res(chips)"
			("LOCATION" "R1900")
		)
		("@t6g_mb_lib.t6g(sch_1):page180_i513@pure_quanta.q_res(chips)"
			("LOCATION" "R2671")
		)
		("@t6g_mb_lib.t6g(sch_1):page180_i642@pure_quanta.q_res(chips)"
			("LOCATION" "R3656")
		)
		("@t6g_mb_lib.t6g(sch_1):page180_i654@pure_quanta.q_res(chips)"
			("LOCATION" "R3693")
		)
		("@t6g_mb_lib.t6g(sch_1):page180_i461@pure_quanta.emmitsburg_rev0p9(chips)"
			("LOCATION" "U8")
		)
		("@t6g_mb_lib.t6g(sch_1):page180_i617@pure_quanta.\\74lvc1g07gv\\(chips)"
			("LOCATION" "U54")
		)
		("@t6g_mb_lib.t6g(sch_1):page180_i612@pure_quanta.\\74lvc1g07gv\\(chips)"
			("LOCATION" "U55")
		)
		("@t6g_mb_lib.t6g(sch_1):page180_i644@pure_quanta.sn74lvc1g17dckr(chips)"
			("LOCATION" "U157")
		)
		("@t6g_mb_lib.t6g(sch_1):page243_i403@pure_quanta.q_cap(chips)"
			("LOCATION" "C1106")
		)
		("@t6g_mb_lib.t6g(sch_1):page243_i406@pure_quanta.q_cap(chips)"
			("LOCATION" "C1107")
		)
		("@t6g_mb_lib.t6g(sch_1):page243_i409@pure_quanta.q_cap(chips)"
			("LOCATION" "C1108")
		)
		("@t6g_mb_lib.t6g(sch_1):page243_i396@pure_quanta.q_cap(chips)"
			("LOCATION" "C1109")
		)
		("@t6g_mb_lib.t6g(sch_1):page243_i398@pure_quanta.q_cap(chips)"
			("LOCATION" "C1110")
		)
		("@t6g_mb_lib.t6g(sch_1):page243_i402@pure_quanta.q_cap(chips)"
			("LOCATION" "C1111")
		)
		("@t6g_mb_lib.t6g(sch_1):page243_i395@pure_quanta.q_cap(chips)"
			("LOCATION" "C1112")
		)
		("@t6g_mb_lib.t6g(sch_1):page243_i397@pure_quanta.q_cap(chips)"
			("LOCATION" "C1113")
		)
		("@t6g_mb_lib.t6g(sch_1):page243_i401@pure_quanta.q_cap(chips)"
			("LOCATION" "C1114")
		)
		("@t6g_mb_lib.t6g(sch_1):page243_i384@pure_quanta.q_cap(chips)"
			("LOCATION" "C1115")
		)
		("@t6g_mb_lib.t6g(sch_1):page243_i387@pure_quanta.q_cap(chips)"
			("LOCATION" "C1116")
		)
		("@t6g_mb_lib.t6g(sch_1):page243_i392@pure_quanta.q_cap(chips)"
			("LOCATION" "C1117")
		)
		("@t6g_mb_lib.t6g(sch_1):page243_i394@pure_quanta.q_cap(chips)"
			("LOCATION" "C1118")
		)
		("@t6g_mb_lib.t6g(sch_1):page243_i400@pure_quanta.q_cap(chips)"
			("LOCATION" "C1119")
		)
		("@t6g_mb_lib.t6g(sch_1):page243_i424@pure_quanta.q_cap(chips)"
			("LOCATION" "C1120")
		)
		("@t6g_mb_lib.t6g(sch_1):page243_i391@pure_quanta.q_cap(chips)"
			("LOCATION" "C1121")
		)
		("@t6g_mb_lib.t6g(sch_1):page243_i393@pure_quanta.q_cap(chips)"
			("LOCATION" "C1122")
		)
		("@t6g_mb_lib.t6g(sch_1):page243_i399@pure_quanta.q_cap(chips)"
			("LOCATION" "C1123")
		)
		("@t6g_mb_lib.t6g(sch_1):page243_i358@pure_quanta.q_cap(chips)"
			("LOCATION" "C1124")
		)
		("@t6g_mb_lib.t6g(sch_1):page243_i362@pure_quanta.q_cap(chips)"
			("LOCATION" "C1125")
		)
		("@t6g_mb_lib.t6g(sch_1):page243_i378@pure_quanta.q_cap(chips)"
			("LOCATION" "C1126")
		)
		("@t6g_mb_lib.t6g(sch_1):page243_i380@pure_quanta.q_cap(chips)"
			("LOCATION" "C1127")
		)
		("@t6g_mb_lib.t6g(sch_1):page243_i383@pure_quanta.q_cap(chips)"
			("LOCATION" "C1128")
		)
		("@t6g_mb_lib.t6g(sch_1):page243_i422@pure_quanta.q_cap(chips)"
			("LOCATION" "C1129")
		)
		("@t6g_mb_lib.t6g(sch_1):page243_i357@pure_quanta.q_cap(chips)"
			("LOCATION" "C1130")
		)
		("@t6g_mb_lib.t6g(sch_1):page243_i360@pure_quanta.q_cap(chips)"
			("LOCATION" "C1131")
		)
		("@t6g_mb_lib.t6g(sch_1):page243_i377@pure_quanta.q_cap(chips)"
			("LOCATION" "C1132")
		)
		("@t6g_mb_lib.t6g(sch_1):page243_i379@pure_quanta.q_cap(chips)"
			("LOCATION" "C1133")
		)
		("@t6g_mb_lib.t6g(sch_1):page243_i336@pure_quanta.q_cap(chips)"
			("LOCATION" "C1134")
		)
		("@t6g_mb_lib.t6g(sch_1):page243_i421@pure_quanta.q_cap(chips)"
			("LOCATION" "C1135")
		)
		("@t6g_mb_lib.t6g(sch_1):page243_i356@pure_quanta.q_cap(chips)"
			("LOCATION" "C1136")
		)
		("@t6g_mb_lib.t6g(sch_1):page243_i374@pure_quanta.q_cap(chips)"
			("LOCATION" "C1137")
		)
		("@t6g_mb_lib.t6g(sch_1):page243_i376@pure_quanta.q_cap(chips)"
			("LOCATION" "C1138")
		)
		("@t6g_mb_lib.t6g(sch_1):page243_i382@pure_quanta.q_cap(chips)"
			("LOCATION" "C1139")
		)
		("@t6g_mb_lib.t6g(sch_1):page243_i355@pure_quanta.q_cap(chips)"
			("LOCATION" "C1140")
		)
		("@t6g_mb_lib.t6g(sch_1):page243_i373@pure_quanta.q_cap(chips)"
			("LOCATION" "C1141")
		)
		("@t6g_mb_lib.t6g(sch_1):page243_i375@pure_quanta.q_cap(chips)"
			("LOCATION" "C1142")
		)
		("@t6g_mb_lib.t6g(sch_1):page243_i381@pure_quanta.q_cap(chips)"
			("LOCATION" "C1143")
		)
		("@t6g_mb_lib.t6g(sch_1):page243_i353@pure_quanta.q_cap(chips)"
			("LOCATION" "C1144")
		)
		("@t6g_mb_lib.t6g(sch_1):page243_i366@pure_quanta.q_cap(chips)"
			("LOCATION" "C1145")
		)
		("@t6g_mb_lib.t6g(sch_1):page243_i368@pure_quanta.q_cap(chips)"
			("LOCATION" "C1146")
		)
		("@t6g_mb_lib.t6g(sch_1):page243_i372@pure_quanta.q_cap(chips)"
			("LOCATION" "C1147")
		)
		("@t6g_mb_lib.t6g(sch_1):page243_i352@pure_quanta.q_cap(chips)"
			("LOCATION" "C1148")
		)
		("@t6g_mb_lib.t6g(sch_1):page243_i365@pure_quanta.q_cap(chips)"
			("LOCATION" "C1149")
		)
		("@t6g_mb_lib.t6g(sch_1):page243_i367@pure_quanta.q_cap(chips)"
			("LOCATION" "C1150")
		)
		("@t6g_mb_lib.t6g(sch_1):page243_i371@pure_quanta.q_cap(chips)"
			("LOCATION" "C1151")
		)
		("@t6g_mb_lib.t6g(sch_1):page243_i364@pure_quanta.q_cap(chips)"
			("LOCATION" "C1152")
		)
		("@t6g_mb_lib.t6g(sch_1):page243_i370@pure_quanta.q_cap(chips)"
			("LOCATION" "C1153")
		)
		("@t6g_mb_lib.t6g(sch_1):page243_i363@pure_quanta.q_cap(chips)"
			("LOCATION" "C1154")
		)
		("@t6g_mb_lib.t6g(sch_1):page243_i369@pure_quanta.q_cap(chips)"
			("LOCATION" "C1155")
		)
		("@t6g_mb_lib.t6g(sch_1):page243_i342@pure_quanta.q_cap(chips)"
			("LOCATION" "C1156")
		)
		("@t6g_mb_lib.t6g(sch_1):page243_i345@pure_quanta.q_cap(chips)"
			("LOCATION" "C1157")
		)
		("@t6g_mb_lib.t6g(sch_1):page243_i349@pure_quanta.q_cap(chips)"
			("LOCATION" "C1158")
		)
		("@t6g_mb_lib.t6g(sch_1):page243_i341@pure_quanta.q_cap(chips)"
			("LOCATION" "C1159")
		)
		("@t6g_mb_lib.t6g(sch_1):page243_i414@pure_quanta.q_cap(chips)"
			("LOCATION" "C1160")
		)
		("@t6g_mb_lib.t6g(sch_1):page243_i344@pure_quanta.q_cap(chips)"
			("LOCATION" "C1161")
		)
		("@t6g_mb_lib.t6g(sch_1):page243_i348@pure_quanta.q_cap(chips)"
			("LOCATION" "C1162")
		)
		("@t6g_mb_lib.t6g(sch_1):page243_i338@pure_quanta.q_cap(chips)"
			("LOCATION" "C1163")
		)
		("@t6g_mb_lib.t6g(sch_1):page243_i340@pure_quanta.q_cap(chips)"
			("LOCATION" "C1164")
		)
		("@t6g_mb_lib.t6g(sch_1):page243_i347@pure_quanta.q_cap(chips)"
			("LOCATION" "C1165")
		)
		("@t6g_mb_lib.t6g(sch_1):page243_i413@pure_quanta.q_cap(chips)"
			("LOCATION" "C1166")
		)
		("@t6g_mb_lib.t6g(sch_1):page243_i339@pure_quanta.q_cap(chips)"
			("LOCATION" "C1167")
		)
		("@t6g_mb_lib.t6g(sch_1):page243_i346@pure_quanta.q_cap(chips)"
			("LOCATION" "C1168")
		)
		("@t6g_mb_lib.t6g(sch_1):page243_i412@pure_quanta.q_cap(chips)"
			("LOCATION" "C1169")
		)
		("@t6g_mb_lib.t6g(sch_1):page243_i385@pure_quanta.q_inductor(chips)"
			("LOCATION" "L36")
		)
		("@t6g_mb_lib.t6g(sch_1):page243_i386@pure_quanta.q_inductor(chips)"
			("LOCATION" "L37")
		)
		("@t6g_mb_lib.t6g(sch_1):page243_i436@pure_quanta.q_res(chips)"
			("LOCATION" "R507")
		)
		("@t6g_mb_lib.t6g(sch_1):page243_i437@pure_quanta.q_res(chips)"
			("LOCATION" "R508")
		)
		("@t6g_mb_lib.t6g(sch_1):page243_i430@pure_quanta.q_res(chips)"
			("LOCATION" "R509")
		)
		("@t6g_mb_lib.t6g(sch_1):page243_i390@pure_quanta.q_res(chips)"
			("LOCATION" "R510")
		)
		("@t6g_mb_lib.t6g(sch_1):page243_i425@pure_quanta.q_res(chips)"
			("LOCATION" "R511")
		)
		("@t6g_mb_lib.t6g(sch_1):page243_i426@pure_quanta.q_res(chips)"
			("LOCATION" "R512")
		)
		("@t6g_mb_lib.t6g(sch_1):page243_i416@pure_quanta.q_res(chips)"
			("LOCATION" "R513")
		)
		("@t6g_mb_lib.t6g(sch_1):page243_i417@pure_quanta.q_res(chips)"
			("LOCATION" "R514")
		)
		("@t6g_mb_lib.t6g(sch_1):page243_i440@pure_quanta.\\10m25daf484c7g\\(chips)"
			("LOCATION" "U3")
		)
		("@t6g_mb_lib.t6g(sch_1):page277_i431@pure_quanta.q_cap(chips)"
			("LOCATION" "C1172")
		)
		("@t6g_mb_lib.t6g(sch_1):page277_i441@pure_quanta.conn3_210hp1030br1(chips)"
			("LOCATION" "JP32")
		)
		("@t6g_mb_lib.t6g(sch_1):page277_i393@pure_quanta.mosfet_nch_dual(chips)"
			("LOCATION" "Q77")
		)
		("@t6g_mb_lib.t6g(sch_1):page277_i390@pure_quanta.mosfet_nch_dual(chips)"
			("LOCATION" "Q77")
		)
		("@t6g_mb_lib.t6g(sch_1):page277_i443@pure_quanta.q_res(chips)"
			("LOCATION" "R703")
		)
		("@t6g_mb_lib.t6g(sch_1):page277_i449@pure_quanta.q_res(chips)"
			("LOCATION" "R704")
		)
		("@t6g_mb_lib.t6g(sch_1):page277_i434@pure_quanta.q_res(chips)"
			("LOCATION" "R836")
		)
		("@t6g_mb_lib.t6g(sch_1):page277_i411@pure_quanta.q_res(chips)"
			("LOCATION" "R837")
		)
		("@t6g_mb_lib.t6g(sch_1):page277_i410@pure_quanta.q_res(chips)"
			("LOCATION" "R893")
		)
		("@t6g_mb_lib.t6g(sch_1):page277_i412@pure_quanta.q_res(chips)"
			("LOCATION" "R894")
		)
		("@t6g_mb_lib.t6g(sch_1):page277_i414@pure_quanta.q_res(chips)"
			("LOCATION" "R895")
		)
		("@t6g_mb_lib.t6g(sch_1):page277_i413@pure_quanta.q_res(chips)"
			("LOCATION" "R896")
		)
		("@t6g_mb_lib.t6g(sch_1):page277_i415@pure_quanta.q_res(chips)"
			("LOCATION" "R897")
		)
		("@t6g_mb_lib.t6g(sch_1):page277_i417@pure_quanta.q_res(chips)"
			("LOCATION" "R899")
		)
		("@t6g_mb_lib.t6g(sch_1):page277_i416@pure_quanta.q_res(chips)"
			("LOCATION" "R900")
		)
		("@t6g_mb_lib.t6g(sch_1):page277_i419@pure_quanta.q_res(chips)"
			("LOCATION" "R901")
		)
		("@t6g_mb_lib.t6g(sch_1):page277_i418@pure_quanta.q_res(chips)"
			("LOCATION" "R902")
		)
		("@t6g_mb_lib.t6g(sch_1):page277_i420@pure_quanta.q_res(chips)"
			("LOCATION" "R903")
		)
		("@t6g_mb_lib.t6g(sch_1):page277_i421@pure_quanta.q_res(chips)"
			("LOCATION" "R904")
		)
		("@t6g_mb_lib.t6g(sch_1):page277_i422@pure_quanta.q_res(chips)"
			("LOCATION" "R905")
		)
		("@t6g_mb_lib.t6g(sch_1):page277_i427@pure_quanta.q_res(chips)"
			("LOCATION" "R906")
		)
		("@t6g_mb_lib.t6g(sch_1):page277_i428@pure_quanta.q_res(chips)"
			("LOCATION" "R907")
		)
		("@t6g_mb_lib.t6g(sch_1):page277_i429@pure_quanta.q_res(chips)"
			("LOCATION" "R908")
		)
		("@t6g_mb_lib.t6g(sch_1):page277_i457@pure_quanta.q_res(chips)"
			("LOCATION" "R913")
		)
		("@t6g_mb_lib.t6g(sch_1):page277_i458@pure_quanta.q_res(chips)"
			("LOCATION" "R914")
		)
		("@t6g_mb_lib.t6g(sch_1):page277_i460@pure_quanta.q_res(chips)"
			("LOCATION" "R915")
		)
		("@t6g_mb_lib.t6g(sch_1):page277_i459@pure_quanta.q_res(chips)"
			("LOCATION" "R916")
		)
		("@t6g_mb_lib.t6g(sch_1):page277_i336@pure_quanta.q_res(chips)"
			("LOCATION" "R918")
		)
		("@t6g_mb_lib.t6g(sch_1):page277_i335@pure_quanta.q_res(chips)"
			("LOCATION" "R924")
		)
		("@t6g_mb_lib.t6g(sch_1):page277_i334@pure_quanta.q_res(chips)"
			("LOCATION" "R926")
		)
		("@t6g_mb_lib.t6g(sch_1):page277_i333@pure_quanta.q_res(chips)"
			("LOCATION" "R940")
		)
		("@t6g_mb_lib.t6g(sch_1):page277_i332@pure_quanta.q_res(chips)"
			("LOCATION" "R941")
		)
		("@t6g_mb_lib.t6g(sch_1):page277_i331@pure_quanta.q_res(chips)"
			("LOCATION" "R942")
		)
		("@t6g_mb_lib.t6g(sch_1):page277_i330@pure_quanta.q_res(chips)"
			("LOCATION" "R943")
		)
		("@t6g_mb_lib.t6g(sch_1):page277_i329@pure_quanta.q_res(chips)"
			("LOCATION" "R944")
		)
		("@t6g_mb_lib.t6g(sch_1):page277_i327@pure_quanta.q_res(chips)"
			("LOCATION" "R945")
		)
		("@t6g_mb_lib.t6g(sch_1):page277_i328@pure_quanta.q_res(chips)"
			("LOCATION" "R946")
		)
		("@t6g_mb_lib.t6g(sch_1):page277_i326@pure_quanta.q_res(chips)"
			("LOCATION" "R947")
		)
		("@t6g_mb_lib.t6g(sch_1):page277_i325@pure_quanta.q_res(chips)"
			("LOCATION" "R948")
		)
		("@t6g_mb_lib.t6g(sch_1):page277_i381@pure_quanta.q_res(chips)"
			("LOCATION" "R1336")
		)
		("@t6g_mb_lib.t6g(sch_1):page277_i436@pure_quanta.q_res(chips)"
			("LOCATION" "R1618")
		)
		("@t6g_mb_lib.t6g(sch_1):page277_i435@pure_quanta.q_res(chips)"
			("LOCATION" "R1619")
		)
		("@t6g_mb_lib.t6g(sch_1):page277_i380@pure_quanta.q_res(chips)"
			("LOCATION" "R3648")
		)
		("@t6g_mb_lib.t6g(sch_1):page277_i387@pure_quanta.q_res(chips)"
			("LOCATION" "R3708")
		)
		("@t6g_mb_lib.t6g(sch_1):page277_i388@pure_quanta.q_res(chips)"
			("LOCATION" "R3709")
		)
		("@t6g_mb_lib.t6g(sch_1):page277_i397@pure_quanta.pca9848pw(chips)"
			("LOCATION" "U159")
		)
		("@t6g_mb_lib.t6g(sch_1):page191_i2@pure_quanta.q_cap(chips)"
			("LOCATION" "C1177")
		)
		("@t6g_mb_lib.t6g(sch_1):page191_i33@pure_quanta.q_res(chips)"
			("LOCATION" "R1334")
		)
		("@t6g_mb_lib.t6g(sch_1):page191_i34@pure_quanta.q_res(chips)"
			("LOCATION" "R1335")
		)
		("@t6g_mb_lib.t6g(sch_1):page191_i26@pure_quanta.q_res(chips)"
			("LOCATION" "R1684")
		)
		("@t6g_mb_lib.t6g(sch_1):page191_i27@pure_quanta.q_res(chips)"
			("LOCATION" "R1685")
		)
		("@t6g_mb_lib.t6g(sch_1):page191_i28@pure_quanta.q_res(chips)"
			("LOCATION" "R1686")
		)
		("@t6g_mb_lib.t6g(sch_1):page191_i32@pure_quanta.q_res(chips)"
			("LOCATION" "R1687")
		)
		("@t6g_mb_lib.t6g(sch_1):page191_i31@pure_quanta.q_res(chips)"
			("LOCATION" "R1688")
		)
		("@t6g_mb_lib.t6g(sch_1):page191_i23@pure_quanta.q_res(chips)"
			("LOCATION" "R1689")
		)
		("@t6g_mb_lib.t6g(sch_1):page191_i10@pure_quanta.q_res(chips)"
			("LOCATION" "R1690")
		)
		("@t6g_mb_lib.t6g(sch_1):page191_i9@pure_quanta.q_res(chips)"
			("LOCATION" "R1691")
		)
		("@t6g_mb_lib.t6g(sch_1):page191_i22@pure_quanta.q_res(chips)"
			("LOCATION" "R1692")
		)
		("@t6g_mb_lib.t6g(sch_1):page191_i6@pure_quanta.q_res(chips)"
			("LOCATION" "R1693")
		)
		("@t6g_mb_lib.t6g(sch_1):page191_i19@pure_quanta.q_res(chips)"
			("LOCATION" "R1694")
		)
		("@t6g_mb_lib.t6g(sch_1):page191_i18@pure_quanta.q_res(chips)"
			("LOCATION" "R1695")
		)
		("@t6g_mb_lib.t6g(sch_1):page191_i12@pure_quanta.sw8s_dhnf04ftvtr(chips)"
			("LOCATION" "S1")
		)
		("@t6g_mb_lib.t6g(sch_1):page191_i1@pure_quanta.sw8s_dhnf04ftvtr(chips)"
			("LOCATION" "S2")
		)
		("@t6g_mb_lib.t6g(sch_1):page186_i335@pure_quanta.q_cap(chips)"
			("LOCATION" "C1178")
		)
		("@t6g_mb_lib.t6g(sch_1):page186_i337@pure_quanta.q_cap(chips)"
			("LOCATION" "C1181")
		)
		("@t6g_mb_lib.t6g(sch_1):page186_i339@pure_quanta.q_cap(chips)"
			("LOCATION" "C1182")
		)
		("@t6g_mb_lib.t6g(sch_1):page186_i341@pure_quanta.q_cap(chips)"
			("LOCATION" "C1183")
		)
		("@t6g_mb_lib.t6g(sch_1):page186_i349@pure_quanta.q_cap(chips)"
			("LOCATION" "C1184")
		)
		("@t6g_mb_lib.t6g(sch_1):page186_i321@pure_quanta.q_cap(chips)"
			("LOCATION" "C1185")
		)
		("@t6g_mb_lib.t6g(sch_1):page186_i323@pure_quanta.q_cap(chips)"
			("LOCATION" "C1186")
		)
		("@t6g_mb_lib.t6g(sch_1):page186_i330@pure_quanta.q_cap(chips)"
			("LOCATION" "C1187")
		)
		("@t6g_mb_lib.t6g(sch_1):page186_i333@pure_quanta.q_cap(chips)"
			("LOCATION" "C1189")
		)
		("@t6g_mb_lib.t6g(sch_1):page186_i346@pure_quanta.q_cap(chips)"
			("LOCATION" "C1191")
		)
		("@t6g_mb_lib.t6g(sch_1):page186_i319@pure_quanta.q_cap(chips)"
			("LOCATION" "C1192")
		)
		("@t6g_mb_lib.t6g(sch_1):page186_i322@pure_quanta.q_cap(chips)"
			("LOCATION" "C1197")
		)
		("@t6g_mb_lib.t6g(sch_1):page186_i329@pure_quanta.q_cap(chips)"
			("LOCATION" "C1198")
		)
		("@t6g_mb_lib.t6g(sch_1):page186_i332@pure_quanta.q_cap(chips)"
			("LOCATION" "C1200")
		)
		("@t6g_mb_lib.t6g(sch_1):page186_i345@pure_quanta.q_cap(chips)"
			("LOCATION" "C1201")
		)
		("@t6g_mb_lib.t6g(sch_1):page186_i317@pure_quanta.q_cap(chips)"
			("LOCATION" "C1202")
		)
		("@t6g_mb_lib.t6g(sch_1):page186_i326@pure_quanta.q_cap(chips)"
			("LOCATION" "C1203")
		)
		("@t6g_mb_lib.t6g(sch_1):page186_i328@pure_quanta.q_cap(chips)"
			("LOCATION" "C1204")
		)
		("@t6g_mb_lib.t6g(sch_1):page186_i313@pure_quanta.q_cap(chips)"
			("LOCATION" "C1205")
		)
		("@t6g_mb_lib.t6g(sch_1):page186_i343@pure_quanta.q_cap(chips)"
			("LOCATION" "C1206")
		)
		("@t6g_mb_lib.t6g(sch_1):page186_i315@pure_quanta.q_cap(chips)"
			("LOCATION" "C1207")
		)
		("@t6g_mb_lib.t6g(sch_1):page186_i324@pure_quanta.q_cap(chips)"
			("LOCATION" "C1210")
		)
		("@t6g_mb_lib.t6g(sch_1):page186_i327@pure_quanta.q_cap(chips)"
			("LOCATION" "C1214")
		)
		("@t6g_mb_lib.t6g(sch_1):page186_i310@pure_quanta.q_cap(chips)"
			("LOCATION" "C1228")
		)
		("@t6g_mb_lib.t6g(sch_1):page186_i304@pure_quanta.q_cap(chips)"
			("LOCATION" "C1231")
		)
		("@t6g_mb_lib.t6g(sch_1):page186_i306@pure_quanta.q_cap(chips)"
			("LOCATION" "C1242")
		)
		("@t6g_mb_lib.t6g(sch_1):page186_i308@pure_quanta.q_cap(chips)"
			("LOCATION" "C1243")
		)
		("@t6g_mb_lib.t6g(sch_1):page186_i288@pure_quanta.q_cap(chips)"
			("LOCATION" "C1244")
		)
		("@t6g_mb_lib.t6g(sch_1):page186_i302@pure_quanta.q_cap(chips)"
			("LOCATION" "C1245")
		)
		("@t6g_mb_lib.t6g(sch_1):page186_i286@pure_quanta.q_cap(chips)"
			("LOCATION" "C1246")
		)
		("@t6g_mb_lib.t6g(sch_1):page186_i291@pure_quanta.q_cap(chips)"
			("LOCATION" "C1247")
		)
		("@t6g_mb_lib.t6g(sch_1):page186_i284@pure_quanta.q_cap(chips)"
			("LOCATION" "C1248")
		)
		("@t6g_mb_lib.t6g(sch_1):page186_i289@pure_quanta.q_cap(chips)"
			("LOCATION" "C1249")
		)
		("@t6g_mb_lib.t6g(sch_1):page186_i267@pure_quanta.q_cap(chips)"
			("LOCATION" "C1250")
		)
		("@t6g_mb_lib.t6g(sch_1):page186_i271@pure_quanta.q_cap(chips)"
			("LOCATION" "C1251")
		)
		("@t6g_mb_lib.t6g(sch_1):page186_i301@pure_quanta.q_cap(chips)"
			("LOCATION" "C1252")
		)
		("@t6g_mb_lib.t6g(sch_1):page186_i281@pure_quanta.q_cap(chips)"
			("LOCATION" "C1253")
		)
		("@t6g_mb_lib.t6g(sch_1):page186_i269@pure_quanta.q_cap(chips)"
			("LOCATION" "C1254")
		)
		("@t6g_mb_lib.t6g(sch_1):page186_i300@pure_quanta.q_cap(chips)"
			("LOCATION" "C1255")
		)
		("@t6g_mb_lib.t6g(sch_1):page186_i265@pure_quanta.q_cap(chips)"
			("LOCATION" "C1256")
		)
		("@t6g_mb_lib.t6g(sch_1):page186_i278@pure_quanta.q_cap(chips)"
			("LOCATION" "C1257")
		)
		("@t6g_mb_lib.t6g(sch_1):page186_i261@pure_quanta.q_cap(chips)"
			("LOCATION" "C1258")
		)
		("@t6g_mb_lib.t6g(sch_1):page186_i298@pure_quanta.q_cap(chips)"
			("LOCATION" "C1259")
		)
		("@t6g_mb_lib.t6g(sch_1):page186_i257@pure_quanta.q_cap(chips)"
			("LOCATION" "C1260")
		)
		("@t6g_mb_lib.t6g(sch_1):page186_i277@pure_quanta.q_cap(chips)"
			("LOCATION" "C1261")
		)
		("@t6g_mb_lib.t6g(sch_1):page186_i260@pure_quanta.q_cap(chips)"
			("LOCATION" "C1262")
		)
		("@t6g_mb_lib.t6g(sch_1):page186_i297@pure_quanta.q_cap(chips)"
			("LOCATION" "C1263")
		)
		("@t6g_mb_lib.t6g(sch_1):page186_i255@pure_quanta.q_cap(chips)"
			("LOCATION" "C1264")
		)
		("@t6g_mb_lib.t6g(sch_1):page186_i274@pure_quanta.q_cap(chips)"
			("LOCATION" "C1265")
		)
		("@t6g_mb_lib.t6g(sch_1):page186_i295@pure_quanta.q_cap(chips)"
			("LOCATION" "C1266")
		)
		("@t6g_mb_lib.t6g(sch_1):page186_i252@pure_quanta.q_cap(chips)"
			("LOCATION" "C1272")
		)
		("@t6g_mb_lib.t6g(sch_1):page186_i293@pure_quanta.q_cap(chips)"
			("LOCATION" "C1273")
		)
		("@t6g_mb_lib.t6g(sch_1):page186_i264@pure_quanta.q_inductor(chips)"
			("LOCATION" "L2")
		)
		("@t6g_mb_lib.t6g(sch_1):page186_i279@pure_quanta.q_inductor(chips)"
			("LOCATION" "L10")
		)
		("@t6g_mb_lib.t6g(sch_1):page186_i263@pure_quanta.q_res(chips)"
			("LOCATION" "R1463")
		)
		("@t6g_mb_lib.t6g(sch_1):page186_i273@pure_quanta.q_res(chips)"
			("LOCATION" "R1464")
		)
		("@t6g_mb_lib.t6g(sch_1):page144_i102@pure_quanta.q_cap_diffbus(chips)"
			("LOCATION" "C1194")
		)
		("@t6g_mb_lib.t6g(sch_1):page144_i42@pure_quanta.q_cap_diffbus(chips)"
			("LOCATION" "C1195")
		)
		("@t6g_mb_lib.t6g(sch_1):page144_i23@pure_quanta.q_cap_diffbus(chips)"
			("LOCATION" "C1196")
		)
		("@t6g_mb_lib.t6g(sch_1):page144_i17@pure_quanta.q_cap_diffbus(chips)"
			("LOCATION" "C1199")
		)
		("@t6g_mb_lib.t6g(sch_1):page144_i16@pure_quanta.q_cap_diffbus(chips)"
			("LOCATION" "C1236")
		)
		("@t6g_mb_lib.t6g(sch_1):page144_i4@pure_quanta.q_cap_diffbus(chips)"
			("LOCATION" "C1237")
		)
		("@t6g_mb_lib.t6g(sch_1):page144_i91@pure_quanta.q_cap_diffbus(chips)"
			("LOCATION" "C1276")
		)
		("@t6g_mb_lib.t6g(sch_1):page144_i78@pure_quanta.q_cap_diffbus(chips)"
			("LOCATION" "C1277")
		)
		("@t6g_mb_lib.t6g(sch_1):page144_i79@pure_quanta.q_cap_diffbus(chips)"
			("LOCATION" "C1278")
		)
		("@t6g_mb_lib.t6g(sch_1):page144_i77@pure_quanta.q_cap_diffbus(chips)"
			("LOCATION" "C1279")
		)
		("@t6g_mb_lib.t6g(sch_1):page144_i68@pure_quanta.q_cap_diffbus(chips)"
			("LOCATION" "C1280")
		)
		("@t6g_mb_lib.t6g(sch_1):page144_i67@pure_quanta.q_cap_diffbus(chips)"
			("LOCATION" "C1281")
		)
		("@t6g_mb_lib.t6g(sch_1):page144_i55@pure_quanta.q_cap_diffbus(chips)"
			("LOCATION" "C1285")
		)
		("@t6g_mb_lib.t6g(sch_1):page144_i96@pure_quanta.q_cap_diffbus(chips)"
			("LOCATION" "C1294")
		)
		("@t6g_mb_lib.t6g(sch_1):page144_i93@pure_quanta.q_cap_diffbus(chips)"
			("LOCATION" "C1295")
		)
		("@t6g_mb_lib.t6g(sch_1):page144_i83@pure_quanta.q_cap_diffbus(chips)"
			("LOCATION" "C1299")
		)
		("@t6g_mb_lib.t6g(sch_1):page144_i80@pure_quanta.q_cap_diffbus(chips)"
			("LOCATION" "C1303")
		)
		("@t6g_mb_lib.t6g(sch_1):page144_i73@pure_quanta.q_cap_diffbus(chips)"
			("LOCATION" "C1304")
		)
		("@t6g_mb_lib.t6g(sch_1):page144_i100@pure_quanta.q_cap_diffbus(chips)"
			("LOCATION" "C1326")
		)
		("@t6g_mb_lib.t6g(sch_1):page144_i69@pure_quanta.q_cap_diffbus(chips)"
			("LOCATION" "C1334")
		)
		("@t6g_mb_lib.t6g(sch_1):page144_i53@pure_quanta.q_cap_diffbus(chips)"
			("LOCATION" "C1335")
		)
		("@t6g_mb_lib.t6g(sch_1):page144_i22@pure_quanta.q_cap_diffbus(chips)"
			("LOCATION" "C2544")
		)
		("@t6g_mb_lib.t6g(sch_1):page144_i21@pure_quanta.q_cap_diffbus(chips)"
			("LOCATION" "C2545")
		)
		("@t6g_mb_lib.t6g(sch_1):page144_i101@pure_quanta.q_cap_diffbus(chips)"
			("LOCATION" "C2546")
		)
		("@t6g_mb_lib.t6g(sch_1):page144_i44@pure_quanta.q_cap_diffbus(chips)"
			("LOCATION" "C2547")
		)
		("@t6g_mb_lib.t6g(sch_1):page144_i25@pure_quanta.q_cap_diffbus(chips)"
			("LOCATION" "C2548")
		)
		("@t6g_mb_lib.t6g(sch_1):page144_i24@pure_quanta.q_cap_diffbus(chips)"
			("LOCATION" "C2549")
		)
		("@t6g_mb_lib.t6g(sch_1):page144_i20@pure_quanta.q_cap_diffbus(chips)"
			("LOCATION" "C2550")
		)
		("@t6g_mb_lib.t6g(sch_1):page144_i19@pure_quanta.q_cap_diffbus(chips)"
			("LOCATION" "C2551")
		)
		("@t6g_mb_lib.t6g(sch_1):page144_i18@pure_quanta.q_cap_diffbus(chips)"
			("LOCATION" "C2552")
		)
		("@t6g_mb_lib.t6g(sch_1):page144_i3@pure_quanta.q_cap_diffbus(chips)"
			("LOCATION" "C2553")
		)
		("@t6g_mb_lib.t6g(sch_1):page144_i103@pure_quanta.q_cap_diffbus(chips)"
			("LOCATION" "C2554")
		)
		("@t6g_mb_lib.t6g(sch_1):page140_i485@pure_quanta.q_cap(chips)"
			("LOCATION" "C1238")
		)
		("@t6g_mb_lib.t6g(sch_1):page140_i484@pure_quanta.q_cap(chips)"
			("LOCATION" "C1239")
		)
		("@t6g_mb_lib.t6g(sch_1):page140_i476@pure_quanta.q_cap(chips)"
			("LOCATION" "C1240")
		)
		("@t6g_mb_lib.t6g(sch_1):page140_i496@pure_quanta.q_cap(chips)"
			("LOCATION" "C2419")
		)
		("@t6g_mb_lib.t6g(sch_1):page140_i495@pure_quanta.q_cap(chips)"
			("LOCATION" "C2420")
		)
		("@t6g_mb_lib.t6g(sch_1):page140_i494@pure_quanta.q_cap(chips)"
			("LOCATION" "C2421")
		)
		("@t6g_mb_lib.t6g(sch_1):page140_i490@pure_quanta.q_cap(chips)"
			("LOCATION" "C2422")
		)
		("@t6g_mb_lib.t6g(sch_1):page140_i489@pure_quanta.q_cap(chips)"
			("LOCATION" "C2423")
		)
		("@t6g_mb_lib.t6g(sch_1):page140_i487@pure_quanta.q_cap(chips)"
			("LOCATION" "C2424")
		)
		("@t6g_mb_lib.t6g(sch_1):page140_i486@pure_quanta.q_cap(chips)"
			("LOCATION" "C2425")
		)
		("@t6g_mb_lib.t6g(sch_1):page140_i526@pure_quanta.sconn168_623403214(chips)"
			("LOCATION" "J80")
		)
		("@t6g_mb_lib.t6g(sch_1):page140_i450@pure_quanta.q_res(chips)"
			("LOCATION" "R417")
		)
		("@t6g_mb_lib.t6g(sch_1):page140_i452@pure_quanta.q_res(chips)"
			("LOCATION" "R418")
		)
		("@t6g_mb_lib.t6g(sch_1):page140_i499@pure_quanta.q_res(chips)"
			("LOCATION" "R420")
		)
		("@t6g_mb_lib.t6g(sch_1):page140_i500@pure_quanta.q_res(chips)"
			("LOCATION" "R421")
		)
		("@t6g_mb_lib.t6g(sch_1):page140_i504@pure_quanta.q_res(chips)"
			("LOCATION" "R422")
		)
		("@t6g_mb_lib.t6g(sch_1):page140_i505@pure_quanta.q_res(chips)"
			("LOCATION" "R423")
		)
		("@t6g_mb_lib.t6g(sch_1):page140_i349@pure_quanta.q_res(chips)"
			("LOCATION" "R424")
		)
		("@t6g_mb_lib.t6g(sch_1):page140_i350@pure_quanta.q_res(chips)"
			("LOCATION" "R425")
		)
		("@t6g_mb_lib.t6g(sch_1):page140_i449@pure_quanta.q_res(chips)"
			("LOCATION" "R429")
		)
		("@t6g_mb_lib.t6g(sch_1):page140_i355@pure_quanta.q_res(chips)"
			("LOCATION" "R445")
		)
		("@t6g_mb_lib.t6g(sch_1):page140_i544@pure_quanta.q_res(chips)"
			("LOCATION" "R879")
		)
		("@t6g_mb_lib.t6g(sch_1):page140_i546@pure_quanta.q_res(chips)"
			("LOCATION" "R880")
		)
		("@t6g_mb_lib.t6g(sch_1):page140_i451@pure_quanta.q_res(chips)"
			("LOCATION" "R1510")
		)
		("@t6g_mb_lib.t6g(sch_1):page140_i354@pure_quanta.q_res(chips)"
			("LOCATION" "R1511")
		)
		("@t6g_mb_lib.t6g(sch_1):page140_i536@pure_quanta.q_res(chips)"
			("LOCATION" "R1671")
		)
		("@t6g_mb_lib.t6g(sch_1):page140_i513@pure_quanta.q_res(chips)"
			("LOCATION" "R1907")
		)
		("@t6g_mb_lib.t6g(sch_1):page140_i516@pure_quanta.q_res(chips)"
			("LOCATION" "R1908")
		)
		("@t6g_mb_lib.t6g(sch_1):page140_i512@pure_quanta.q_res(chips)"
			("LOCATION" "R1909")
		)
		("@t6g_mb_lib.t6g(sch_1):page140_i514@pure_quanta.q_res(chips)"
			("LOCATION" "R1910")
		)
		("@t6g_mb_lib.t6g(sch_1):page140_i522@pure_quanta.q_res(chips)"
			("LOCATION" "R1911")
		)
		("@t6g_mb_lib.t6g(sch_1):page140_i523@pure_quanta.q_res(chips)"
			("LOCATION" "R1912")
		)
		("@t6g_mb_lib.t6g(sch_1):page140_i538@pure_quanta.q_res(chips)"
			("LOCATION" "R3549")
		)
		("@t6g_mb_lib.t6g(sch_1):page140_i545@pure_quanta.q_res(chips)"
			("LOCATION" "R3720")
		)
		("@t6g_mb_lib.t6g(sch_1):page143_i294@pure_quanta.q_cap(chips)"
			("LOCATION" "C1282")
		)
		("@t6g_mb_lib.t6g(sch_1):page143_i293@pure_quanta.q_cap(chips)"
			("LOCATION" "C1283")
		)
		("@t6g_mb_lib.t6g(sch_1):page143_i291@pure_quanta.q_cap(chips)"
			("LOCATION" "C1284")
		)
		("@t6g_mb_lib.t6g(sch_1):page143_i302@pure_quanta.q_cap(chips)"
			("LOCATION" "C2426")
		)
		("@t6g_mb_lib.t6g(sch_1):page143_i301@pure_quanta.q_cap(chips)"
			("LOCATION" "C2427")
		)
		("@t6g_mb_lib.t6g(sch_1):page143_i299@pure_quanta.q_cap(chips)"
			("LOCATION" "C2428")
		)
		("@t6g_mb_lib.t6g(sch_1):page143_i298@pure_quanta.q_cap(chips)"
			("LOCATION" "C2429")
		)
		("@t6g_mb_lib.t6g(sch_1):page143_i297@pure_quanta.q_cap(chips)"
			("LOCATION" "C2430")
		)
		("@t6g_mb_lib.t6g(sch_1):page143_i295@pure_quanta.q_cap(chips)"
			("LOCATION" "C2431")
		)
		("@t6g_mb_lib.t6g(sch_1):page143_i289@pure_quanta.q_cap(chips)"
			("LOCATION" "C2432")
		)
		("@t6g_mb_lib.t6g(sch_1):page143_i367@pure_quanta.q_cap(chips)"
			("LOCATION" "C2819")
		)
		("@t6g_mb_lib.t6g(sch_1):page143_i1@pure_quanta.sconn168_623403214(chips)"
			("LOCATION" "J81")
		)
		("@t6g_mb_lib.t6g(sch_1):page143_i317@pure_quanta.q_res(chips)"
			("LOCATION" "R426")
		)
		("@t6g_mb_lib.t6g(sch_1):page143_i320@pure_quanta.q_res(chips)"
			("LOCATION" "R427")
		)
		("@t6g_mb_lib.t6g(sch_1):page143_i315@pure_quanta.q_res(chips)"
			("LOCATION" "R430")
		)
		("@t6g_mb_lib.t6g(sch_1):page143_i307@pure_quanta.q_res(chips)"
			("LOCATION" "R438")
		)
		("@t6g_mb_lib.t6g(sch_1):page143_i308@pure_quanta.q_res(chips)"
			("LOCATION" "R439")
		)
		("@t6g_mb_lib.t6g(sch_1):page143_i269@pure_quanta.q_res(chips)"
			("LOCATION" "R449")
		)
		("@t6g_mb_lib.t6g(sch_1):page143_i271@pure_quanta.q_res(chips)"
			("LOCATION" "R451")
		)
		("@t6g_mb_lib.t6g(sch_1):page143_i378@pure_quanta.q_res(chips)"
			("LOCATION" "R881")
		)
		("@t6g_mb_lib.t6g(sch_1):page143_i260@pure_quanta.q_res(chips)"
			("LOCATION" "R925")
		)
		("@t6g_mb_lib.t6g(sch_1):page143_i89@pure_quanta.q_res(chips)"
			("LOCATION" "R1493")
		)
		("@t6g_mb_lib.t6g(sch_1):page143_i90@pure_quanta.q_res(chips)"
			("LOCATION" "R1529")
		)
		("@t6g_mb_lib.t6g(sch_1):page143_i318@pure_quanta.q_res(chips)"
			("LOCATION" "R1913")
		)
		("@t6g_mb_lib.t6g(sch_1):page143_i268@pure_quanta.q_res(chips)"
			("LOCATION" "R1915")
		)
		("@t6g_mb_lib.t6g(sch_1):page143_i270@pure_quanta.q_res(chips)"
			("LOCATION" "R1918")
		)
		("@t6g_mb_lib.t6g(sch_1):page143_i272@pure_quanta.q_res(chips)"
			("LOCATION" "R1921")
		)
		("@t6g_mb_lib.t6g(sch_1):page143_i305@pure_quanta.q_res(chips)"
			("LOCATION" "R1922")
		)
		("@t6g_mb_lib.t6g(sch_1):page143_i306@pure_quanta.q_res(chips)"
			("LOCATION" "R1923")
		)
		("@t6g_mb_lib.t6g(sch_1):page143_i284@pure_quanta.q_res(chips)"
			("LOCATION" "R1987")
		)
		("@t6g_mb_lib.t6g(sch_1):page143_i287@pure_quanta.q_res(chips)"
			("LOCATION" "R1988")
		)
		("@t6g_mb_lib.t6g(sch_1):page143_i376@pure_quanta.q_res(chips)"
			("LOCATION" "R3532")
		)
		("@t6g_mb_lib.t6g(sch_1):page143_i377@pure_quanta.q_res(chips)"
			("LOCATION" "R3533")
		)
		("@t6g_mb_lib.t6g(sch_1):page143_i408@pure_quanta.q_res(chips)"
			("LOCATION" "R3789")
		)
		("@t6g_mb_lib.t6g(sch_1):page143_i409@pure_quanta.q_res(chips)"
			("LOCATION" "R3790")
		)
		("@t6g_mb_lib.t6g(sch_1):page143_i368@pure_quanta.sn74lvc1g08dbvr(chips)"
			("LOCATION" "U191")
		)
		("@t6g_mb_lib.t6g(sch_1):page285_i160@pure_quanta.q_cap(chips)"
			("LOCATION" "C1286")
		)
		("@t6g_mb_lib.t6g(sch_1):page285_i149@pure_quanta.q_cap(chips)"
			("LOCATION" "PC113")
		)
		("@t6g_mb_lib.t6g(sch_1):page285_i182@pure_quanta.q_capp(chips)"
			("LOCATION" "PC117")
		)
		("@t6g_mb_lib.t6g(sch_1):page285_i153@pure_quanta.q_capp(chips)"
			("LOCATION" "PC1215")
		)
		("@t6g_mb_lib.t6g(sch_1):page285_i155@pure_quanta.q_cap(chips)"
			("LOCATION" "PC1216")
		)
		("@t6g_mb_lib.t6g(sch_1):page285_i164@pure_quanta.q_cap(chips)"
			("LOCATION" "PC1217")
		)
		("@t6g_mb_lib.t6g(sch_1):page285_i165@pure_quanta.q_cap(chips)"
			("LOCATION" "PC1218")
		)
		("@t6g_mb_lib.t6g(sch_1):page285_i166@pure_quanta.q_cap(chips)"
			("LOCATION" "PC1219")
		)
		("@t6g_mb_lib.t6g(sch_1):page285_i171@pure_quanta.q_cap(chips)"
			("LOCATION" "PC1221")
		)
		("@t6g_mb_lib.t6g(sch_1):page285_i175@pure_quanta.q_cap(chips)"
			("LOCATION" "PC1222")
		)
		("@t6g_mb_lib.t6g(sch_1):page285_i174@pure_quanta.q_cap(chips)"
			("LOCATION" "PC1223")
		)
		("@t6g_mb_lib.t6g(sch_1):page285_i187@pure_quanta.q_cap(chips)"
			("LOCATION" "PC1224")
		)
		("@t6g_mb_lib.t6g(sch_1):page285_i188@pure_quanta.q_cap(chips)"
			("LOCATION" "PC1225")
		)
		("@t6g_mb_lib.t6g(sch_1):page285_i192@pure_quanta.q_cap(chips)"
			("LOCATION" "PC1226")
		)
		("@t6g_mb_lib.t6g(sch_1):page285_i184@pure_quanta.q_capp(chips)"
			("LOCATION" "PC1227")
		)
		("@t6g_mb_lib.t6g(sch_1):page285_i194@pure_quanta.q_capp(chips)"
			("LOCATION" "PC1229")
		)
		("@t6g_mb_lib.t6g(sch_1):page285_i185@pure_quanta.q_capp(chips)"
			("LOCATION" "PC1230")
		)
		("@t6g_mb_lib.t6g(sch_1):page285_i191@pure_quanta.q_short(chips)"
			("LOCATION" "PJ62")
		)
		("@t6g_mb_lib.t6g(sch_1):page285_i146@pure_quanta.q_inductor(chips)"
			("LOCATION" "PL110")
		)
		("@t6g_mb_lib.t6g(sch_1):page285_i179@pure_quanta.q_inductor(chips)"
			("LOCATION" "PL150")
		)
		("@t6g_mb_lib.t6g(sch_1):page285_i176@pure_quanta.q_res(chips)"
			("LOCATION" "PR186")
		)
		("@t6g_mb_lib.t6g(sch_1):page285_i173@pure_quanta.q_res(chips)"
			("LOCATION" "PR187")
		)
		("@t6g_mb_lib.t6g(sch_1):page285_i156@pure_quanta.q_res(chips)"
			("LOCATION" "PR1326")
		)
		("@t6g_mb_lib.t6g(sch_1):page285_i168@pure_quanta.q_res(chips)"
			("LOCATION" "PR1327")
		)
		("@t6g_mb_lib.t6g(sch_1):page285_i178@pure_quanta.q_res(chips)"
			("LOCATION" "PR1328")
		)
		("@t6g_mb_lib.t6g(sch_1):page285_i162@pure_quanta.q_res(chips)"
			("LOCATION" "PR1388")
		)
		("@t6g_mb_lib.t6g(sch_1):page285_i158@pure_quanta.q_res(chips)"
			("LOCATION" "PR1389")
		)
		("@t6g_mb_lib.t6g(sch_1):page285_i163@pure_quanta.q_res(chips)"
			("LOCATION" "PR1647")
		)
		("@t6g_mb_lib.t6g(sch_1):page285_i180@pure_quanta.q_res(chips)"
			("LOCATION" "PR1650")
		)
		("@t6g_mb_lib.t6g(sch_1):page285_i181@pure_quanta.q_res(chips)"
			("LOCATION" "PR2390")
		)
		("@t6g_mb_lib.t6g(sch_1):page285_i169@pure_quanta.mpq8633bglec838z(chips)"
			("LOCATION" "PU73")
		)
		("@t6g_mb_lib.t6g(sch_1):page285_i161@pure_quanta.q_res(chips)"
			("LOCATION" "R1649")
		)
		("@t6g_mb_lib.t6g(sch_1):page305_i178@pure_quanta.q_cap(chips)"
			("LOCATION" "C1296")
		)
		("@t6g_mb_lib.t6g(sch_1):page305_i154@pure_quanta.q_cap(chips)"
			("LOCATION" "C1307")
		)
		("@t6g_mb_lib.t6g(sch_1):page305_i169@pure_quanta.q_cap(chips)"
			("LOCATION" "PC27")
		)
		("@t6g_mb_lib.t6g(sch_1):page305_i179@pure_quanta.q_cap(chips)"
			("LOCATION" "PC237")
		)
		("@t6g_mb_lib.t6g(sch_1):page305_i188@pure_quanta.q_cap(chips)"
			("LOCATION" "PC1206")
		)
		("@t6g_mb_lib.t6g(sch_1):page305_i164@pure_quanta.q_cap(chips)"
			("LOCATION" "PC1272")
		)
		("@t6g_mb_lib.t6g(sch_1):page305_i165@pure_quanta.q_cap(chips)"
			("LOCATION" "PC1273")
		)
		("@t6g_mb_lib.t6g(sch_1):page305_i166@pure_quanta.q_cap(chips)"
			("LOCATION" "PC1274")
		)
		("@t6g_mb_lib.t6g(sch_1):page305_i176@pure_quanta.q_cap(chips)"
			("LOCATION" "PC1275")
		)
		("@t6g_mb_lib.t6g(sch_1):page305_i183@pure_quanta.q_cap(chips)"
			("LOCATION" "PC1276")
		)
		("@t6g_mb_lib.t6g(sch_1):page305_i184@pure_quanta.q_cap(chips)"
			("LOCATION" "PC1277")
		)
		("@t6g_mb_lib.t6g(sch_1):page305_i185@pure_quanta.q_cap(chips)"
			("LOCATION" "PC1278")
		)
		("@t6g_mb_lib.t6g(sch_1):page305_i186@pure_quanta.q_cap(chips)"
			("LOCATION" "PC1279")
		)
		("@t6g_mb_lib.t6g(sch_1):page305_i159@pure_quanta.q_cap(chips)"
			("LOCATION" "PC2221")
		)
		("@t6g_mb_lib.t6g(sch_1):page305_i180@pure_quanta.q_inductor(chips)"
			("LOCATION" "PL120")
		)
		("@t6g_mb_lib.t6g(sch_1):page305_i172@pure_quanta.q_res(chips)"
			("LOCATION" "PR50")
		)
		("@t6g_mb_lib.t6g(sch_1):page305_i182@pure_quanta.q_res(chips)"
			("LOCATION" "PR501")
		)
		("@t6g_mb_lib.t6g(sch_1):page305_i162@pure_quanta.q_res(chips)"
			("LOCATION" "PR1301")
		)
		("@t6g_mb_lib.t6g(sch_1):page305_i161@pure_quanta.q_res(chips)"
			("LOCATION" "PR1303")
		)
		("@t6g_mb_lib.t6g(sch_1):page305_i174@pure_quanta.q_res(chips)"
			("LOCATION" "PR1317")
		)
		("@t6g_mb_lib.t6g(sch_1):page305_i190@pure_quanta.mpq8626gdz(chips)"
			("LOCATION" "PU81")
		)
		("@t6g_mb_lib.t6g(sch_1):page305_i155@pure_quanta.q_res(chips)"
			("LOCATION" "R1445")
		)
		("@t6g_mb_lib.t6g(sch_1):page305_i173@pure_quanta.q_res(chips)"
			("LOCATION" "R1652")
		)
		("@t6g_mb_lib.t6g(sch_1):page305_i156@pure_quanta.q_res(chips)"
			("LOCATION" "R2338")
		)
		("@t6g_mb_lib.t6g(sch_1):page323_i186@pure_quanta.q_cap(chips)"
			("LOCATION" "C1297")
		)
		("@t6g_mb_lib.t6g(sch_1):page323_i166@pure_quanta.q_cap(chips)"
			("LOCATION" "C1308")
		)
		("@t6g_mb_lib.t6g(sch_1):page323_i179@pure_quanta.q_cap(chips)"
			("LOCATION" "PC28")
		)
		("@t6g_mb_lib.t6g(sch_1):page323_i189@pure_quanta.q_cap(chips)"
			("LOCATION" "PC238")
		)
		("@t6g_mb_lib.t6g(sch_1):page323_i196@pure_quanta.q_cap(chips)"
			("LOCATION" "PC1207")
		)
		("@t6g_mb_lib.t6g(sch_1):page323_i169@pure_quanta.q_cap(chips)"
			("LOCATION" "PC1280")
		)
		("@t6g_mb_lib.t6g(sch_1):page323_i170@pure_quanta.q_cap(chips)"
			("LOCATION" "PC1281")
		)
		("@t6g_mb_lib.t6g(sch_1):page323_i175@pure_quanta.q_cap(chips)"
			("LOCATION" "PC1282")
		)
		("@t6g_mb_lib.t6g(sch_1):page323_i181@pure_quanta.q_cap(chips)"
			("LOCATION" "PC1283")
		)
		("@t6g_mb_lib.t6g(sch_1):page323_i184@pure_quanta.q_cap(chips)"
			("LOCATION" "PC1284")
		)
		("@t6g_mb_lib.t6g(sch_1):page323_i192@pure_quanta.q_cap(chips)"
			("LOCATION" "PC1285")
		)
		("@t6g_mb_lib.t6g(sch_1):page323_i193@pure_quanta.q_cap(chips)"
			("LOCATION" "PC1286")
		)
		("@t6g_mb_lib.t6g(sch_1):page323_i194@pure_quanta.q_cap(chips)"
			("LOCATION" "PC1287")
		)
		("@t6g_mb_lib.t6g(sch_1):page323_i174@pure_quanta.q_cap(chips)"
			("LOCATION" "PC2222")
		)
		("@t6g_mb_lib.t6g(sch_1):page323_i182@pure_quanta.q_inductor(chips)"
			("LOCATION" "PL121")
		)
		("@t6g_mb_lib.t6g(sch_1):page323_i180@pure_quanta.q_res(chips)"
			("LOCATION" "PR51")
		)
		("@t6g_mb_lib.t6g(sch_1):page323_i190@pure_quanta.q_res(chips)"
			("LOCATION" "PR502")
		)
		("@t6g_mb_lib.t6g(sch_1):page323_i187@pure_quanta.q_res(chips)"
			("LOCATION" "PR1320")
		)
		("@t6g_mb_lib.t6g(sch_1):page323_i171@pure_quanta.q_res(chips)"
			("LOCATION" "PR2220")
		)
		("@t6g_mb_lib.t6g(sch_1):page323_i177@pure_quanta.q_res(chips)"
			("LOCATION" "PR2222")
		)
		("@t6g_mb_lib.t6g(sch_1):page323_i198@pure_quanta.mpq8626gdz(chips)"
			("LOCATION" "PU82")
		)
		("@t6g_mb_lib.t6g(sch_1):page323_i161@pure_quanta.q_res(chips)"
			("LOCATION" "R2384")
		)
		("@t6g_mb_lib.t6g(sch_1):page323_i168@pure_quanta.q_res(chips)"
			("LOCATION" "R2385")
		)
		("@t6g_mb_lib.t6g(sch_1):page323_i183@pure_quanta.q_res(chips)"
			("LOCATION" "R2387")
		)
		("@t6g_mb_lib.t6g(sch_1):page304_i14@pure_quanta.q_cap(chips)"
			("LOCATION" "C1300")
		)
		("@t6g_mb_lib.t6g(sch_1):page304_i27@pure_quanta.q_cap(chips)"
			("LOCATION" "C1301")
		)
		("@t6g_mb_lib.t6g(sch_1):page304_i44@pure_quanta.q_cap(chips)"
			("LOCATION" "PC831")
		)
		("@t6g_mb_lib.t6g(sch_1):page304_i10@pure_quanta.q_cap(chips)"
			("LOCATION" "PC1247")
		)
		("@t6g_mb_lib.t6g(sch_1):page304_i17@pure_quanta.q_cap(chips)"
			("LOCATION" "PC1248")
		)
		("@t6g_mb_lib.t6g(sch_1):page304_i18@pure_quanta.q_cap(chips)"
			("LOCATION" "PC1249")
		)
		("@t6g_mb_lib.t6g(sch_1):page304_i20@pure_quanta.q_cap(chips)"
			("LOCATION" "PC1251")
		)
		("@t6g_mb_lib.t6g(sch_1):page304_i23@pure_quanta.q_cap(chips)"
			("LOCATION" "PC1252")
		)
		("@t6g_mb_lib.t6g(sch_1):page304_i30@pure_quanta.q_cap(chips)"
			("LOCATION" "PC1253")
		)
		("@t6g_mb_lib.t6g(sch_1):page304_i34@pure_quanta.q_cap(chips)"
			("LOCATION" "PC1254")
		)
		("@t6g_mb_lib.t6g(sch_1):page304_i37@pure_quanta.q_cap(chips)"
			("LOCATION" "PC1255")
		)
		("@t6g_mb_lib.t6g(sch_1):page304_i38@pure_quanta.q_cap(chips)"
			("LOCATION" "PC1256")
		)
		("@t6g_mb_lib.t6g(sch_1):page304_i39@pure_quanta.q_cap(chips)"
			("LOCATION" "PC1257")
		)
		("@t6g_mb_lib.t6g(sch_1):page304_i42@pure_quanta.q_capp(chips)"
			("LOCATION" "PC1258")
		)
		("@t6g_mb_lib.t6g(sch_1):page304_i2@pure_quanta.q_cap(chips)"
			("LOCATION" "PC2643")
		)
		("@t6g_mb_lib.t6g(sch_1):page304_i24@pure_quanta.q_inductor(chips)"
			("LOCATION" "PL118")
		)
		("@t6g_mb_lib.t6g(sch_1):page304_i25@pure_quanta.q_res(chips)"
			("LOCATION" "PR1309")
		)
		("@t6g_mb_lib.t6g(sch_1):page304_i22@pure_quanta.q_res(chips)"
			("LOCATION" "PR1310")
		)
		("@t6g_mb_lib.t6g(sch_1):page304_i5@pure_quanta.q_res(chips)"
			("LOCATION" "PR1335")
		)
		("@t6g_mb_lib.t6g(sch_1):page304_i12@pure_quanta.q_res(chips)"
			("LOCATION" "PR1336")
		)
		("@t6g_mb_lib.t6g(sch_1):page304_i33@pure_quanta.q_res(chips)"
			("LOCATION" "PR1337")
		)
		("@t6g_mb_lib.t6g(sch_1):page304_i13@pure_quanta.mpq8633aglec807z(chips)"
			("LOCATION" "PU79")
		)
		("@t6g_mb_lib.t6g(sch_1):page304_i7@pure_quanta.q_res(chips)"
			("LOCATION" "R2330")
		)
		("@t6g_mb_lib.t6g(sch_1):page304_i16@pure_quanta.q_res(chips)"
			("LOCATION" "R2332")
		)
		("@t6g_mb_lib.t6g(sch_1):page304_i28@pure_quanta.q_res(chips)"
			("LOCATION" "R2334")
		)
		("@t6g_mb_lib.t6g(sch_1):page304_i29@pure_quanta.q_res(chips)"
			("LOCATION" "R2336")
		)
		("@t6g_mb_lib.t6g(sch_1):page304_i32@pure_quanta.mosfet_n(chips)"
			("LOCATION" "U73")
		)
		("@t6g_mb_lib.t6g(sch_1):page271_i488@pure_quanta.q_cap(chips)"
			("LOCATION" "C1302")
		)
		("@t6g_mb_lib.t6g(sch_1):page271_i561@pure_quanta.q_cap(chips)"
			("LOCATION" "C1348")
		)
		("@t6g_mb_lib.t6g(sch_1):page271_i551@pure_quanta.q_cap(chips)"
			("LOCATION" "C1352")
		)
		("@t6g_mb_lib.t6g(sch_1):page271_i565@pure_quanta.q_cap(chips)"
			("LOCATION" "C1434")
		)
		("@t6g_mb_lib.t6g(sch_1):page271_i557@pure_quanta.q_cap(chips)"
			("LOCATION" "C1435")
		)
		("@t6g_mb_lib.t6g(sch_1):page271_i324@pure_quanta.sconn168_623403212(chips)"
			("LOCATION" "J70")
		)
		("@t6g_mb_lib.t6g(sch_1):page271_i560@pure_quanta.mosfet_pch_gds_esd_protected(chips)"
			("LOCATION" "Q44")
		)
		("@t6g_mb_lib.t6g(sch_1):page271_i479@pure_quanta.mosfet_nch_dual(chips)"
			("LOCATION" "Q87")
		)
		("@t6g_mb_lib.t6g(sch_1):page271_i477@pure_quanta.mosfet_nch_dual(chips)"
			("LOCATION" "Q87")
		)
		("@t6g_mb_lib.t6g(sch_1):page271_i495@pure_quanta.mosfet_nch_dual(chips)"
			("LOCATION" "Q89")
		)
		("@t6g_mb_lib.t6g(sch_1):page271_i494@pure_quanta.mosfet_nch_dual(chips)"
			("LOCATION" "Q89")
		)
		("@t6g_mb_lib.t6g(sch_1):page271_i570@pure_quanta.mosfet_nch_dual(chips)"
			("LOCATION" "Q101")
		)
		("@t6g_mb_lib.t6g(sch_1):page271_i563@pure_quanta.mosfet_nch_dual(chips)"
			("LOCATION" "Q101")
		)
		("@t6g_mb_lib.t6g(sch_1):page271_i553@pure_quanta.mosfet_pch_gds_esd_protected(chips)"
			("LOCATION" "Q102")
		)
		("@t6g_mb_lib.t6g(sch_1):page271_i486@pure_quanta.q_res(chips)"
			("LOCATION" "R142")
		)
		("@t6g_mb_lib.t6g(sch_1):page271_i498@pure_quanta.q_res(chips)"
			("LOCATION" "R891")
		)
		("@t6g_mb_lib.t6g(sch_1):page271_i499@pure_quanta.q_res(chips)"
			("LOCATION" "R1040")
		)
		("@t6g_mb_lib.t6g(sch_1):page271_i448@pure_quanta.q_res(chips)"
			("LOCATION" "R1711")
		)
		("@t6g_mb_lib.t6g(sch_1):page271_i451@pure_quanta.q_res(chips)"
			("LOCATION" "R1789")
		)
		("@t6g_mb_lib.t6g(sch_1):page271_i449@pure_quanta.q_res(chips)"
			("LOCATION" "R1797")
		)
		("@t6g_mb_lib.t6g(sch_1):page271_i450@pure_quanta.q_res(chips)"
			("LOCATION" "R1798")
		)
		("@t6g_mb_lib.t6g(sch_1):page271_i328@pure_quanta.q_res(chips)"
			("LOCATION" "R1801")
		)
		("@t6g_mb_lib.t6g(sch_1):page271_i446@pure_quanta.q_res(chips)"
			("LOCATION" "R1815")
		)
		("@t6g_mb_lib.t6g(sch_1):page271_i447@pure_quanta.q_res(chips)"
			("LOCATION" "R1816")
		)
		("@t6g_mb_lib.t6g(sch_1):page271_i453@pure_quanta.q_res(chips)"
			("LOCATION" "R1833")
		)
		("@t6g_mb_lib.t6g(sch_1):page271_i452@pure_quanta.q_res(chips)"
			("LOCATION" "R1845")
		)
		("@t6g_mb_lib.t6g(sch_1):page271_i573@pure_quanta.q_res(chips)"
			("LOCATION" "R1854")
		)
		("@t6g_mb_lib.t6g(sch_1):page271_i559@pure_quanta.q_res(chips)"
			("LOCATION" "R1855")
		)
		("@t6g_mb_lib.t6g(sch_1):page271_i568@pure_quanta.q_res(chips)"
			("LOCATION" "R1856")
		)
		("@t6g_mb_lib.t6g(sch_1):page271_i556@pure_quanta.q_res(chips)"
			("LOCATION" "R1857")
		)
		("@t6g_mb_lib.t6g(sch_1):page271_i481@pure_quanta.q_res(chips)"
			("LOCATION" "R1905")
		)
		("@t6g_mb_lib.t6g(sch_1):page271_i482@pure_quanta.q_res(chips)"
			("LOCATION" "R1906")
		)
		("@t6g_mb_lib.t6g(sch_1):page271_i564@pure_quanta.q_res(chips)"
			("LOCATION" "R3543")
		)
		("@t6g_mb_lib.t6g(sch_1):page271_i676@pure_quanta.q_res(chips)"
			("LOCATION" "R3678")
		)
		("@t6g_mb_lib.t6g(sch_1):page271_i675@pure_quanta.q_res(chips)"
			("LOCATION" "R3738")
		)
		("@t6g_mb_lib.t6g(sch_1):page271_i604@pure_quanta.q_res(chips)"
			("LOCATION" "R3754")
		)
		("@t6g_mb_lib.t6g(sch_1):page271_i605@pure_quanta.q_res(chips)"
			("LOCATION" "R3755")
		)
		("@t6g_mb_lib.t6g(sch_1):page271_i606@pure_quanta.q_res(chips)"
			("LOCATION" "R3756")
		)
		("@t6g_mb_lib.t6g(sch_1):page271_i607@pure_quanta.q_res(chips)"
			("LOCATION" "R3757")
		)
		("@t6g_mb_lib.t6g(sch_1):page271_i615@pure_quanta.q_res(chips)"
			("LOCATION" "R3767")
		)
		("@t6g_mb_lib.t6g(sch_1):page271_i612@pure_quanta.q_res(chips)"
			("LOCATION" "R3768")
		)
		("@t6g_mb_lib.t6g(sch_1):page271_i611@pure_quanta.q_res(chips)"
			("LOCATION" "R3769")
		)
		("@t6g_mb_lib.t6g(sch_1):page271_i628@pure_quanta.q_res(chips)"
			("LOCATION" "R3770")
		)
		("@t6g_mb_lib.t6g(sch_1):page271_i630@pure_quanta.q_res(chips)"
			("LOCATION" "R3771")
		)
		("@t6g_mb_lib.t6g(sch_1):page271_i623@pure_quanta.q_res(chips)"
			("LOCATION" "R3776")
		)
		("@t6g_mb_lib.t6g(sch_1):page271_i624@pure_quanta.q_res(chips)"
			("LOCATION" "R3777")
		)
		("@t6g_mb_lib.t6g(sch_1):page271_i619@pure_quanta.q_res(chips)"
			("LOCATION" "R3778")
		)
		("@t6g_mb_lib.t6g(sch_1):page271_i620@pure_quanta.q_res(chips)"
			("LOCATION" "R3779")
		)
		("@t6g_mb_lib.t6g(sch_1):page271_i632@pure_quanta.q_res(chips)"
			("LOCATION" "R3782")
		)
		("@t6g_mb_lib.t6g(sch_1):page271_i631@pure_quanta.q_res(chips)"
			("LOCATION" "R3783")
		)
		("@t6g_mb_lib.t6g(sch_1):page271_i621@pure_quanta.q_res(chips)"
			("LOCATION" "R3784")
		)
		("@t6g_mb_lib.t6g(sch_1):page271_i636@pure_quanta.q_res(chips)"
			("LOCATION" "R3786")
		)
		("@t6g_mb_lib.t6g(sch_1):page271_i635@pure_quanta.q_res(chips)"
			("LOCATION" "R3787")
		)
		("@t6g_mb_lib.t6g(sch_1):page271_i678@pure_quanta.q_res(chips)"
			("LOCATION" "R3788")
		)
		("@t6g_mb_lib.t6g(sch_1):page271_i679@pure_quanta.q_res(chips)"
			("LOCATION" "R3793")
		)
		("@t6g_mb_lib.t6g(sch_1):page271_i674@pure_quanta.q_res(chips)"
			("LOCATION" "R3796")
		)
		("@t6g_mb_lib.t6g(sch_1):page271_i677@pure_quanta.q_res(chips)"
			("LOCATION" "R3797")
		)
		("@t6g_mb_lib.t6g(sch_1):page271_i687@pure_quanta.q_res(chips)"
			("LOCATION" "R3828")
		)
		("@t6g_mb_lib.t6g(sch_1):page271_i688@pure_quanta.q_res(chips)"
			("LOCATION" "R3829")
		)
		("@t6g_mb_lib.t6g(sch_1):page271_i694@pure_quanta.q_res(chips)"
			("LOCATION" "R3830")
		)
		("@t6g_mb_lib.t6g(sch_1):page271_i693@pure_quanta.q_res(chips)"
			("LOCATION" "R3832")
		)
		("@t6g_mb_lib.t6g(sch_1):page271_i695@pure_quanta.q_res(chips)"
			("LOCATION" "R3833")
		)
		("@t6g_mb_lib.t6g(sch_1):page271_i696@pure_quanta.q_res(chips)"
			("LOCATION" "R3834")
		)
		("@t6g_mb_lib.t6g(sch_1):page271_i705@pure_quanta.tpd2eusb30drtr(chips)"
			("LOCATION" "U198")
		)
		("@t6g_mb_lib.t6g(sch_1):page271_i701@pure_quanta.tpd2eusb30drtr(chips)"
			("LOCATION" "U199")
		)
		("@t6g_mb_lib.t6g(sch_1):page249_i23@pure_quanta.q_cap(chips)"
			("LOCATION" "C1315")
		)
		("@t6g_mb_lib.t6g(sch_1):page249_i38@pure_quanta.q_cap(chips)"
			("LOCATION" "C1316")
		)
		("@t6g_mb_lib.t6g(sch_1):page249_i9@pure_quanta.q_cap(chips)"
			("LOCATION" "C1317")
		)
		("@t6g_mb_lib.t6g(sch_1):page249_i6@pure_quanta.q_cap(chips)"
			("LOCATION" "C1318")
		)
		("@t6g_mb_lib.t6g(sch_1):page249_i28@pure_quanta.q_cap(chips)"
			("LOCATION" "C1319")
		)
		("@t6g_mb_lib.t6g(sch_1):page249_i47@pure_quanta.mosfet_nch_dual(chips)"
			("LOCATION" "Q18")
		)
		("@t6g_mb_lib.t6g(sch_1):page249_i42@pure_quanta.mosfet_nch_dual(chips)"
			("LOCATION" "Q18")
		)
		("@t6g_mb_lib.t6g(sch_1):page249_i13@pure_quanta.q_res(chips)"
			("LOCATION" "R1745")
		)
		("@t6g_mb_lib.t6g(sch_1):page249_i19@pure_quanta.q_res(chips)"
			("LOCATION" "R1781")
		)
		("@t6g_mb_lib.t6g(sch_1):page249_i18@pure_quanta.q_res(chips)"
			("LOCATION" "R1782")
		)
		("@t6g_mb_lib.t6g(sch_1):page249_i21@pure_quanta.q_res(chips)"
			("LOCATION" "R1783")
		)
		("@t6g_mb_lib.t6g(sch_1):page249_i4@pure_quanta.q_res(chips)"
			("LOCATION" "R1784")
		)
		("@t6g_mb_lib.t6g(sch_1):page249_i2@pure_quanta.q_res(chips)"
			("LOCATION" "R1785")
		)
		("@t6g_mb_lib.t6g(sch_1):page249_i48@pure_quanta.q_res(chips)"
			("LOCATION" "R1786")
		)
		("@t6g_mb_lib.t6g(sch_1):page249_i33@pure_quanta.q_res(chips)"
			("LOCATION" "R1787")
		)
		("@t6g_mb_lib.t6g(sch_1):page249_i30@pure_quanta.q_res(chips)"
			("LOCATION" "R1788")
		)
		("@t6g_mb_lib.t6g(sch_1):page249_i41@pure_quanta.q_res(chips)"
			("LOCATION" "R3700")
		)
		("@t6g_mb_lib.t6g(sch_1):page249_i45@pure_quanta.q_res(chips)"
			("LOCATION" "R3707")
		)
		("@t6g_mb_lib.t6g(sch_1):page249_i49@pure_quanta.q_res(chips)"
			("LOCATION" "R3842")
		)
		("@t6g_mb_lib.t6g(sch_1):page249_i26@pure_quanta.adm1086akszreel7(chips)"
			("LOCATION" "U170")
		)
		("@t6g_mb_lib.t6g(sch_1):page249_i14@pure_quanta.sn74lvc1g07dckr(chips)"
			("LOCATION" "U171")
		)
		("@t6g_mb_lib.t6g(sch_1):page249_i25@pure_quanta.tps3897pdryr(chips)"
			("LOCATION" "U172")
		)
		("@t6g_mb_lib.t6g(sch_1):page239_i366@pure_quanta.q_cap(chips)"
			("LOCATION" "C1320")
		)
		("@t6g_mb_lib.t6g(sch_1):page239_i369@pure_quanta.q_osc4p(chips)"
			("LOCATION" "OSC2")
		)
		("@t6g_mb_lib.t6g(sch_1):page239_i371@pure_quanta.q_res(chips)"
			("LOCATION" "R1099")
		)
		("@t6g_mb_lib.t6g(sch_1):page239_i345@pure_quanta.q_res(chips)"
			("LOCATION" "R1100")
		)
		("@t6g_mb_lib.t6g(sch_1):page239_i307@pure_quanta.q_res(chips)"
			("LOCATION" "R1644")
		)
		("@t6g_mb_lib.t6g(sch_1):page239_i309@pure_quanta.q_res(chips)"
			("LOCATION" "R1823")
		)
		("@t6g_mb_lib.t6g(sch_1):page239_i381@pure_quanta.q_res(chips)"
			("LOCATION" "R3843")
		)
		("@t6g_mb_lib.t6g(sch_1):page239_i376@pure_quanta.q_res(chips)"
			("LOCATION" "R3844")
		)
		("@t6g_mb_lib.t6g(sch_1):page239_i382@pure_quanta.q_res(chips)"
			("LOCATION" "R3845")
		)
		("@t6g_mb_lib.t6g(sch_1):page239_i378@pure_quanta.q_res(chips)"
			("LOCATION" "R3846")
		)
		("@t6g_mb_lib.t6g(sch_1):page239_i286@pure_quanta.\\10m25daf484c7g\\(chips)"
			("LOCATION" "U3")
		)
		("@t6g_mb_lib.t6g(sch_1):page242_i205@pure_quanta.q_cap(chips)"
			("LOCATION" "C1325")
		)
		("@t6g_mb_lib.t6g(sch_1):page242_i262@pure_quanta.q_led(chips)"
			("LOCATION" "D0")
		)
		("@t6g_mb_lib.t6g(sch_1):page242_i265@pure_quanta.q_res(chips)"
			("LOCATION" "R668")
		)
		("@t6g_mb_lib.t6g(sch_1):page242_i273@pure_quanta.q_res(chips)"
			("LOCATION" "R699")
		)
		("@t6g_mb_lib.t6g(sch_1):page242_i270@pure_quanta.q_res(chips)"
			("LOCATION" "R706")
		)
		("@t6g_mb_lib.t6g(sch_1):page242_i272@pure_quanta.q_res(chips)"
			("LOCATION" "R707")
		)
		("@t6g_mb_lib.t6g(sch_1):page242_i203@pure_quanta.q_res(chips)"
			("LOCATION" "R1106")
		)
		("@t6g_mb_lib.t6g(sch_1):page242_i264@pure_quanta.q_res(chips)"
			("LOCATION" "R1195")
		)
		("@t6g_mb_lib.t6g(sch_1):page242_i204@pure_quanta.q_res(chips)"
			("LOCATION" "R1710")
		)
		("@t6g_mb_lib.t6g(sch_1):page242_i254@pure_quanta.q_res(chips)"
			("LOCATION" "R1738")
		)
		("@t6g_mb_lib.t6g(sch_1):page242_i255@pure_quanta.q_res(chips)"
			("LOCATION" "R1739")
		)
		("@t6g_mb_lib.t6g(sch_1):page242_i256@pure_quanta.q_res(chips)"
			("LOCATION" "R1740")
		)
		("@t6g_mb_lib.t6g(sch_1):page242_i226@pure_quanta.q_res(chips)"
			("LOCATION" "R1917")
		)
		("@t6g_mb_lib.t6g(sch_1):page242_i289@pure_quanta.q_res(chips)"
			("LOCATION" "R3676")
		)
		("@t6g_mb_lib.t6g(sch_1):page242_i284@pure_quanta.q_res(chips)"
			("LOCATION" "R3722")
		)
		("@t6g_mb_lib.t6g(sch_1):page242_i229@pure_quanta.\\10m25daf484c7g\\(chips)"
			("LOCATION" "U3")
		)
		("@t6g_mb_lib.t6g(sch_1):page242_i258@pure_quanta.\\10m25daf484c7g\\(chips)"
			("LOCATION" "U3")
		)
		("@t6g_mb_lib.t6g(sch_1):page242_i259@pure_quanta.mosfet_n(chips)"
			("LOCATION" "U89")
		)
		("@t6g_mb_lib.t6g(sch_1):page284_i11@pure_quanta.q_cap(chips)"
			("LOCATION" "C1327")
		)
		("@t6g_mb_lib.t6g(sch_1):page284_i17@pure_quanta.q_cap(chips)"
			("LOCATION" "C1328")
		)
		("@t6g_mb_lib.t6g(sch_1):page284_i18@pure_quanta.q_cap(chips)"
			("LOCATION" "C1329")
		)
		("@t6g_mb_lib.t6g(sch_1):page284_i20@pure_quanta.q_cap(chips)"
			("LOCATION" "C1330")
		)
		("@t6g_mb_lib.t6g(sch_1):page284_i7@pure_quanta.q_res(chips)"
			("LOCATION" "R1716")
		)
		("@t6g_mb_lib.t6g(sch_1):page284_i1@pure_quanta.q_res(chips)"
			("LOCATION" "R1729")
		)
		("@t6g_mb_lib.t6g(sch_1):page284_i9@pure_quanta.q_res(chips)"
			("LOCATION" "R1818")
		)
		("@t6g_mb_lib.t6g(sch_1):page284_i8@pure_quanta.q_res(chips)"
			("LOCATION" "R1819")
		)
		("@t6g_mb_lib.t6g(sch_1):page284_i15@pure_quanta.q_res(chips)"
			("LOCATION" "R2340")
		)
		("@t6g_mb_lib.t6g(sch_1):page284_i14@pure_quanta.q_res(chips)"
			("LOCATION" "R2343")
		)
		("@t6g_mb_lib.t6g(sch_1):page284_i24@pure_quanta.rt9059gqw(chips)"
			("LOCATION" "U182")
		)
		("@t6g_mb_lib.t6g(sch_1):page83_i41@pure_quanta.q_cap(chips)"
			("LOCATION" "C1363")
		)
		("@t6g_mb_lib.t6g(sch_1):page83_i42@pure_quanta.q_cap(chips)"
			("LOCATION" "C1364")
		)
		("@t6g_mb_lib.t6g(sch_1):page83_i44@pure_quanta.q_cap(chips)"
			("LOCATION" "C1365")
		)
		("@t6g_mb_lib.t6g(sch_1):page83_i46@pure_quanta.q_cap(chips)"
			("LOCATION" "C1366")
		)
		("@t6g_mb_lib.t6g(sch_1):page83_i5@pure_quanta.q_res(chips)"
			("LOCATION" "R319")
		)
		("@t6g_mb_lib.t6g(sch_1):page83_i4@pure_quanta.q_res(chips)"
			("LOCATION" "R320")
		)
		("@t6g_mb_lib.t6g(sch_1):page83_i2@pure_quanta.q_res(chips)"
			("LOCATION" "R321")
		)
		("@t6g_mb_lib.t6g(sch_1):page83_i13@pure_quanta.q_res(chips)"
			("LOCATION" "R323")
		)
		("@t6g_mb_lib.t6g(sch_1):page83_i11@pure_quanta.q_res(chips)"
			("LOCATION" "R324")
		)
		("@t6g_mb_lib.t6g(sch_1):page83_i25@pure_quanta.q_res(chips)"
			("LOCATION" "R325")
		)
		("@t6g_mb_lib.t6g(sch_1):page83_i24@pure_quanta.q_res(chips)"
			("LOCATION" "R326")
		)
		("@t6g_mb_lib.t6g(sch_1):page83_i20@pure_quanta.q_res(chips)"
			("LOCATION" "R327")
		)
		("@t6g_mb_lib.t6g(sch_1):page83_i37@pure_quanta.q_res(chips)"
			("LOCATION" "R329")
		)
		("@t6g_mb_lib.t6g(sch_1):page83_i36@pure_quanta.q_res(chips)"
			("LOCATION" "R330")
		)
		("@t6g_mb_lib.t6g(sch_1):page83_i18@pure_quanta.q_res(chips)"
			("LOCATION" "R383")
		)
		("@t6g_mb_lib.t6g(sch_1):page83_i1@pure_quanta.q_res(chips)"
			("LOCATION" "R1216")
		)
		("@t6g_mb_lib.t6g(sch_1):page83_i19@pure_quanta.q_res(chips)"
			("LOCATION" "R1217")
		)
		("@t6g_mb_lib.t6g(sch_1):page86_i10@pure_quanta.q_cap(chips)"
			("LOCATION" "C1511")
		)
		("@t6g_mb_lib.t6g(sch_1):page86_i4@pure_quanta.q_cap(chips)"
			("LOCATION" "C1574")
		)
		("@t6g_mb_lib.t6g(sch_1):page86_i45@pure_quanta.q_cap(chips)"
			("LOCATION" "C1575")
		)
		("@t6g_mb_lib.t6g(sch_1):page86_i28@pure_quanta.q_cap(chips)"
			("LOCATION" "C1576")
		)
		("@t6g_mb_lib.t6g(sch_1):page86_i34@pure_quanta.q_cap(chips)"
			("LOCATION" "C1797")
		)
		("@t6g_mb_lib.t6g(sch_1):page86_i22@pure_quanta.q_cap(chips)"
			("LOCATION" "C1798")
		)
		("@t6g_mb_lib.t6g(sch_1):page86_i71@pure_quanta.q_cap(chips)"
			("LOCATION" "C1799")
		)
		("@t6g_mb_lib.t6g(sch_1):page86_i65@pure_quanta.q_cap(chips)"
			("LOCATION" "C1800")
		)
		("@t6g_mb_lib.t6g(sch_1):page86_i80@pure_quanta.mosfet_nch_dual(chips)"
			("LOCATION" "Q8")
		)
		("@t6g_mb_lib.t6g(sch_1):page86_i79@pure_quanta.mosfet_nch_dual(chips)"
			("LOCATION" "Q8")
		)
		("@t6g_mb_lib.t6g(sch_1):page86_i81@pure_quanta.mosfet_nch_dual(chips)"
			("LOCATION" "Q39")
		)
		("@t6g_mb_lib.t6g(sch_1):page86_i82@pure_quanta.mosfet_nch_dual(chips)"
			("LOCATION" "Q39")
		)
		("@t6g_mb_lib.t6g(sch_1):page86_i77@pure_quanta.mosfet_nch_dual(chips)"
			("LOCATION" "Q49")
		)
		("@t6g_mb_lib.t6g(sch_1):page86_i78@pure_quanta.mosfet_nch_dual(chips)"
			("LOCATION" "Q49")
		)
		("@t6g_mb_lib.t6g(sch_1):page86_i84@pure_quanta.mosfet_nch_dual(chips)"
			("LOCATION" "Q50")
		)
		("@t6g_mb_lib.t6g(sch_1):page86_i83@pure_quanta.mosfet_nch_dual(chips)"
			("LOCATION" "Q50")
		)
		("@t6g_mb_lib.t6g(sch_1):page86_i6@pure_quanta.q_res(chips)"
			("LOCATION" "R2300")
		)
		("@t6g_mb_lib.t6g(sch_1):page86_i15@pure_quanta.q_res(chips)"
			("LOCATION" "R2301")
		)
		("@t6g_mb_lib.t6g(sch_1):page86_i14@pure_quanta.q_res(chips)"
			("LOCATION" "R2307")
		)
		("@t6g_mb_lib.t6g(sch_1):page86_i7@pure_quanta.q_res(chips)"
			("LOCATION" "R2355")
		)
		("@t6g_mb_lib.t6g(sch_1):page86_i41@pure_quanta.q_res(chips)"
			("LOCATION" "R2356")
		)
		("@t6g_mb_lib.t6g(sch_1):page86_i26@pure_quanta.q_res(chips)"
			("LOCATION" "R2357")
		)
		("@t6g_mb_lib.t6g(sch_1):page86_i25@pure_quanta.q_res(chips)"
			("LOCATION" "R2358")
		)
		("@t6g_mb_lib.t6g(sch_1):page86_i46@pure_quanta.q_res(chips)"
			("LOCATION" "R2359")
		)
		("@t6g_mb_lib.t6g(sch_1):page86_i42@pure_quanta.q_res(chips)"
			("LOCATION" "R2360")
		)
		("@t6g_mb_lib.t6g(sch_1):page86_i74@pure_quanta.q_res(chips)"
			("LOCATION" "R2361")
		)
		("@t6g_mb_lib.t6g(sch_1):page86_i66@pure_quanta.q_res(chips)"
			("LOCATION" "R2362")
		)
		("@t6g_mb_lib.t6g(sch_1):page86_i72@pure_quanta.q_res(chips)"
			("LOCATION" "R2368")
		)
		("@t6g_mb_lib.t6g(sch_1):page86_i12@pure_quanta.q_res(chips)"
			("LOCATION" "R2414")
		)
		("@t6g_mb_lib.t6g(sch_1):page86_i5@pure_quanta.q_res(chips)"
			("LOCATION" "R2415")
		)
		("@t6g_mb_lib.t6g(sch_1):page86_i37@pure_quanta.q_res(chips)"
			("LOCATION" "R2461")
		)
		("@t6g_mb_lib.t6g(sch_1):page86_i18@pure_quanta.q_res(chips)"
			("LOCATION" "R2462")
		)
		("@t6g_mb_lib.t6g(sch_1):page86_i30@pure_quanta.q_res(chips)"
			("LOCATION" "R2463")
		)
		("@t6g_mb_lib.t6g(sch_1):page86_i48@pure_quanta.q_res(chips)"
			("LOCATION" "R2464")
		)
		("@t6g_mb_lib.t6g(sch_1):page86_i39@pure_quanta.q_res(chips)"
			("LOCATION" "R2851")
		)
		("@t6g_mb_lib.t6g(sch_1):page86_i24@pure_quanta.q_res(chips)"
			("LOCATION" "R2852")
		)
		("@t6g_mb_lib.t6g(sch_1):page86_i61@pure_quanta.q_res(chips)"
			("LOCATION" "R2855")
		)
		("@t6g_mb_lib.t6g(sch_1):page86_i52@pure_quanta.q_res(chips)"
			("LOCATION" "R2856")
		)
		("@t6g_mb_lib.t6g(sch_1):page86_i56@pure_quanta.q_res(chips)"
			("LOCATION" "R2857")
		)
		("@t6g_mb_lib.t6g(sch_1):page86_i70@pure_quanta.q_res(chips)"
			("LOCATION" "R2858")
		)
		("@t6g_mb_lib.t6g(sch_1):page87_i63@pure_quanta.q_cap(chips)"
			("LOCATION" "C1584")
		)
		("@t6g_mb_lib.t6g(sch_1):page87_i9@pure_quanta.q_cap(chips)"
			("LOCATION" "C1974")
		)
		("@t6g_mb_lib.t6g(sch_1):page87_i4@pure_quanta.q_cap(chips)"
			("LOCATION" "C1975")
		)
		("@t6g_mb_lib.t6g(sch_1):page87_i28@pure_quanta.q_cap(chips)"
			("LOCATION" "C1976")
		)
		("@t6g_mb_lib.t6g(sch_1):page87_i46@pure_quanta.q_cap(chips)"
			("LOCATION" "C1977")
		)
		("@t6g_mb_lib.t6g(sch_1):page87_i21@pure_quanta.q_cap(chips)"
			("LOCATION" "C1978")
		)
		("@t6g_mb_lib.t6g(sch_1):page87_i37@pure_quanta.q_cap(chips)"
			("LOCATION" "C1979")
		)
		("@t6g_mb_lib.t6g(sch_1):page87_i71@pure_quanta.q_cap(chips)"
			("LOCATION" "C1980")
		)
		("@t6g_mb_lib.t6g(sch_1):page87_i83@pure_quanta.mosfet_nch_dual(chips)"
			("LOCATION" "Q35")
		)
		("@t6g_mb_lib.t6g(sch_1):page87_i84@pure_quanta.mosfet_nch_dual(chips)"
			("LOCATION" "Q35")
		)
		("@t6g_mb_lib.t6g(sch_1):page87_i79@pure_quanta.mosfet_nch_dual(chips)"
			("LOCATION" "Q36")
		)
		("@t6g_mb_lib.t6g(sch_1):page87_i80@pure_quanta.mosfet_nch_dual(chips)"
			("LOCATION" "Q36")
		)
		("@t6g_mb_lib.t6g(sch_1):page87_i77@pure_quanta.mosfet_nch_dual(chips)"
			("LOCATION" "Q37")
		)
		("@t6g_mb_lib.t6g(sch_1):page87_i78@pure_quanta.mosfet_nch_dual(chips)"
			("LOCATION" "Q37")
		)
		("@t6g_mb_lib.t6g(sch_1):page87_i81@pure_quanta.mosfet_nch_dual(chips)"
			("LOCATION" "Q38")
		)
		("@t6g_mb_lib.t6g(sch_1):page87_i82@pure_quanta.mosfet_nch_dual(chips)"
			("LOCATION" "Q38")
		)
		("@t6g_mb_lib.t6g(sch_1):page87_i11@pure_quanta.q_res(chips)"
			("LOCATION" "R2287")
		)
		("@t6g_mb_lib.t6g(sch_1):page87_i5@pure_quanta.q_res(chips)"
			("LOCATION" "R2289")
		)
		("@t6g_mb_lib.t6g(sch_1):page87_i32@pure_quanta.q_res(chips)"
			("LOCATION" "R2290")
		)
		("@t6g_mb_lib.t6g(sch_1):page87_i33@pure_quanta.q_res(chips)"
			("LOCATION" "R2291")
		)
		("@t6g_mb_lib.t6g(sch_1):page87_i48@pure_quanta.q_res(chips)"
			("LOCATION" "R2292")
		)
		("@t6g_mb_lib.t6g(sch_1):page87_i23@pure_quanta.q_res(chips)"
			("LOCATION" "R2295")
		)
		("@t6g_mb_lib.t6g(sch_1):page87_i62@pure_quanta.q_res(chips)"
			("LOCATION" "R2296")
		)
		("@t6g_mb_lib.t6g(sch_1):page87_i70@pure_quanta.q_res(chips)"
			("LOCATION" "R2297")
		)
		("@t6g_mb_lib.t6g(sch_1):page87_i13@pure_quanta.q_res(chips)"
			("LOCATION" "R2369")
		)
		("@t6g_mb_lib.t6g(sch_1):page87_i6@pure_quanta.q_res(chips)"
			("LOCATION" "R2370")
		)
		("@t6g_mb_lib.t6g(sch_1):page87_i24@pure_quanta.q_res(chips)"
			("LOCATION" "R2371")
		)
		("@t6g_mb_lib.t6g(sch_1):page87_i14@pure_quanta.q_res(chips)"
			("LOCATION" "R2413")
		)
		("@t6g_mb_lib.t6g(sch_1):page87_i18@pure_quanta.q_res(chips)"
			("LOCATION" "R2417")
		)
		("@t6g_mb_lib.t6g(sch_1):page87_i52@pure_quanta.q_res(chips)"
			("LOCATION" "R2420")
		)
		("@t6g_mb_lib.t6g(sch_1):page87_i7@pure_quanta.q_res(chips)"
			("LOCATION" "R2421")
		)
		("@t6g_mb_lib.t6g(sch_1):page87_i40@pure_quanta.q_res(chips)"
			("LOCATION" "R2422")
		)
		("@t6g_mb_lib.t6g(sch_1):page87_i25@pure_quanta.q_res(chips)"
			("LOCATION" "R2424")
		)
		("@t6g_mb_lib.t6g(sch_1):page87_i44@pure_quanta.q_res(chips)"
			("LOCATION" "R2425")
		)
		("@t6g_mb_lib.t6g(sch_1):page87_i41@pure_quanta.q_res(chips)"
			("LOCATION" "R2426")
		)
		("@t6g_mb_lib.t6g(sch_1):page87_i74@pure_quanta.q_res(chips)"
			("LOCATION" "R2430")
		)
		("@t6g_mb_lib.t6g(sch_1):page87_i58@pure_quanta.q_res(chips)"
			("LOCATION" "R2469")
		)
		("@t6g_mb_lib.t6g(sch_1):page87_i38@pure_quanta.q_res(chips)"
			("LOCATION" "R2472")
		)
		("@t6g_mb_lib.t6g(sch_1):page87_i64@pure_quanta.q_res(chips)"
			("LOCATION" "R2489")
		)
		("@t6g_mb_lib.t6g(sch_1):page87_i72@pure_quanta.q_res(chips)"
			("LOCATION" "R2490")
		)
		("@t6g_mb_lib.t6g(sch_1):page257_i42@pure_quanta.q_cap(chips)"
			("LOCATION" "C1686")
		)
		("@t6g_mb_lib.t6g(sch_1):page257_i13@pure_quanta.q_cap(chips)"
			("LOCATION" "C2820")
		)
		("@t6g_mb_lib.t6g(sch_1):page257_i32@pure_quanta.q_cap(chips)"
			("LOCATION" "C2821")
		)
		("@t6g_mb_lib.t6g(sch_1):page257_i10@pure_quanta.q_cap(chips)"
			("LOCATION" "C2822")
		)
		("@t6g_mb_lib.t6g(sch_1):page257_i29@pure_quanta.q_cap(chips)"
			("LOCATION" "C2823")
		)
		("@t6g_mb_lib.t6g(sch_1):page257_i55@pure_quanta.q_cap(chips)"
			("LOCATION" "C2924")
		)
		("@t6g_mb_lib.t6g(sch_1):page257_i18@pure_quanta.q_res(chips)"
			("LOCATION" "R3520")
		)
		("@t6g_mb_lib.t6g(sch_1):page257_i36@pure_quanta.q_res(chips)"
			("LOCATION" "R3521")
		)
		("@t6g_mb_lib.t6g(sch_1):page257_i16@pure_quanta.q_res(chips)"
			("LOCATION" "R3522")
		)
		("@t6g_mb_lib.t6g(sch_1):page257_i35@pure_quanta.q_res(chips)"
			("LOCATION" "R3523")
		)
		("@t6g_mb_lib.t6g(sch_1):page257_i15@pure_quanta.q_res(chips)"
			("LOCATION" "R3524")
		)
		("@t6g_mb_lib.t6g(sch_1):page257_i27@pure_quanta.q_res(chips)"
			("LOCATION" "R3525")
		)
		("@t6g_mb_lib.t6g(sch_1):page257_i7@pure_quanta.q_res(chips)"
			("LOCATION" "R3526")
		)
		("@t6g_mb_lib.t6g(sch_1):page257_i53@pure_quanta.q_res(chips)"
			("LOCATION" "R3766")
		)
		("@t6g_mb_lib.t6g(sch_1):page257_i20@pure_quanta.sw6s_tbegnqtr(chips)"
			("LOCATION" "SW7")
		)
		("@t6g_mb_lib.t6g(sch_1):page257_i37@pure_quanta.sw6s_tbegnqtr(chips)"
			("LOCATION" "SW8")
		)
		("@t6g_mb_lib.t6g(sch_1):page257_i8@pure_quanta.sn74lvc1g17dckr(chips)"
			("LOCATION" "U19")
		)
		("@t6g_mb_lib.t6g(sch_1):page257_i39@pure_quanta.\\74lvc1g07gw\\(chips)"
			("LOCATION" "U78")
		)
		("@t6g_mb_lib.t6g(sch_1):page257_i25@pure_quanta.sn74lvc1g17dckr(chips)"
			("LOCATION" "U192")
		)
		("@t6g_mb_lib.t6g(sch_1):page257_i47@pure_quanta.sn74lvc1g3157dckr(chips)"
			("LOCATION" "U196")
		)
		("@t6g_mb_lib.t6g(sch_1):page244_i171@pure_quanta.q_cap(chips)"
			("LOCATION" "C2417")
		)
		("@t6g_mb_lib.t6g(sch_1):page244_i170@pure_quanta.q_cap(chips)"
			("LOCATION" "C2418")
		)
		("@t6g_mb_lib.t6g(sch_1):page244_i65@pure_quanta.q_res(chips)"
			("LOCATION" "R139")
		)
		("@t6g_mb_lib.t6g(sch_1):page244_i66@pure_quanta.q_res(chips)"
			("LOCATION" "R140")
		)
		("@t6g_mb_lib.t6g(sch_1):page244_i67@pure_quanta.q_res(chips)"
			("LOCATION" "R141")
		)
		("@t6g_mb_lib.t6g(sch_1):page244_i94@pure_quanta.q_res(chips)"
			("LOCATION" "R393")
		)
		("@t6g_mb_lib.t6g(sch_1):page244_i101@pure_quanta.q_res(chips)"
			("LOCATION" "R397")
		)
		("@t6g_mb_lib.t6g(sch_1):page244_i117@pure_quanta.q_res(chips)"
			("LOCATION" "R921")
		)
		("@t6g_mb_lib.t6g(sch_1):page244_i118@pure_quanta.q_res(chips)"
			("LOCATION" "R922")
		)
		("@t6g_mb_lib.t6g(sch_1):page244_i14@pure_quanta.q_res(chips)"
			("LOCATION" "R1388")
		)
		("@t6g_mb_lib.t6g(sch_1):page244_i16@pure_quanta.q_res(chips)"
			("LOCATION" "R1389")
		)
		("@t6g_mb_lib.t6g(sch_1):page244_i138@pure_quanta.q_res(chips)"
			("LOCATION" "R1489")
		)
		("@t6g_mb_lib.t6g(sch_1):page244_i68@pure_quanta.q_res(chips)"
			("LOCATION" "R1741")
		)
		("@t6g_mb_lib.t6g(sch_1):page244_i95@pure_quanta.q_res(chips)"
			("LOCATION" "R1742")
		)
		("@t6g_mb_lib.t6g(sch_1):page244_i145@pure_quanta.q_res(chips)"
			("LOCATION" "R1790")
		)
		("@t6g_mb_lib.t6g(sch_1):page244_i147@pure_quanta.q_res(chips)"
			("LOCATION" "R1791")
		)
		("@t6g_mb_lib.t6g(sch_1):page244_i119@pure_quanta.q_res(chips)"
			("LOCATION" "R1792")
		)
		("@t6g_mb_lib.t6g(sch_1):page244_i120@pure_quanta.q_res(chips)"
			("LOCATION" "R1793")
		)
		("@t6g_mb_lib.t6g(sch_1):page244_i121@pure_quanta.q_res(chips)"
			("LOCATION" "R1794")
		)
		("@t6g_mb_lib.t6g(sch_1):page244_i136@pure_quanta.q_res(chips)"
			("LOCATION" "R1795")
		)
		("@t6g_mb_lib.t6g(sch_1):page244_i137@pure_quanta.q_res(chips)"
			("LOCATION" "R1796")
		)
		("@t6g_mb_lib.t6g(sch_1):page244_i139@pure_quanta.q_res(chips)"
			("LOCATION" "R1799")
		)
		("@t6g_mb_lib.t6g(sch_1):page244_i141@pure_quanta.q_res(chips)"
			("LOCATION" "R1800")
		)
		("@t6g_mb_lib.t6g(sch_1):page244_i140@pure_quanta.q_res(chips)"
			("LOCATION" "R1802")
		)
		("@t6g_mb_lib.t6g(sch_1):page244_i142@pure_quanta.q_res(chips)"
			("LOCATION" "R1803")
		)
		("@t6g_mb_lib.t6g(sch_1):page244_i143@pure_quanta.q_res(chips)"
			("LOCATION" "R1804")
		)
		("@t6g_mb_lib.t6g(sch_1):page244_i144@pure_quanta.q_res(chips)"
			("LOCATION" "R1805")
		)
		("@t6g_mb_lib.t6g(sch_1):page244_i49@pure_quanta.q_res(chips)"
			("LOCATION" "R1807")
		)
		("@t6g_mb_lib.t6g(sch_1):page244_i50@pure_quanta.q_res(chips)"
			("LOCATION" "R1808")
		)
		("@t6g_mb_lib.t6g(sch_1):page244_i52@pure_quanta.q_res(chips)"
			("LOCATION" "R1811")
		)
		("@t6g_mb_lib.t6g(sch_1):page244_i51@pure_quanta.q_res(chips)"
			("LOCATION" "R1825")
		)
		("@t6g_mb_lib.t6g(sch_1):page244_i54@pure_quanta.q_res(chips)"
			("LOCATION" "R1834")
		)
		("@t6g_mb_lib.t6g(sch_1):page244_i53@pure_quanta.q_res(chips)"
			("LOCATION" "R1835")
		)
		("@t6g_mb_lib.t6g(sch_1):page244_i55@pure_quanta.q_res(chips)"
			("LOCATION" "R1836")
		)
		("@t6g_mb_lib.t6g(sch_1):page244_i56@pure_quanta.q_res(chips)"
			("LOCATION" "R1842")
		)
		("@t6g_mb_lib.t6g(sch_1):page244_i57@pure_quanta.q_res(chips)"
			("LOCATION" "R1843")
		)
		("@t6g_mb_lib.t6g(sch_1):page244_i58@pure_quanta.q_res(chips)"
			("LOCATION" "R1844")
		)
		("@t6g_mb_lib.t6g(sch_1):page244_i59@pure_quanta.q_res(chips)"
			("LOCATION" "R1846")
		)
		("@t6g_mb_lib.t6g(sch_1):page244_i60@pure_quanta.q_res(chips)"
			("LOCATION" "R1847")
		)
		("@t6g_mb_lib.t6g(sch_1):page244_i61@pure_quanta.q_res(chips)"
			("LOCATION" "R1848")
		)
		("@t6g_mb_lib.t6g(sch_1):page244_i62@pure_quanta.q_res(chips)"
			("LOCATION" "R1849")
		)
		("@t6g_mb_lib.t6g(sch_1):page244_i63@pure_quanta.q_res(chips)"
			("LOCATION" "R1851")
		)
		("@t6g_mb_lib.t6g(sch_1):page244_i69@pure_quanta.q_res(chips)"
			("LOCATION" "R1853")
		)
		("@t6g_mb_lib.t6g(sch_1):page244_i70@pure_quanta.q_res(chips)"
			("LOCATION" "R1858")
		)
		("@t6g_mb_lib.t6g(sch_1):page244_i71@pure_quanta.q_res(chips)"
			("LOCATION" "R1859")
		)
		("@t6g_mb_lib.t6g(sch_1):page244_i72@pure_quanta.q_res(chips)"
			("LOCATION" "R1860")
		)
		("@t6g_mb_lib.t6g(sch_1):page244_i73@pure_quanta.q_res(chips)"
			("LOCATION" "R1861")
		)
		("@t6g_mb_lib.t6g(sch_1):page244_i96@pure_quanta.q_res(chips)"
			("LOCATION" "R1862")
		)
		("@t6g_mb_lib.t6g(sch_1):page244_i97@pure_quanta.q_res(chips)"
			("LOCATION" "R1863")
		)
		("@t6g_mb_lib.t6g(sch_1):page244_i98@pure_quanta.q_res(chips)"
			("LOCATION" "R1864")
		)
		("@t6g_mb_lib.t6g(sch_1):page244_i99@pure_quanta.q_res(chips)"
			("LOCATION" "R1865")
		)
		("@t6g_mb_lib.t6g(sch_1):page244_i100@pure_quanta.q_res(chips)"
			("LOCATION" "R1866")
		)
		("@t6g_mb_lib.t6g(sch_1):page244_i103@pure_quanta.q_res(chips)"
			("LOCATION" "R1867")
		)
		("@t6g_mb_lib.t6g(sch_1):page244_i102@pure_quanta.q_res(chips)"
			("LOCATION" "R1868")
		)
		("@t6g_mb_lib.t6g(sch_1):page244_i104@pure_quanta.q_res(chips)"
			("LOCATION" "R1869")
		)
		("@t6g_mb_lib.t6g(sch_1):page244_i1@pure_quanta.q_res(chips)"
			("LOCATION" "R1870")
		)
		("@t6g_mb_lib.t6g(sch_1):page244_i2@pure_quanta.q_res(chips)"
			("LOCATION" "R1871")
		)
		("@t6g_mb_lib.t6g(sch_1):page244_i4@pure_quanta.q_res(chips)"
			("LOCATION" "R1872")
		)
		("@t6g_mb_lib.t6g(sch_1):page244_i3@pure_quanta.q_res(chips)"
			("LOCATION" "R1873")
		)
		("@t6g_mb_lib.t6g(sch_1):page244_i5@pure_quanta.q_res(chips)"
			("LOCATION" "R1874")
		)
		("@t6g_mb_lib.t6g(sch_1):page244_i6@pure_quanta.q_res(chips)"
			("LOCATION" "R1875")
		)
		("@t6g_mb_lib.t6g(sch_1):page244_i7@pure_quanta.q_res(chips)"
			("LOCATION" "R1876")
		)
		("@t6g_mb_lib.t6g(sch_1):page244_i9@pure_quanta.q_res(chips)"
			("LOCATION" "R1877")
		)
		("@t6g_mb_lib.t6g(sch_1):page244_i8@pure_quanta.q_res(chips)"
			("LOCATION" "R1878")
		)
		("@t6g_mb_lib.t6g(sch_1):page244_i11@pure_quanta.q_res(chips)"
			("LOCATION" "R1879")
		)
		("@t6g_mb_lib.t6g(sch_1):page244_i10@pure_quanta.q_res(chips)"
			("LOCATION" "R1880")
		)
		("@t6g_mb_lib.t6g(sch_1):page244_i12@pure_quanta.q_res(chips)"
			("LOCATION" "R1881")
		)
		("@t6g_mb_lib.t6g(sch_1):page244_i13@pure_quanta.q_res(chips)"
			("LOCATION" "R1882")
		)
		("@t6g_mb_lib.t6g(sch_1):page244_i15@pure_quanta.q_res(chips)"
			("LOCATION" "R1883")
		)
		("@t6g_mb_lib.t6g(sch_1):page244_i17@pure_quanta.q_res(chips)"
			("LOCATION" "R1884")
		)
		("@t6g_mb_lib.t6g(sch_1):page244_i18@pure_quanta.q_res(chips)"
			("LOCATION" "R1885")
		)
		("@t6g_mb_lib.t6g(sch_1):page244_i19@pure_quanta.q_res(chips)"
			("LOCATION" "R1886")
		)
		("@t6g_mb_lib.t6g(sch_1):page244_i20@pure_quanta.q_res(chips)"
			("LOCATION" "R1887")
		)
		("@t6g_mb_lib.t6g(sch_1):page244_i21@pure_quanta.q_res(chips)"
			("LOCATION" "R1888")
		)
		("@t6g_mb_lib.t6g(sch_1):page244_i22@pure_quanta.q_res(chips)"
			("LOCATION" "R1889")
		)
		("@t6g_mb_lib.t6g(sch_1):page244_i23@pure_quanta.q_res(chips)"
			("LOCATION" "R1890")
		)
		("@t6g_mb_lib.t6g(sch_1):page244_i75@pure_quanta.q_res(chips)"
			("LOCATION" "R1891")
		)
		("@t6g_mb_lib.t6g(sch_1):page244_i76@pure_quanta.q_res(chips)"
			("LOCATION" "R1892")
		)
		("@t6g_mb_lib.t6g(sch_1):page244_i77@pure_quanta.q_res(chips)"
			("LOCATION" "R1893")
		)
		("@t6g_mb_lib.t6g(sch_1):page244_i79@pure_quanta.q_res(chips)"
			("LOCATION" "R1894")
		)
		("@t6g_mb_lib.t6g(sch_1):page244_i78@pure_quanta.q_res(chips)"
			("LOCATION" "R1895")
		)
		("@t6g_mb_lib.t6g(sch_1):page244_i80@pure_quanta.q_res(chips)"
			("LOCATION" "R1896")
		)
		("@t6g_mb_lib.t6g(sch_1):page244_i81@pure_quanta.q_res(chips)"
			("LOCATION" "R1897")
		)
		("@t6g_mb_lib.t6g(sch_1):page244_i83@pure_quanta.q_res(chips)"
			("LOCATION" "R1898")
		)
		("@t6g_mb_lib.t6g(sch_1):page244_i82@pure_quanta.q_res(chips)"
			("LOCATION" "R1899")
		)
		("@t6g_mb_lib.t6g(sch_1):page195_i175@pure_quanta.q_cap(chips)"
			("LOCATION" "C2433")
		)
		("@t6g_mb_lib.t6g(sch_1):page195_i187@pure_quanta.q_cap(chips)"
			("LOCATION" "C2434")
		)
		("@t6g_mb_lib.t6g(sch_1):page195_i173@pure_quanta.q_cap(chips)"
			("LOCATION" "C2435")
		)
		("@t6g_mb_lib.t6g(sch_1):page195_i185@pure_quanta.q_cap(chips)"
			("LOCATION" "C2436")
		)
		("@t6g_mb_lib.t6g(sch_1):page195_i166@pure_quanta.q_res(chips)"
			("LOCATION" "R1208")
		)
		("@t6g_mb_lib.t6g(sch_1):page195_i193@pure_quanta.q_res(chips)"
			("LOCATION" "R1209")
		)
		("@t6g_mb_lib.t6g(sch_1):page195_i194@pure_quanta.q_res(chips)"
			("LOCATION" "R1210")
		)
		("@t6g_mb_lib.t6g(sch_1):page195_i195@pure_quanta.q_res(chips)"
			("LOCATION" "R1211")
		)
		("@t6g_mb_lib.t6g(sch_1):page195_i196@pure_quanta.q_res(chips)"
			("LOCATION" "R1212")
		)
		("@t6g_mb_lib.t6g(sch_1):page195_i197@pure_quanta.q_res(chips)"
			("LOCATION" "R1213")
		)
		("@t6g_mb_lib.t6g(sch_1):page195_i201@pure_quanta.q_res(chips)"
			("LOCATION" "R1214")
		)
		("@t6g_mb_lib.t6g(sch_1):page195_i177@pure_quanta.q_res(chips)"
			("LOCATION" "R1748")
		)
		("@t6g_mb_lib.t6g(sch_1):page195_i221@pure_quanta.q_res(chips)"
			("LOCATION" "R1749")
		)
		("@t6g_mb_lib.t6g(sch_1):page195_i220@pure_quanta.q_res(chips)"
			("LOCATION" "R1750")
		)
		("@t6g_mb_lib.t6g(sch_1):page195_i208@pure_quanta.q_res(chips)"
			("LOCATION" "R1931")
		)
		("@t6g_mb_lib.t6g(sch_1):page195_i210@pure_quanta.q_res(chips)"
			("LOCATION" "R1932")
		)
		("@t6g_mb_lib.t6g(sch_1):page195_i209@pure_quanta.q_res(chips)"
			("LOCATION" "R1933")
		)
		("@t6g_mb_lib.t6g(sch_1):page195_i211@pure_quanta.q_res(chips)"
			("LOCATION" "R1934")
		)
		("@t6g_mb_lib.t6g(sch_1):page195_i212@pure_quanta.q_res(chips)"
			("LOCATION" "R1935")
		)
		("@t6g_mb_lib.t6g(sch_1):page195_i205@pure_quanta.q_res(chips)"
			("LOCATION" "R1936")
		)
		("@t6g_mb_lib.t6g(sch_1):page195_i207@pure_quanta.q_res(chips)"
			("LOCATION" "R1937")
		)
		("@t6g_mb_lib.t6g(sch_1):page195_i165@pure_quanta.q_res(chips)"
			("LOCATION" "R1938")
		)
		("@t6g_mb_lib.t6g(sch_1):page195_i206@pure_quanta.q_res(chips)"
			("LOCATION" "R1939")
		)
		("@t6g_mb_lib.t6g(sch_1):page195_i199@pure_quanta.q_res(chips)"
			("LOCATION" "R1940")
		)
		("@t6g_mb_lib.t6g(sch_1):page195_i176@pure_quanta.q_res(chips)"
			("LOCATION" "R1941")
		)
		("@t6g_mb_lib.t6g(sch_1):page195_i189@pure_quanta.nc7sb3157(chips)"
			("LOCATION" "U60")
		)
		("@t6g_mb_lib.t6g(sch_1):page195_i191@pure_quanta.nc7sb3157(chips)"
			("LOCATION" "U174")
		)
		("@t6g_mb_lib.t6g(sch_1):page95_i104@pure_quanta.q_cap(chips)"
			("LOCATION" "C2442")
		)
		("@t6g_mb_lib.t6g(sch_1):page95_i122@pure_quanta.q_res(chips)"
			("LOCATION" "R159")
		)
		("@t6g_mb_lib.t6g(sch_1):page95_i123@pure_quanta.q_res(chips)"
			("LOCATION" "R160")
		)
		("@t6g_mb_lib.t6g(sch_1):page95_i124@pure_quanta.q_res(chips)"
			("LOCATION" "R161")
		)
		("@t6g_mb_lib.t6g(sch_1):page95_i125@pure_quanta.q_res(chips)"
			("LOCATION" "R162")
		)
		("@t6g_mb_lib.t6g(sch_1):page95_i126@pure_quanta.q_res(chips)"
			("LOCATION" "R163")
		)
		("@t6g_mb_lib.t6g(sch_1):page95_i127@pure_quanta.q_res(chips)"
			("LOCATION" "R164")
		)
		("@t6g_mb_lib.t6g(sch_1):page95_i128@pure_quanta.q_res(chips)"
			("LOCATION" "R165")
		)
		("@t6g_mb_lib.t6g(sch_1):page95_i133@pure_quanta.q_res(chips)"
			("LOCATION" "R166")
		)
		("@t6g_mb_lib.t6g(sch_1):page95_i135@pure_quanta.q_res(chips)"
			("LOCATION" "R168")
		)
		("@t6g_mb_lib.t6g(sch_1):page95_i137@pure_quanta.q_res(chips)"
			("LOCATION" "R171")
		)
		("@t6g_mb_lib.t6g(sch_1):page95_i118@pure_quanta.q_res(chips)"
			("LOCATION" "R173")
		)
		("@t6g_mb_lib.t6g(sch_1):page95_i119@pure_quanta.q_res(chips)"
			("LOCATION" "R174")
		)
		("@t6g_mb_lib.t6g(sch_1):page95_i93@pure_quanta.q_res(chips)"
			("LOCATION" "R175")
		)
		("@t6g_mb_lib.t6g(sch_1):page95_i92@pure_quanta.q_res(chips)"
			("LOCATION" "R176")
		)
		("@t6g_mb_lib.t6g(sch_1):page95_i94@pure_quanta.q_res(chips)"
			("LOCATION" "R177")
		)
		("@t6g_mb_lib.t6g(sch_1):page95_i97@pure_quanta.q_res(chips)"
			("LOCATION" "R178")
		)
		("@t6g_mb_lib.t6g(sch_1):page95_i98@pure_quanta.q_res(chips)"
			("LOCATION" "R179")
		)
		("@t6g_mb_lib.t6g(sch_1):page95_i99@pure_quanta.q_res(chips)"
			("LOCATION" "R180")
		)
		("@t6g_mb_lib.t6g(sch_1):page95_i101@pure_quanta.q_res(chips)"
			("LOCATION" "R181")
		)
		("@t6g_mb_lib.t6g(sch_1):page95_i100@pure_quanta.q_res(chips)"
			("LOCATION" "R182")
		)
		("@t6g_mb_lib.t6g(sch_1):page95_i141@pure_quanta.q_res(chips)"
			("LOCATION" "R183")
		)
		("@t6g_mb_lib.t6g(sch_1):page95_i115@pure_quanta.q_res(chips)"
			("LOCATION" "R184")
		)
		("@t6g_mb_lib.t6g(sch_1):page95_i143@pure_quanta.q_res(chips)"
			("LOCATION" "R185")
		)
		("@t6g_mb_lib.t6g(sch_1):page95_i117@pure_quanta.q_res(chips)"
			("LOCATION" "R186")
		)
		("@t6g_mb_lib.t6g(sch_1):page95_i134@pure_quanta.q_res(chips)"
			("LOCATION" "R2056")
		)
		("@t6g_mb_lib.t6g(sch_1):page95_i136@pure_quanta.q_res(chips)"
			("LOCATION" "R2063")
		)
		("@t6g_mb_lib.t6g(sch_1):page95_i106@pure_quanta.\\74lvc07apw\\(chips)"
			("LOCATION" "U5")
		)
		("@t6g_mb_lib.t6g(sch_1):page95_i108@pure_quanta.\\74lvc07apw\\(chips)"
			("LOCATION" "U5")
		)
		("@t6g_mb_lib.t6g(sch_1):page95_i107@pure_quanta.\\74lvc07apw\\(chips)"
			("LOCATION" "U5")
		)
		("@t6g_mb_lib.t6g(sch_1):page95_i109@pure_quanta.\\74lvc07apw\\(chips)"
			("LOCATION" "U5")
		)
		("@t6g_mb_lib.t6g(sch_1):page95_i120@pure_quanta.\\74lvc07apw\\(chips)"
			("LOCATION" "U5")
		)
		("@t6g_mb_lib.t6g(sch_1):page95_i121@pure_quanta.\\74lvc07apw\\(chips)"
			("LOCATION" "U5")
		)
		("@t6g_mb_lib.t6g(sch_1):page301_i20@pure_quanta.q_cap(chips)"
			("LOCATION" "C2443")
		)
		("@t6g_mb_lib.t6g(sch_1):page301_i24@pure_quanta.q_cap(chips)"
			("LOCATION" "C2444")
		)
		("@t6g_mb_lib.t6g(sch_1):page301_i45@pure_quanta.q_cap(chips)"
			("LOCATION" "PC626")
		)
		("@t6g_mb_lib.t6g(sch_1):page301_i48@pure_quanta.q_cap(chips)"
			("LOCATION" "PC628")
		)
		("@t6g_mb_lib.t6g(sch_1):page301_i65@pure_quanta.q_cap(chips)"
			("LOCATION" "PC629")
		)
		("@t6g_mb_lib.t6g(sch_1):page301_i66@pure_quanta.q_cap(chips)"
			("LOCATION" "PC632")
		)
		("@t6g_mb_lib.t6g(sch_1):page301_i64@pure_quanta.q_cap(chips)"
			("LOCATION" "PC1196")
		)
		("@t6g_mb_lib.t6g(sch_1):page301_i79@pure_quanta.q_short(chips)"
			("LOCATION" "PJ54")
		)
		("@t6g_mb_lib.t6g(sch_1):page301_i7@pure_quanta.q_res(chips)"
			("LOCATION" "PR357")
		)
		("@t6g_mb_lib.t6g(sch_1):page301_i43@pure_quanta.q_res(chips)"
			("LOCATION" "PR361")
		)
		("@t6g_mb_lib.t6g(sch_1):page301_i44@pure_quanta.q_res(chips)"
			("LOCATION" "PR362")
		)
		("@t6g_mb_lib.t6g(sch_1):page301_i40@pure_quanta.q_res(chips)"
			("LOCATION" "PR363")
		)
		("@t6g_mb_lib.t6g(sch_1):page301_i39@pure_quanta.q_res(chips)"
			("LOCATION" "PR364")
		)
		("@t6g_mb_lib.t6g(sch_1):page301_i37@pure_quanta.q_res(chips)"
			("LOCATION" "PR365")
		)
		("@t6g_mb_lib.t6g(sch_1):page301_i38@pure_quanta.q_res(chips)"
			("LOCATION" "PR366")
		)
		("@t6g_mb_lib.t6g(sch_1):page301_i35@pure_quanta.q_res(chips)"
			("LOCATION" "PR367")
		)
		("@t6g_mb_lib.t6g(sch_1):page301_i36@pure_quanta.q_res(chips)"
			("LOCATION" "PR368")
		)
		("@t6g_mb_lib.t6g(sch_1):page301_i15@pure_quanta.q_res(chips)"
			("LOCATION" "PR370")
		)
		("@t6g_mb_lib.t6g(sch_1):page301_i41@pure_quanta.q_res(chips)"
			("LOCATION" "PR371")
		)
		("@t6g_mb_lib.t6g(sch_1):page301_i17@pure_quanta.q_res(chips)"
			("LOCATION" "PR372")
		)
		("@t6g_mb_lib.t6g(sch_1):page301_i72@pure_quanta.q_res(chips)"
			("LOCATION" "PR375")
		)
		("@t6g_mb_lib.t6g(sch_1):page301_i60@pure_quanta.q_res(chips)"
			("LOCATION" "PR378")
		)
		("@t6g_mb_lib.t6g(sch_1):page301_i78@pure_quanta.q_res(chips)"
			("LOCATION" "PR591")
		)
		("@t6g_mb_lib.t6g(sch_1):page301_i33@pure_quanta.q_res(chips)"
			("LOCATION" "PR592")
		)
		("@t6g_mb_lib.t6g(sch_1):page301_i51@pure_quanta.isl69260irazt(chips)"
			("LOCATION" "PU35")
		)
		("@t6g_mb_lib.t6g(sch_1):page301_i26@pure_quanta.q_res(chips)"
			("LOCATION" "R1717")
		)
		("@t6g_mb_lib.t6g(sch_1):page301_i25@pure_quanta.q_res(chips)"
			("LOCATION" "R1735")
		)
		("@t6g_mb_lib.t6g(sch_1):page322_i11@pure_quanta.q_cap(chips)"
			("LOCATION" "C2445")
		)
		("@t6g_mb_lib.t6g(sch_1):page322_i39@pure_quanta.q_cap(chips)"
			("LOCATION" "C2446")
		)
		("@t6g_mb_lib.t6g(sch_1):page322_i7@pure_quanta.q_cap(chips)"
			("LOCATION" "PC644")
		)
		("@t6g_mb_lib.t6g(sch_1):page322_i4@pure_quanta.q_cap(chips)"
			("LOCATION" "PC1259")
		)
		("@t6g_mb_lib.t6g(sch_1):page322_i19@pure_quanta.q_cap(chips)"
			("LOCATION" "PC1260")
		)
		("@t6g_mb_lib.t6g(sch_1):page322_i20@pure_quanta.q_cap(chips)"
			("LOCATION" "PC1261")
		)
		("@t6g_mb_lib.t6g(sch_1):page322_i21@pure_quanta.q_cap(chips)"
			("LOCATION" "PC1262")
		)
		("@t6g_mb_lib.t6g(sch_1):page322_i17@pure_quanta.q_cap(chips)"
			("LOCATION" "PC1264")
		)
		("@t6g_mb_lib.t6g(sch_1):page322_i22@pure_quanta.q_cap(chips)"
			("LOCATION" "PC1265")
		)
		("@t6g_mb_lib.t6g(sch_1):page322_i28@pure_quanta.q_cap(chips)"
			("LOCATION" "PC1266")
		)
		("@t6g_mb_lib.t6g(sch_1):page322_i30@pure_quanta.q_cap(chips)"
			("LOCATION" "PC1267")
		)
		("@t6g_mb_lib.t6g(sch_1):page322_i31@pure_quanta.q_cap(chips)"
			("LOCATION" "PC1268")
		)
		("@t6g_mb_lib.t6g(sch_1):page322_i32@pure_quanta.q_cap(chips)"
			("LOCATION" "PC1269")
		)
		("@t6g_mb_lib.t6g(sch_1):page322_i35@pure_quanta.q_cap(chips)"
			("LOCATION" "PC1270")
		)
		("@t6g_mb_lib.t6g(sch_1):page322_i36@pure_quanta.q_capp(chips)"
			("LOCATION" "PC1771")
		)
		("@t6g_mb_lib.t6g(sch_1):page322_i41@pure_quanta.q_inductor(chips)"
			("LOCATION" "PL119")
		)
		("@t6g_mb_lib.t6g(sch_1):page322_i23@pure_quanta.q_res(chips)"
			("LOCATION" "PR1313")
		)
		("@t6g_mb_lib.t6g(sch_1):page322_i26@pure_quanta.q_res(chips)"
			("LOCATION" "PR1314")
		)
		("@t6g_mb_lib.t6g(sch_1):page322_i8@pure_quanta.q_res(chips)"
			("LOCATION" "PR1338")
		)
		("@t6g_mb_lib.t6g(sch_1):page322_i14@pure_quanta.q_res(chips)"
			("LOCATION" "PR1339")
		)
		("@t6g_mb_lib.t6g(sch_1):page322_i29@pure_quanta.q_res(chips)"
			("LOCATION" "PR1340")
		)
		("@t6g_mb_lib.t6g(sch_1):page322_i15@pure_quanta.mpq8633aglec807z(chips)"
			("LOCATION" "PU80")
		)
		("@t6g_mb_lib.t6g(sch_1):page322_i18@pure_quanta.q_res(chips)"
			("LOCATION" "R2367")
		)
		("@t6g_mb_lib.t6g(sch_1):page322_i12@pure_quanta.q_res(chips)"
			("LOCATION" "R2374")
		)
		("@t6g_mb_lib.t6g(sch_1):page322_i40@pure_quanta.q_res(chips)"
			("LOCATION" "R2380")
		)
		("@t6g_mb_lib.t6g(sch_1):page322_i27@pure_quanta.q_res(chips)"
			("LOCATION" "R2381")
		)
		("@t6g_mb_lib.t6g(sch_1):page322_i34@pure_quanta.mosfet_n(chips)"
			("LOCATION" "U74")
		)
		("@t6g_mb_lib.t6g(sch_1):page96_i16@pure_quanta.q_cap(chips)"
			("LOCATION" "C2447")
		)
		("@t6g_mb_lib.t6g(sch_1):page96_i27@pure_quanta.q_res(chips)"
			("LOCATION" "R121")
		)
		("@t6g_mb_lib.t6g(sch_1):page96_i28@pure_quanta.q_res(chips)"
			("LOCATION" "R122")
		)
		("@t6g_mb_lib.t6g(sch_1):page96_i29@pure_quanta.q_res(chips)"
			("LOCATION" "R123")
		)
		("@t6g_mb_lib.t6g(sch_1):page96_i30@pure_quanta.q_res(chips)"
			("LOCATION" "R124")
		)
		("@t6g_mb_lib.t6g(sch_1):page96_i31@pure_quanta.q_res(chips)"
			("LOCATION" "R125")
		)
		("@t6g_mb_lib.t6g(sch_1):page96_i32@pure_quanta.q_res(chips)"
			("LOCATION" "R126")
		)
		("@t6g_mb_lib.t6g(sch_1):page96_i33@pure_quanta.q_res(chips)"
			("LOCATION" "R127")
		)
		("@t6g_mb_lib.t6g(sch_1):page96_i34@pure_quanta.q_res(chips)"
			("LOCATION" "R128")
		)
		("@t6g_mb_lib.t6g(sch_1):page96_i49@pure_quanta.q_res(chips)"
			("LOCATION" "R129")
		)
		("@t6g_mb_lib.t6g(sch_1):page96_i50@pure_quanta.q_res(chips)"
			("LOCATION" "R130")
		)
		("@t6g_mb_lib.t6g(sch_1):page96_i52@pure_quanta.q_res(chips)"
			("LOCATION" "R132")
		)
		("@t6g_mb_lib.t6g(sch_1):page96_i45@pure_quanta.q_res(chips)"
			("LOCATION" "R133")
		)
		("@t6g_mb_lib.t6g(sch_1):page96_i46@pure_quanta.q_res(chips)"
			("LOCATION" "R134")
		)
		("@t6g_mb_lib.t6g(sch_1):page96_i11@pure_quanta.q_res(chips)"
			("LOCATION" "R135")
		)
		("@t6g_mb_lib.t6g(sch_1):page96_i12@pure_quanta.q_res(chips)"
			("LOCATION" "R136")
		)
		("@t6g_mb_lib.t6g(sch_1):page96_i14@pure_quanta.q_res(chips)"
			("LOCATION" "R150")
		)
		("@t6g_mb_lib.t6g(sch_1):page96_i21@pure_quanta.q_res(chips)"
			("LOCATION" "R151")
		)
		("@t6g_mb_lib.t6g(sch_1):page96_i22@pure_quanta.q_res(chips)"
			("LOCATION" "R152")
		)
		("@t6g_mb_lib.t6g(sch_1):page96_i23@pure_quanta.q_res(chips)"
			("LOCATION" "R153")
		)
		("@t6g_mb_lib.t6g(sch_1):page96_i24@pure_quanta.q_res(chips)"
			("LOCATION" "R154")
		)
		("@t6g_mb_lib.t6g(sch_1):page96_i56@pure_quanta.q_res(chips)"
			("LOCATION" "R155")
		)
		("@t6g_mb_lib.t6g(sch_1):page96_i42@pure_quanta.q_res(chips)"
			("LOCATION" "R156")
		)
		("@t6g_mb_lib.t6g(sch_1):page96_i58@pure_quanta.q_res(chips)"
			("LOCATION" "R157")
		)
		("@t6g_mb_lib.t6g(sch_1):page96_i44@pure_quanta.q_res(chips)"
			("LOCATION" "R158")
		)
		("@t6g_mb_lib.t6g(sch_1):page96_i51@pure_quanta.q_res(chips)"
			("LOCATION" "R2444")
		)
		("@t6g_mb_lib.t6g(sch_1):page96_i13@pure_quanta.q_res(chips)"
			("LOCATION" "R2452")
		)
		("@t6g_mb_lib.t6g(sch_1):page96_i18@pure_quanta.\\74lvc07apw\\(chips)"
			("LOCATION" "U6")
		)
		("@t6g_mb_lib.t6g(sch_1):page96_i20@pure_quanta.\\74lvc07apw\\(chips)"
			("LOCATION" "U6")
		)
		("@t6g_mb_lib.t6g(sch_1):page96_i25@pure_quanta.\\74lvc07apw\\(chips)"
			("LOCATION" "U6")
		)
		("@t6g_mb_lib.t6g(sch_1):page96_i26@pure_quanta.\\74lvc07apw\\(chips)"
			("LOCATION" "U6")
		)
		("@t6g_mb_lib.t6g(sch_1):page96_i47@pure_quanta.\\74lvc07apw\\(chips)"
			("LOCATION" "U6")
		)
		("@t6g_mb_lib.t6g(sch_1):page96_i48@pure_quanta.\\74lvc07apw\\(chips)"
			("LOCATION" "U6")
		)
		("@t6g_mb_lib.t6g(sch_1):page213_i41@pure_quanta.q_cap(chips)"
			("LOCATION" "C2460")
		)
		("@t6g_mb_lib.t6g(sch_1):page213_i103@pure_quanta.q_cap(chips)"
			("LOCATION" "C2461")
		)
		("@t6g_mb_lib.t6g(sch_1):page213_i113@pure_quanta.q_cap(chips)"
			("LOCATION" "C2462")
		)
		("@t6g_mb_lib.t6g(sch_1):page213_i112@pure_quanta.q_cap(chips)"
			("LOCATION" "C2463")
		)
		("@t6g_mb_lib.t6g(sch_1):page213_i127@pure_quanta.q_cap(chips)"
			("LOCATION" "C2464")
		)
		("@t6g_mb_lib.t6g(sch_1):page213_i124@pure_quanta.q_cap(chips)"
			("LOCATION" "C2465")
		)
		("@t6g_mb_lib.t6g(sch_1):page213_i23@pure_quanta.q_cap(chips)"
			("LOCATION" "C2466")
		)
		("@t6g_mb_lib.t6g(sch_1):page213_i100@pure_quanta.q_cap(chips)"
			("LOCATION" "C2467")
		)
		("@t6g_mb_lib.t6g(sch_1):page213_i22@pure_quanta.q_cap(chips)"
			("LOCATION" "C2468")
		)
		("@t6g_mb_lib.t6g(sch_1):page213_i116@pure_quanta.q_cap(chips)"
			("LOCATION" "C2472")
		)
		("@t6g_mb_lib.t6g(sch_1):page213_i115@pure_quanta.q_cap(chips)"
			("LOCATION" "C2473")
		)
		("@t6g_mb_lib.t6g(sch_1):page213_i38@pure_quanta.q_cap(chips)"
			("LOCATION" "C2474")
		)
		("@t6g_mb_lib.t6g(sch_1):page213_i102@pure_quanta.q_cap(chips)"
			("LOCATION" "C2475")
		)
		("@t6g_mb_lib.t6g(sch_1):page213_i90@pure_quanta.q_cap(chips)"
			("LOCATION" "C2476")
		)
		("@t6g_mb_lib.t6g(sch_1):page213_i95@pure_quanta.q_cap(chips)"
			("LOCATION" "C2477")
		)
		("@t6g_mb_lib.t6g(sch_1):page213_i121@pure_quanta.q_cap(chips)"
			("LOCATION" "C2478")
		)
		("@t6g_mb_lib.t6g(sch_1):page213_i91@pure_quanta.q_cap(chips)"
			("LOCATION" "C2479")
		)
		("@t6g_mb_lib.t6g(sch_1):page213_i94@pure_quanta.q_cap(chips)"
			("LOCATION" "C2480")
		)
		("@t6g_mb_lib.t6g(sch_1):page213_i120@pure_quanta.q_cap(chips)"
			("LOCATION" "C2481")
		)
		("@t6g_mb_lib.t6g(sch_1):page213_i128@pure_quanta.q_inductor(chips)"
			("LOCATION" "L98")
		)
		("@t6g_mb_lib.t6g(sch_1):page213_i129@pure_quanta.q_inductor(chips)"
			("LOCATION" "L99")
		)
		("@t6g_mb_lib.t6g(sch_1):page213_i130@pure_quanta.q_inductor(chips)"
			("LOCATION" "L100")
		)
		("@t6g_mb_lib.t6g(sch_1):page213_i67@pure_quanta.q_res(chips)"
			("LOCATION" "R390")
		)
		("@t6g_mb_lib.t6g(sch_1):page213_i97@pure_quanta.q_res(chips)"
			("LOCATION" "R391")
		)
		("@t6g_mb_lib.t6g(sch_1):page213_i122@pure_quanta.q_res(chips)"
			("LOCATION" "R392")
		)
		("@t6g_mb_lib.t6g(sch_1):page151_i30@pure_quanta.q_cap(chips)"
			("LOCATION" "C2511")
		)
		("@t6g_mb_lib.t6g(sch_1):page151_i38@pure_quanta.q_cap(chips)"
			("LOCATION" "C2512")
		)
		("@t6g_mb_lib.t6g(sch_1):page151_i61@pure_quanta.q_cap(chips)"
			("LOCATION" "C2513")
		)
		("@t6g_mb_lib.t6g(sch_1):page151_i58@pure_quanta.q_cap(chips)"
			("LOCATION" "C2514")
		)
		("@t6g_mb_lib.t6g(sch_1):page151_i63@pure_quanta.q_cap(chips)"
			("LOCATION" "C2515")
		)
		("@t6g_mb_lib.t6g(sch_1):page151_i60@pure_quanta.q_cap(chips)"
			("LOCATION" "C2516")
		)
		("@t6g_mb_lib.t6g(sch_1):page151_i67@pure_quanta.q_cap(chips)"
			("LOCATION" "C2517")
		)
		("@t6g_mb_lib.t6g(sch_1):page151_i130@pure_quanta.q_cap(chips)"
			("LOCATION" "C2891")
		)
		("@t6g_mb_lib.t6g(sch_1):page151_i20@pure_quanta.q_diode(chips)"
			("LOCATION" "D37")
		)
		("@t6g_mb_lib.t6g(sch_1):page151_i19@pure_quanta.q_diode(chips)"
			("LOCATION" "D38")
		)
		("@t6g_mb_lib.t6g(sch_1):page151_i18@pure_quanta.q_diode(chips)"
			("LOCATION" "D39")
		)
		("@t6g_mb_lib.t6g(sch_1):page151_i17@pure_quanta.q_diode(chips)"
			("LOCATION" "D40")
		)
		("@t6g_mb_lib.t6g(sch_1):page151_i31@pure_quanta.q_diode(chips)"
			("LOCATION" "D42")
		)
		("@t6g_mb_lib.t6g(sch_1):page151_i43@pure_quanta.mosfet_nch_dual(chips)"
			("LOCATION" "Q67")
		)
		("@t6g_mb_lib.t6g(sch_1):page151_i44@pure_quanta.mosfet_nch_dual(chips)"
			("LOCATION" "Q67")
		)
		("@t6g_mb_lib.t6g(sch_1):page151_i41@pure_quanta.mosfet_nch_dual(chips)"
			("LOCATION" "Q82")
		)
		("@t6g_mb_lib.t6g(sch_1):page151_i40@pure_quanta.mosfet_nch_dual(chips)"
			("LOCATION" "Q82")
		)
		("@t6g_mb_lib.t6g(sch_1):page151_i89@pure_quanta.mosfet_nch_dual(chips)"
			("LOCATION" "Q83")
		)
		("@t6g_mb_lib.t6g(sch_1):page151_i93@pure_quanta.mosfet_nch_dual(chips)"
			("LOCATION" "Q83")
		)
		("@t6g_mb_lib.t6g(sch_1):page151_i45@pure_quanta.q_res(chips)"
			("LOCATION" "R402")
		)
		("@t6g_mb_lib.t6g(sch_1):page151_i26@pure_quanta.q_res(chips)"
			("LOCATION" "R404")
		)
		("@t6g_mb_lib.t6g(sch_1):page151_i23@pure_quanta.q_res(chips)"
			("LOCATION" "R406")
		)
		("@t6g_mb_lib.t6g(sch_1):page151_i24@pure_quanta.q_res(chips)"
			("LOCATION" "R407")
		)
		("@t6g_mb_lib.t6g(sch_1):page151_i16@pure_quanta.q_res(chips)"
			("LOCATION" "R408")
		)
		("@t6g_mb_lib.t6g(sch_1):page151_i54@pure_quanta.q_res(chips)"
			("LOCATION" "R409")
		)
		("@t6g_mb_lib.t6g(sch_1):page151_i53@pure_quanta.q_res(chips)"
			("LOCATION" "R410")
		)
		("@t6g_mb_lib.t6g(sch_1):page151_i76@pure_quanta.q_res(chips)"
			("LOCATION" "R411")
		)
		("@t6g_mb_lib.t6g(sch_1):page151_i90@pure_quanta.q_res(chips)"
			("LOCATION" "R412")
		)
		("@t6g_mb_lib.t6g(sch_1):page151_i79@pure_quanta.q_res(chips)"
			("LOCATION" "R413")
		)
		("@t6g_mb_lib.t6g(sch_1):page151_i78@pure_quanta.q_res(chips)"
			("LOCATION" "R414")
		)
		("@t6g_mb_lib.t6g(sch_1):page151_i75@pure_quanta.q_res(chips)"
			("LOCATION" "R415")
		)
		("@t6g_mb_lib.t6g(sch_1):page151_i74@pure_quanta.q_res(chips)"
			("LOCATION" "R416")
		)
		("@t6g_mb_lib.t6g(sch_1):page151_i70@pure_quanta.q_res(chips)"
			("LOCATION" "R419")
		)
		("@t6g_mb_lib.t6g(sch_1):page151_i102@pure_quanta.q_res(chips)"
			("LOCATION" "R431")
		)
		("@t6g_mb_lib.t6g(sch_1):page151_i72@pure_quanta.q_res(chips)"
			("LOCATION" "R1240")
		)
		("@t6g_mb_lib.t6g(sch_1):page151_i69@pure_quanta.q_res(chips)"
			("LOCATION" "R1245")
		)
		("@t6g_mb_lib.t6g(sch_1):page151_i68@pure_quanta.q_res(chips)"
			("LOCATION" "R1248")
		)
		("@t6g_mb_lib.t6g(sch_1):page151_i95@pure_quanta.q_res(chips)"
			("LOCATION" "R1250")
		)
		("@t6g_mb_lib.t6g(sch_1):page151_i97@pure_quanta.q_res(chips)"
			("LOCATION" "R1251")
		)
		("@t6g_mb_lib.t6g(sch_1):page151_i100@pure_quanta.q_res(chips)"
			("LOCATION" "R1252")
		)
		("@t6g_mb_lib.t6g(sch_1):page151_i123@pure_quanta.q_res(chips)"
			("LOCATION" "R1914")
		)
		("@t6g_mb_lib.t6g(sch_1):page151_i125@pure_quanta.q_res(chips)"
			("LOCATION" "R1916")
		)
		("@t6g_mb_lib.t6g(sch_1):page151_i121@pure_quanta.q_res(chips)"
			("LOCATION" "R2776")
		)
		("@t6g_mb_lib.t6g(sch_1):page151_i124@pure_quanta.q_res(chips)"
			("LOCATION" "R2778")
		)
		("@t6g_mb_lib.t6g(sch_1):page151_i129@pure_quanta.q_res(chips)"
			("LOCATION" "R3611")
		)
		("@t6g_mb_lib.t6g(sch_1):page151_i34@pure_quanta.sn74lvc1g17dckr(chips)"
			("LOCATION" "U93")
		)
		("@t6g_mb_lib.t6g(sch_1):page151_i36@pure_quanta.sn74lvc2g07dckr(chips)"
			("LOCATION" "U94")
		)
		("@t6g_mb_lib.t6g(sch_1):page151_i64@pure_quanta.tps3808g18dbvr(chips)"
			("LOCATION" "U95")
		)
		("@t6g_mb_lib.t6g(sch_1):page153_i6@pure_quanta.q_cap(chips)"
			("LOCATION" "C2521")
		)
		("@t6g_mb_lib.t6g(sch_1):page153_i26@pure_quanta.q_cap(chips)"
			("LOCATION" "C2522")
		)
		("@t6g_mb_lib.t6g(sch_1):page153_i23@pure_quanta.q_cap(chips)"
			("LOCATION" "C2523")
		)
		("@t6g_mb_lib.t6g(sch_1):page153_i4@pure_quanta.q_cap(chips)"
			("LOCATION" "C2524")
		)
		("@t6g_mb_lib.t6g(sch_1):page153_i31@pure_quanta.q_cap(chips)"
			("LOCATION" "C2525")
		)
		("@t6g_mb_lib.t6g(sch_1):page153_i15@pure_quanta.q_cap(chips)"
			("LOCATION" "C2526")
		)
		("@t6g_mb_lib.t6g(sch_1):page153_i20@pure_quanta.diode_tvs(chips)"
			("LOCATION" "D43")
		)
		("@t6g_mb_lib.t6g(sch_1):page153_i29@pure_quanta.schottky_ac(chips)"
			("LOCATION" "D44")
		)
		("@t6g_mb_lib.t6g(sch_1):page153_i9@pure_quanta.q_short(chips)"
			("LOCATION" "J213")
		)
		("@t6g_mb_lib.t6g(sch_1):page153_i8@pure_quanta.q_short(chips)"
			("LOCATION" "J214")
		)
		("@t6g_mb_lib.t6g(sch_1):page153_i10@pure_quanta.q_res(chips)"
			("LOCATION" "R1273")
		)
		("@t6g_mb_lib.t6g(sch_1):page153_i34@pure_quanta.q_res(chips)"
			("LOCATION" "R1274")
		)
		("@t6g_mb_lib.t6g(sch_1):page153_i18@pure_quanta.q_res(chips)"
			("LOCATION" "R1275")
		)
		("@t6g_mb_lib.t6g(sch_1):page153_i27@pure_quanta.tps259541dsgr(chips)"
			("LOCATION" "U99")
		)
		("@t6g_mb_lib.t6g(sch_1):page153_i13@pure_quanta.tps259521dsgr(chips)"
			("LOCATION" "U100")
		)
		("@t6g_mb_lib.t6g(sch_1):page272_i15@pure_quanta.q_cap(chips)"
			("LOCATION" "C2534")
		)
		("@t6g_mb_lib.t6g(sch_1):page272_i38@pure_quanta.q_cap(chips)"
			("LOCATION" "C2535")
		)
		("@t6g_mb_lib.t6g(sch_1):page272_i35@pure_quanta.q_cap(chips)"
			("LOCATION" "C2536")
		)
		("@t6g_mb_lib.t6g(sch_1):page272_i62@pure_quanta.conn3_210hp1030br1(chips)"
			("LOCATION" "JP30")
		)
		("@t6g_mb_lib.t6g(sch_1):page272_i18@pure_quanta.q_res(chips)"
			("LOCATION" "R460")
		)
		("@t6g_mb_lib.t6g(sch_1):page272_i3@pure_quanta.q_res(chips)"
			("LOCATION" "R475")
		)
		("@t6g_mb_lib.t6g(sch_1):page272_i42@pure_quanta.q_res(chips)"
			("LOCATION" "R711")
		)
		("@t6g_mb_lib.t6g(sch_1):page272_i41@pure_quanta.q_res(chips)"
			("LOCATION" "R712")
		)
		("@t6g_mb_lib.t6g(sch_1):page272_i24@pure_quanta.q_res(chips)"
			("LOCATION" "R714")
		)
		("@t6g_mb_lib.t6g(sch_1):page272_i56@pure_quanta.q_res(chips)"
			("LOCATION" "R719")
		)
		("@t6g_mb_lib.t6g(sch_1):page272_i44@pure_quanta.q_res(chips)"
			("LOCATION" "R721")
		)
		("@t6g_mb_lib.t6g(sch_1):page272_i12@pure_quanta.q_res(chips)"
			("LOCATION" "R725")
		)
		("@t6g_mb_lib.t6g(sch_1):page272_i13@pure_quanta.q_res(chips)"
			("LOCATION" "R726")
		)
		("@t6g_mb_lib.t6g(sch_1):page272_i33@pure_quanta.q_res(chips)"
			("LOCATION" "R729")
		)
		("@t6g_mb_lib.t6g(sch_1):page272_i50@pure_quanta.q_res(chips)"
			("LOCATION" "R732")
		)
		("@t6g_mb_lib.t6g(sch_1):page272_i4@pure_quanta.q_res(chips)"
			("LOCATION" "R1302")
		)
		("@t6g_mb_lib.t6g(sch_1):page272_i6@pure_quanta.q_res(chips)"
			("LOCATION" "R1303")
		)
		("@t6g_mb_lib.t6g(sch_1):page272_i34@pure_quanta.q_res(chips)"
			("LOCATION" "R1304")
		)
		("@t6g_mb_lib.t6g(sch_1):page272_i30@pure_quanta.q_res(chips)"
			("LOCATION" "R1305")
		)
		("@t6g_mb_lib.t6g(sch_1):page272_i49@pure_quanta.q_res(chips)"
			("LOCATION" "R1308")
		)
		("@t6g_mb_lib.t6g(sch_1):page272_i27@pure_quanta.q_res(chips)"
			("LOCATION" "R1311")
		)
		("@t6g_mb_lib.t6g(sch_1):page272_i54@pure_quanta.q_res(chips)"
			("LOCATION" "R1312")
		)
		("@t6g_mb_lib.t6g(sch_1):page272_i28@pure_quanta.q_res(chips)"
			("LOCATION" "R1314")
		)
		("@t6g_mb_lib.t6g(sch_1):page272_i19@pure_quanta.q_res(chips)"
			("LOCATION" "R2853")
		)
		("@t6g_mb_lib.t6g(sch_1):page272_i55@pure_quanta.q_res(chips)"
			("LOCATION" "R2854")
		)
		("@t6g_mb_lib.t6g(sch_1):page272_i52@pure_quanta.q_res(chips)"
			("LOCATION" "R2859")
		)
		("@t6g_mb_lib.t6g(sch_1):page272_i46@pure_quanta.q_res(chips)"
			("LOCATION" "R2868")
		)
		("@t6g_mb_lib.t6g(sch_1):page272_i43@pure_quanta.q_res(chips)"
			("LOCATION" "R2880")
		)
		("@t6g_mb_lib.t6g(sch_1):page272_i48@pure_quanta.q_res(chips)"
			("LOCATION" "R2883")
		)
		("@t6g_mb_lib.t6g(sch_1):page272_i59@pure_quanta.tmp75aidr(chips)"
			("LOCATION" "U114")
		)
		("@t6g_mb_lib.t6g(sch_1):page272_i21@pure_quanta.tmp75aidr(chips)"
			("LOCATION" "U163")
		)
		("@t6g_mb_lib.t6g(sch_1):page272_i60@pure_quanta.m24128bwmn6tpa(chips)"
			("LOCATION" "U173")
		)
		("@t6g_mb_lib.t6g(sch_1):page266_i36@pure_quanta.q_cap(chips)"
			("LOCATION" "C2578")
		)
		("@t6g_mb_lib.t6g(sch_1):page266_i30@pure_quanta.q_cap(chips)"
			("LOCATION" "C2581")
		)
		("@t6g_mb_lib.t6g(sch_1):page266_i29@pure_quanta.q_cap(chips)"
			("LOCATION" "C2582")
		)
		("@t6g_mb_lib.t6g(sch_1):page266_i39@pure_quanta.q_cap(chips)"
			("LOCATION" "C2583")
		)
		("@t6g_mb_lib.t6g(sch_1):page266_i12@pure_quanta.q_cap(chips)"
			("LOCATION" "C2584")
		)
		("@t6g_mb_lib.t6g(sch_1):page266_i44@pure_quanta.q_cap(chips)"
			("LOCATION" "C2585")
		)
		("@t6g_mb_lib.t6g(sch_1):page266_i42@pure_quanta.q_cap(chips)"
			("LOCATION" "C2586")
		)
		("@t6g_mb_lib.t6g(sch_1):page266_i50@pure_quanta.q_cap(chips)"
			("LOCATION" "C2588")
		)
		("@t6g_mb_lib.t6g(sch_1):page266_i46@pure_quanta.q_cap(chips)"
			("LOCATION" "C2589")
		)
		("@t6g_mb_lib.t6g(sch_1):page266_i52@pure_quanta.q_cap(chips)"
			("LOCATION" "C2590")
		)
		("@t6g_mb_lib.t6g(sch_1):page266_i47@pure_quanta.q_cap(chips)"
			("LOCATION" "C2591")
		)
		("@t6g_mb_lib.t6g(sch_1):page266_i56@pure_quanta.q_cap(chips)"
			("LOCATION" "C2592")
		)
		("@t6g_mb_lib.t6g(sch_1):page266_i54@pure_quanta.q_cap(chips)"
			("LOCATION" "C2593")
		)
		("@t6g_mb_lib.t6g(sch_1):page266_i63@pure_quanta.q_cap(chips)"
			("LOCATION" "C2594")
		)
		("@t6g_mb_lib.t6g(sch_1):page266_i58@pure_quanta.q_cap(chips)"
			("LOCATION" "C2595")
		)
		("@t6g_mb_lib.t6g(sch_1):page266_i21@pure_quanta.q_cap(chips)"
			("LOCATION" "C2596")
		)
		("@t6g_mb_lib.t6g(sch_1):page266_i23@pure_quanta.q_cap(chips)"
			("LOCATION" "C2597")
		)
		("@t6g_mb_lib.t6g(sch_1):page266_i4@pure_quanta.q_cap(chips)"
			("LOCATION" "C2598")
		)
		("@t6g_mb_lib.t6g(sch_1):page266_i7@pure_quanta.q_cap(chips)"
			("LOCATION" "C2599")
		)
		("@t6g_mb_lib.t6g(sch_1):page266_i33@pure_quanta.q_cap(chips)"
			("LOCATION" "C2600")
		)
		("@t6g_mb_lib.t6g(sch_1):page266_i25@pure_quanta.q_cap(chips)"
			("LOCATION" "C2601")
		)
		("@t6g_mb_lib.t6g(sch_1):page266_i8@pure_quanta.q_cap(chips)"
			("LOCATION" "C2602")
		)
		("@t6g_mb_lib.t6g(sch_1):page266_i27@pure_quanta.q_cap(chips)"
			("LOCATION" "C2604")
		)
		("@t6g_mb_lib.t6g(sch_1):page266_i11@pure_quanta.q_cap(chips)"
			("LOCATION" "C2605")
		)
		("@t6g_mb_lib.t6g(sch_1):page266_i38@pure_quanta.q_cap(chips)"
			("LOCATION" "C2606")
		)
		("@t6g_mb_lib.t6g(sch_1):page266_i69@pure_quanta.q_cap(chips)"
			("LOCATION" "C2607")
		)
		("@t6g_mb_lib.t6g(sch_1):page266_i13@pure_quanta.q_cap(chips)"
			("LOCATION" "C2612")
		)
		("@t6g_mb_lib.t6g(sch_1):page266_i14@pure_quanta.q_cap(chips)"
			("LOCATION" "C2615")
		)
		("@t6g_mb_lib.t6g(sch_1):page266_i16@pure_quanta.q_cap(chips)"
			("LOCATION" "C2616")
		)
		("@t6g_mb_lib.t6g(sch_1):page266_i65@pure_quanta.q_cap(chips)"
			("LOCATION" "C2625")
		)
		("@t6g_mb_lib.t6g(sch_1):page266_i59@pure_quanta.q_cap(chips)"
			("LOCATION" "C2626")
		)
		("@t6g_mb_lib.t6g(sch_1):page266_i67@pure_quanta.q_cap(chips)"
			("LOCATION" "C2627")
		)
		("@t6g_mb_lib.t6g(sch_1):page266_i61@pure_quanta.q_cap(chips)"
			("LOCATION" "C2628")
		)
		("@t6g_mb_lib.t6g(sch_1):page266_i24@pure_quanta.q_inductor(chips)"
			("LOCATION" "L83")
		)
		("@t6g_mb_lib.t6g(sch_1):page266_i18@pure_quanta.q_inductor(chips)"
			("LOCATION" "L84")
		)
		("@t6g_mb_lib.t6g(sch_1):page266_i70@pure_quanta.cyusb330468ltxi(chips)"
			("LOCATION" "U204")
		)
		("@t6g_mb_lib.t6g(sch_1):page201_i721@pure_quanta.q_cap(chips)"
			("LOCATION" "C2763")
		)
		("@t6g_mb_lib.t6g(sch_1):page201_i720@pure_quanta.q_cap(chips)"
			("LOCATION" "C2764")
		)
		("@t6g_mb_lib.t6g(sch_1):page201_i850@pure_quanta.q_cap(chips)"
			("LOCATION" "C2766")
		)
		("@t6g_mb_lib.t6g(sch_1):page201_i701@pure_quanta.q_cap(chips)"
			("LOCATION" "C2767")
		)
		("@t6g_mb_lib.t6g(sch_1):page201_i700@pure_quanta.q_cap(chips)"
			("LOCATION" "C2768")
		)
		("@t6g_mb_lib.t6g(sch_1):page201_i859@pure_quanta.q_cap(chips)"
			("LOCATION" "C2770")
		)
		("@t6g_mb_lib.t6g(sch_1):page201_i682@pure_quanta.q_cap(chips)"
			("LOCATION" "C2771")
		)
		("@t6g_mb_lib.t6g(sch_1):page201_i683@pure_quanta.q_cap(chips)"
			("LOCATION" "C2772")
		)
		("@t6g_mb_lib.t6g(sch_1):page201_i868@pure_quanta.q_cap(chips)"
			("LOCATION" "C2774")
		)
		("@t6g_mb_lib.t6g(sch_1):page201_i726@pure_quanta.q_cap(chips)"
			("LOCATION" "C2775")
		)
		("@t6g_mb_lib.t6g(sch_1):page201_i725@pure_quanta.q_cap(chips)"
			("LOCATION" "C2776")
		)
		("@t6g_mb_lib.t6g(sch_1):page201_i849@pure_quanta.q_cap(chips)"
			("LOCATION" "C2778")
		)
		("@t6g_mb_lib.t6g(sch_1):page201_i705@pure_quanta.q_cap(chips)"
			("LOCATION" "C2779")
		)
		("@t6g_mb_lib.t6g(sch_1):page201_i704@pure_quanta.q_cap(chips)"
			("LOCATION" "C2780")
		)
		("@t6g_mb_lib.t6g(sch_1):page201_i860@pure_quanta.q_cap(chips)"
			("LOCATION" "C2782")
		)
		("@t6g_mb_lib.t6g(sch_1):page201_i689@pure_quanta.q_cap(chips)"
			("LOCATION" "C2783")
		)
		("@t6g_mb_lib.t6g(sch_1):page201_i688@pure_quanta.q_cap(chips)"
			("LOCATION" "C2784")
		)
		("@t6g_mb_lib.t6g(sch_1):page201_i867@pure_quanta.q_cap(chips)"
			("LOCATION" "C2786")
		)
		("@t6g_mb_lib.t6g(sch_1):page201_i770@pure_quanta.q_cap(chips)"
			("LOCATION" "C2787")
		)
		("@t6g_mb_lib.t6g(sch_1):page201_i769@pure_quanta.q_cap(chips)"
			("LOCATION" "C2788")
		)
		("@t6g_mb_lib.t6g(sch_1):page201_i853@pure_quanta.q_cap(chips)"
			("LOCATION" "C2790")
		)
		("@t6g_mb_lib.t6g(sch_1):page201_i743@pure_quanta.q_cap(chips)"
			("LOCATION" "C2791")
		)
		("@t6g_mb_lib.t6g(sch_1):page201_i742@pure_quanta.q_cap(chips)"
			("LOCATION" "C2792")
		)
		("@t6g_mb_lib.t6g(sch_1):page201_i858@pure_quanta.q_cap(chips)"
			("LOCATION" "C2794")
		)
		("@t6g_mb_lib.t6g(sch_1):page201_i733@pure_quanta.q_cap(chips)"
			("LOCATION" "C2795")
		)
		("@t6g_mb_lib.t6g(sch_1):page201_i732@pure_quanta.q_cap(chips)"
			("LOCATION" "C2796")
		)
		("@t6g_mb_lib.t6g(sch_1):page201_i866@pure_quanta.q_cap(chips)"
			("LOCATION" "C2798")
		)
		("@t6g_mb_lib.t6g(sch_1):page201_i774@pure_quanta.q_cap(chips)"
			("LOCATION" "C2799")
		)
		("@t6g_mb_lib.t6g(sch_1):page201_i773@pure_quanta.q_cap(chips)"
			("LOCATION" "C2800")
		)
		("@t6g_mb_lib.t6g(sch_1):page201_i854@pure_quanta.q_cap(chips)"
			("LOCATION" "C2802")
		)
		("@t6g_mb_lib.t6g(sch_1):page201_i747@pure_quanta.q_cap(chips)"
			("LOCATION" "C2803")
		)
		("@t6g_mb_lib.t6g(sch_1):page201_i746@pure_quanta.q_cap(chips)"
			("LOCATION" "C2804")
		)
		("@t6g_mb_lib.t6g(sch_1):page201_i857@pure_quanta.q_cap(chips)"
			("LOCATION" "C2806")
		)
		("@t6g_mb_lib.t6g(sch_1):page201_i737@pure_quanta.q_cap(chips)"
			("LOCATION" "C2807")
		)
		("@t6g_mb_lib.t6g(sch_1):page201_i736@pure_quanta.q_cap(chips)"
			("LOCATION" "C2808")
		)
		("@t6g_mb_lib.t6g(sch_1):page201_i865@pure_quanta.q_cap(chips)"
			("LOCATION" "C2810")
		)
		("@t6g_mb_lib.t6g(sch_1):page201_i852@pure_quanta.q_cap(chips)"
			("LOCATION" "C2911")
		)
		("@t6g_mb_lib.t6g(sch_1):page201_i864@pure_quanta.q_cap(chips)"
			("LOCATION" "C2912")
		)
		("@t6g_mb_lib.t6g(sch_1):page201_i872@pure_quanta.q_cap(chips)"
			("LOCATION" "C2913")
		)
		("@t6g_mb_lib.t6g(sch_1):page201_i851@pure_quanta.q_cap(chips)"
			("LOCATION" "C2914")
		)
		("@t6g_mb_lib.t6g(sch_1):page201_i863@pure_quanta.q_cap(chips)"
			("LOCATION" "C2915")
		)
		("@t6g_mb_lib.t6g(sch_1):page201_i871@pure_quanta.q_cap(chips)"
			("LOCATION" "C2916")
		)
		("@t6g_mb_lib.t6g(sch_1):page201_i855@pure_quanta.q_cap(chips)"
			("LOCATION" "C2917")
		)
		("@t6g_mb_lib.t6g(sch_1):page201_i862@pure_quanta.q_cap(chips)"
			("LOCATION" "C2918")
		)
		("@t6g_mb_lib.t6g(sch_1):page201_i870@pure_quanta.q_cap(chips)"
			("LOCATION" "C2919")
		)
		("@t6g_mb_lib.t6g(sch_1):page201_i856@pure_quanta.q_cap(chips)"
			("LOCATION" "C2920")
		)
		("@t6g_mb_lib.t6g(sch_1):page201_i861@pure_quanta.q_cap(chips)"
			("LOCATION" "C2921")
		)
		("@t6g_mb_lib.t6g(sch_1):page201_i869@pure_quanta.q_cap(chips)"
			("LOCATION" "C2922")
		)
		("@t6g_mb_lib.t6g(sch_1):page201_i728@pure_quanta.sconn38_u10d238300t(chips)"
			("LOCATION" "J276")
		)
		("@t6g_mb_lib.t6g(sch_1):page201_i786@pure_quanta.sconn38_u10d238300t(chips)"
			("LOCATION" "J277")
		)
		("@t6g_mb_lib.t6g(sch_1):page201_i708@pure_quanta.sconn38_u10d238300t(chips)"
			("LOCATION" "J278")
		)
		("@t6g_mb_lib.t6g(sch_1):page201_i799@pure_quanta.q_res(chips)"
			("LOCATION" "R3711")
		)
		("@t6g_mb_lib.t6g(sch_1):page201_i796@pure_quanta.q_res(chips)"
			("LOCATION" "R3712")
		)
		("@t6g_mb_lib.t6g(sch_1):page276_i113@pure_quanta.q_cap(chips)"
			("LOCATION" "C2815")
		)
		("@t6g_mb_lib.t6g(sch_1):page276_i141@pure_quanta.q_led(chips)"
			("LOCATION" "D12")
		)
		("@t6g_mb_lib.t6g(sch_1):page276_i123@pure_quanta.sconn20_5011902017(chips)"
			("LOCATION" "J127")
		)
		("@t6g_mb_lib.t6g(sch_1):page276_i51@pure_quanta.sconn24_5041902441001(chips)"
			("LOCATION" "J269")
		)
		("@t6g_mb_lib.t6g(sch_1):page276_i130@pure_quanta.mosfet_nch_dual(chips)"
			("LOCATION" "Q19")
		)
		("@t6g_mb_lib.t6g(sch_1):page276_i144@pure_quanta.mosfet_nch_dual(chips)"
			("LOCATION" "Q19")
		)
		("@t6g_mb_lib.t6g(sch_1):page276_i68@pure_quanta.q_res(chips)"
			("LOCATION" "R432")
		)
		("@t6g_mb_lib.t6g(sch_1):page276_i127@pure_quanta.q_res(chips)"
			("LOCATION" "R1089")
		)
		("@t6g_mb_lib.t6g(sch_1):page276_i126@pure_quanta.q_res(chips)"
			("LOCATION" "R1094")
		)
		("@t6g_mb_lib.t6g(sch_1):page276_i90@pure_quanta.q_res(chips)"
			("LOCATION" "R1485")
		)
		("@t6g_mb_lib.t6g(sch_1):page276_i69@pure_quanta.q_res(chips)"
			("LOCATION" "R1490")
		)
		("@t6g_mb_lib.t6g(sch_1):page276_i89@pure_quanta.q_res(chips)"
			("LOCATION" "R1491")
		)
		("@t6g_mb_lib.t6g(sch_1):page276_i94@pure_quanta.q_res(chips)"
			("LOCATION" "R3496")
		)
		("@t6g_mb_lib.t6g(sch_1):page276_i95@pure_quanta.q_res(chips)"
			("LOCATION" "R3497")
		)
		("@t6g_mb_lib.t6g(sch_1):page276_i124@pure_quanta.q_res(chips)"
			("LOCATION" "R3498")
		)
		("@t6g_mb_lib.t6g(sch_1):page276_i114@pure_quanta.q_res(chips)"
			("LOCATION" "R3500")
		)
		("@t6g_mb_lib.t6g(sch_1):page276_i115@pure_quanta.q_res(chips)"
			("LOCATION" "R3501")
		)
		("@t6g_mb_lib.t6g(sch_1):page276_i119@pure_quanta.q_res(chips)"
			("LOCATION" "R3502")
		)
		("@t6g_mb_lib.t6g(sch_1):page276_i117@pure_quanta.q_res(chips)"
			("LOCATION" "R3503")
		)
		("@t6g_mb_lib.t6g(sch_1):page276_i118@pure_quanta.q_res(chips)"
			("LOCATION" "R3504")
		)
		("@t6g_mb_lib.t6g(sch_1):page276_i107@pure_quanta.q_res(chips)"
			("LOCATION" "R3505")
		)
		("@t6g_mb_lib.t6g(sch_1):page276_i100@pure_quanta.q_res(chips)"
			("LOCATION" "R3506")
		)
		("@t6g_mb_lib.t6g(sch_1):page276_i99@pure_quanta.q_res(chips)"
			("LOCATION" "R3507")
		)
		("@t6g_mb_lib.t6g(sch_1):page276_i142@pure_quanta.q_res(chips)"
			("LOCATION" "R3701")
		)
		("@t6g_mb_lib.t6g(sch_1):page276_i139@pure_quanta.q_res(chips)"
			("LOCATION" "R3702")
		)
		("@t6g_mb_lib.t6g(sch_1):page263_i36@pure_quanta.q_cap(chips)"
			("LOCATION" "C2817")
		)
		("@t6g_mb_lib.t6g(sch_1):page263_i180@pure_quanta.q_cap(chips)"
			("LOCATION" "C2818")
		)
		("@t6g_mb_lib.t6g(sch_1):page263_i150@pure_quanta.q_cap(chips)"
			("LOCATION" "C2892")
		)
		("@t6g_mb_lib.t6g(sch_1):page263_i414@pure_quanta.conn2_210hp102gbr05k(chips)"
			("LOCATION" "J288")
		)
		("@t6g_mb_lib.t6g(sch_1):page263_i27@pure_quanta.q_res(chips)"
			("LOCATION" "R3508")
		)
		("@t6g_mb_lib.t6g(sch_1):page263_i22@pure_quanta.q_res(chips)"
			("LOCATION" "R3509")
		)
		("@t6g_mb_lib.t6g(sch_1):page263_i189@pure_quanta.q_res(chips)"
			("LOCATION" "R3510")
		)
		("@t6g_mb_lib.t6g(sch_1):page263_i196@pure_quanta.q_res(chips)"
			("LOCATION" "R3511")
		)
		("@t6g_mb_lib.t6g(sch_1):page263_i29@pure_quanta.q_res(chips)"
			("LOCATION" "R3512")
		)
		("@t6g_mb_lib.t6g(sch_1):page263_i24@pure_quanta.q_res(chips)"
			("LOCATION" "R3513")
		)
		("@t6g_mb_lib.t6g(sch_1):page263_i188@pure_quanta.q_res(chips)"
			("LOCATION" "R3514")
		)
		("@t6g_mb_lib.t6g(sch_1):page263_i194@pure_quanta.q_res(chips)"
			("LOCATION" "R3515")
		)
		("@t6g_mb_lib.t6g(sch_1):page263_i30@pure_quanta.q_res(chips)"
			("LOCATION" "R3516")
		)
		("@t6g_mb_lib.t6g(sch_1):page263_i26@pure_quanta.q_res(chips)"
			("LOCATION" "R3517")
		)
		("@t6g_mb_lib.t6g(sch_1):page263_i186@pure_quanta.q_res(chips)"
			("LOCATION" "R3518")
		)
		("@t6g_mb_lib.t6g(sch_1):page263_i192@pure_quanta.q_res(chips)"
			("LOCATION" "R3519")
		)
		("@t6g_mb_lib.t6g(sch_1):page263_i64@pure_quanta.q_res(chips)"
			("LOCATION" "R3527")
		)
		("@t6g_mb_lib.t6g(sch_1):page263_i60@pure_quanta.q_res(chips)"
			("LOCATION" "R3528")
		)
		("@t6g_mb_lib.t6g(sch_1):page263_i184@pure_quanta.q_res(chips)"
			("LOCATION" "R3529")
		)
		("@t6g_mb_lib.t6g(sch_1):page263_i185@pure_quanta.q_res(chips)"
			("LOCATION" "R3530")
		)
		("@t6g_mb_lib.t6g(sch_1):page263_i157@pure_quanta.q_res(chips)"
			("LOCATION" "R3616")
		)
		("@t6g_mb_lib.t6g(sch_1):page263_i162@pure_quanta.q_res(chips)"
			("LOCATION" "R3617")
		)
		("@t6g_mb_lib.t6g(sch_1):page263_i155@pure_quanta.q_res(chips)"
			("LOCATION" "R3618")
		)
		("@t6g_mb_lib.t6g(sch_1):page263_i160@pure_quanta.q_res(chips)"
			("LOCATION" "R3619")
		)
		("@t6g_mb_lib.t6g(sch_1):page263_i154@pure_quanta.q_res(chips)"
			("LOCATION" "R3620")
		)
		("@t6g_mb_lib.t6g(sch_1):page263_i158@pure_quanta.q_res(chips)"
			("LOCATION" "R3621")
		)
		("@t6g_mb_lib.t6g(sch_1):page263_i152@pure_quanta.q_res(chips)"
			("LOCATION" "R3622")
		)
		("@t6g_mb_lib.t6g(sch_1):page263_i153@pure_quanta.q_res(chips)"
			("LOCATION" "R3623")
		)
		("@t6g_mb_lib.t6g(sch_1):page263_i396@pure_quanta.q_res(chips)"
			("LOCATION" "R3848")
		)
		("@t6g_mb_lib.t6g(sch_1):page263_i395@pure_quanta.q_res(chips)"
			("LOCATION" "R3849")
		)
		("@t6g_mb_lib.t6g(sch_1):page263_i392@pure_quanta.q_res(chips)"
			("LOCATION" "R3850")
		)
		("@t6g_mb_lib.t6g(sch_1):page263_i391@pure_quanta.q_res(chips)"
			("LOCATION" "R3851")
		)
		("@t6g_mb_lib.t6g(sch_1):page263_i429@pure_quanta.q_res(chips)"
			("LOCATION" "R3852")
		)
		("@t6g_mb_lib.t6g(sch_1):page263_i450@pure_quanta.q_res(chips)"
			("LOCATION" "R3859")
		)
		("@t6g_mb_lib.t6g(sch_1):page263_i449@pure_quanta.q_res(chips)"
			("LOCATION" "R3860")
		)
		("@t6g_mb_lib.t6g(sch_1):page263_i448@pure_quanta.q_res(chips)"
			("LOCATION" "R3861")
		)
		("@t6g_mb_lib.t6g(sch_1):page263_i447@pure_quanta.q_res(chips)"
			("LOCATION" "R3862")
		)
		("@t6g_mb_lib.t6g(sch_1):page263_i433@pure_quanta.q_res(chips)"
			("LOCATION" "R3863")
		)
		("@t6g_mb_lib.t6g(sch_1):page263_i446@pure_quanta.q_res(chips)"
			("LOCATION" "R3864")
		)
		("@t6g_mb_lib.t6g(sch_1):page263_i432@pure_quanta.q_res(chips)"
			("LOCATION" "R3865")
		)
		("@t6g_mb_lib.t6g(sch_1):page263_i445@pure_quanta.q_res(chips)"
			("LOCATION" "R3866")
		)
		("@t6g_mb_lib.t6g(sch_1):page263_i431@pure_quanta.q_res(chips)"
			("LOCATION" "R3867")
		)
		("@t6g_mb_lib.t6g(sch_1):page263_i444@pure_quanta.q_res(chips)"
			("LOCATION" "R3868")
		)
		("@t6g_mb_lib.t6g(sch_1):page263_i430@pure_quanta.q_res(chips)"
			("LOCATION" "R3869")
		)
		("@t6g_mb_lib.t6g(sch_1):page263_i443@pure_quanta.q_res(chips)"
			("LOCATION" "R3870")
		)
		("@t6g_mb_lib.t6g(sch_1):page263_i459@pure_quanta.q_res(chips)"
			("LOCATION" "R3873")
		)
		("@t6g_mb_lib.t6g(sch_1):page263_i35@pure_quanta.pca9555pw(chips)"
			("LOCATION" "U14")
		)
		("@t6g_mb_lib.t6g(sch_1):page263_i182@pure_quanta.pca9555pw(chips)"
			("LOCATION" "U15")
		)
		("@t6g_mb_lib.t6g(sch_1):page263_i198@pure_quanta.pca9555pw(chips)"
			("LOCATION" "U194")
		)
		("@t6g_mb_lib.t6g(sch_1):page214_i16@pure_quanta.q_cap(chips)"
			("LOCATION" "C2824")
		)
		("@t6g_mb_lib.t6g(sch_1):page214_i3@pure_quanta.q_res(chips)"
			("LOCATION" "R3536")
		)
		("@t6g_mb_lib.t6g(sch_1):page214_i2@pure_quanta.q_res(chips)"
			("LOCATION" "R3537")
		)
		("@t6g_mb_lib.t6g(sch_1):page214_i8@pure_quanta.q_res(chips)"
			("LOCATION" "R3538")
		)
		("@t6g_mb_lib.t6g(sch_1):page214_i5@pure_quanta.q_res(chips)"
			("LOCATION" "R3539")
		)
		("@t6g_mb_lib.t6g(sch_1):page214_i9@pure_quanta.q_res(chips)"
			("LOCATION" "R3540")
		)
		("@t6g_mb_lib.t6g(sch_1):page214_i7@pure_quanta.q_res(chips)"
			("LOCATION" "R3541")
		)
		("@t6g_mb_lib.t6g(sch_1):page214_i13@pure_quanta.q_res(chips)"
			("LOCATION" "R3542")
		)
		("@t6g_mb_lib.t6g(sch_1):page214_i24@pure_quanta.m24c64wmn6tp(chips)"
			("LOCATION" "U193")
		)
		("@t6g_mb_lib.t6g(sch_1):page270_i224@pure_quanta.q_cap(chips)"
			("LOCATION" "C2899")
		)
		("@t6g_mb_lib.t6g(sch_1):page270_i219@pure_quanta.q_cap(chips)"
			("LOCATION" "C2900")
		)
		("@t6g_mb_lib.t6g(sch_1):page270_i218@pure_quanta.q_cap(chips)"
			("LOCATION" "C2901")
		)
		("@t6g_mb_lib.t6g(sch_1):page270_i215@pure_quanta.q_cap(chips)"
			("LOCATION" "C2902")
		)
		("@t6g_mb_lib.t6g(sch_1):page270_i214@pure_quanta.q_cap(chips)"
			("LOCATION" "C2903")
		)
		("@t6g_mb_lib.t6g(sch_1):page270_i207@pure_quanta.q_capp(chips)"
			("LOCATION" "C2904")
		)
		("@t6g_mb_lib.t6g(sch_1):page270_i210@pure_quanta.q_capp(chips)"
			("LOCATION" "C2905")
		)
		("@t6g_mb_lib.t6g(sch_1):page270_i237@pure_quanta.q_cap(chips)"
			("LOCATION" "C2906")
		)
		("@t6g_mb_lib.t6g(sch_1):page270_i235@pure_quanta.q_cap(chips)"
			("LOCATION" "C2907")
		)
		("@t6g_mb_lib.t6g(sch_1):page270_i226@pure_quanta.q_cap(chips)"
			("LOCATION" "C2908")
		)
		("@t6g_mb_lib.t6g(sch_1):page270_i225@pure_quanta.q_cap(chips)"
			("LOCATION" "C2909")
		)
		("@t6g_mb_lib.t6g(sch_1):page270_i228@pure_quanta.q_cap(chips)"
			("LOCATION" "C2910")
		)
		("@t6g_mb_lib.t6g(sch_1):page270_i177@pure_quanta.sconn26_504290130nv01(chips)"
			("LOCATION" "J33")
		)
		("@t6g_mb_lib.t6g(sch_1):page270_i97@pure_quanta.conn24_g88mp2410282reu(chips)"
			("LOCATION" "J92")
		)
		("@t6g_mb_lib.t6g(sch_1):page270_i94@pure_quanta.conn24_g88mp2410282reu(chips)"
			("LOCATION" "J93")
		)
		("@t6g_mb_lib.t6g(sch_1):page270_i11@pure_quanta.conn6_g88mp0610282reu(chips)"
			("LOCATION" "JP3")
		)
		("@t6g_mb_lib.t6g(sch_1):page270_i4@pure_quanta.conn6_g88mp0610282reu(chips)"
			("LOCATION" "JP12")
		)
		("@t6g_mb_lib.t6g(sch_1):page270_i196@pure_quanta.q_res(chips)"
			("LOCATION" "R478")
		)
		("@t6g_mb_lib.t6g(sch_1):page270_i194@pure_quanta.q_res(chips)"
			("LOCATION" "R479")
		)
		("@t6g_mb_lib.t6g(sch_1):page288_i59@pure_quanta.q_cap(chips)"
			("LOCATION" "C2927")
		)
		("@t6g_mb_lib.t6g(sch_1):page288_i100@pure_quanta.conn3_210hp1030br1(chips)"
			("LOCATION" "PJP2")
		)
		("@t6g_mb_lib.t6g(sch_1):page288_i54@pure_quanta.q_res(chips)"
			("LOCATION" "R2320")
		)
		("@t6g_mb_lib.t6g(sch_1):page288_i55@pure_quanta.q_res(chips)"
			("LOCATION" "R2321")
		)
		("@t6g_mb_lib.t6g(sch_1):page288_i68@pure_quanta.q_res(chips)"
			("LOCATION" "R3798")
		)
		("@t6g_mb_lib.t6g(sch_1):page288_i71@pure_quanta.q_res(chips)"
			("LOCATION" "R3799")
		)
		("@t6g_mb_lib.t6g(sch_1):page288_i66@pure_quanta.q_res(chips)"
			("LOCATION" "R3800")
		)
		("@t6g_mb_lib.t6g(sch_1):page288_i69@pure_quanta.q_res(chips)"
			("LOCATION" "R3801")
		)
		("@t6g_mb_lib.t6g(sch_1):page288_i63@pure_quanta.q_res(chips)"
			("LOCATION" "R3802")
		)
		("@t6g_mb_lib.t6g(sch_1):page288_i133@pure_quanta.q_res(chips)"
			("LOCATION" "R3803")
		)
		("@t6g_mb_lib.t6g(sch_1):page288_i132@pure_quanta.q_res(chips)"
			("LOCATION" "R3804")
		)
		("@t6g_mb_lib.t6g(sch_1):page288_i135@pure_quanta.q_res(chips)"
			("LOCATION" "R3806")
		)
		("@t6g_mb_lib.t6g(sch_1):page288_i136@pure_quanta.q_res(chips)"
			("LOCATION" "R3807")
		)
		("@t6g_mb_lib.t6g(sch_1):page288_i138@pure_quanta.q_res(chips)"
			("LOCATION" "R3808")
		)
		("@t6g_mb_lib.t6g(sch_1):page288_i137@pure_quanta.q_res(chips)"
			("LOCATION" "R3809")
		)
		("@t6g_mb_lib.t6g(sch_1):page288_i140@pure_quanta.q_res(chips)"
			("LOCATION" "R3810")
		)
		("@t6g_mb_lib.t6g(sch_1):page288_i139@pure_quanta.q_res(chips)"
			("LOCATION" "R3811")
		)
		("@t6g_mb_lib.t6g(sch_1):page288_i142@pure_quanta.q_res(chips)"
			("LOCATION" "R3812")
		)
		("@t6g_mb_lib.t6g(sch_1):page288_i141@pure_quanta.q_res(chips)"
			("LOCATION" "R3813")
		)
		("@t6g_mb_lib.t6g(sch_1):page288_i144@pure_quanta.q_res(chips)"
			("LOCATION" "R3814")
		)
		("@t6g_mb_lib.t6g(sch_1):page288_i143@pure_quanta.q_res(chips)"
			("LOCATION" "R3815")
		)
		("@t6g_mb_lib.t6g(sch_1):page288_i146@pure_quanta.q_res(chips)"
			("LOCATION" "R3816")
		)
		("@t6g_mb_lib.t6g(sch_1):page288_i145@pure_quanta.q_res(chips)"
			("LOCATION" "R3817")
		)
		("@t6g_mb_lib.t6g(sch_1):page288_i148@pure_quanta.q_res(chips)"
			("LOCATION" "R3818")
		)
		("@t6g_mb_lib.t6g(sch_1):page288_i147@pure_quanta.q_res(chips)"
			("LOCATION" "R3819")
		)
		("@t6g_mb_lib.t6g(sch_1):page288_i61@pure_quanta.pca9848pw(chips)"
			("LOCATION" "U197")
		)
		("@t6g_mb_lib.t6g(sch_1):page251_i48@pure_quanta.q_cap(chips)"
			("LOCATION" "C2928")
		)
		("@t6g_mb_lib.t6g(sch_1):page251_i45@pure_quanta.q_cap(chips)"
			("LOCATION" "C2929")
		)
		("@t6g_mb_lib.t6g(sch_1):page251_i44@pure_quanta.mosfet_n_gsd(chips)"
			("LOCATION" "Q43")
		)
		("@t6g_mb_lib.t6g(sch_1):page251_i17@pure_quanta.mosfet_nch_dual(chips)"
			("LOCATION" "Q127")
		)
		("@t6g_mb_lib.t6g(sch_1):page251_i10@pure_quanta.mosfet_nch_dual(chips)"
			("LOCATION" "Q127")
		)
		("@t6g_mb_lib.t6g(sch_1):page251_i37@pure_quanta.mosfet_nch_dual(chips)"
			("LOCATION" "Q129")
		)
		("@t6g_mb_lib.t6g(sch_1):page251_i32@pure_quanta.mosfet_nch_dual(chips)"
			("LOCATION" "Q129")
		)
		("@t6g_mb_lib.t6g(sch_1):page251_i43@pure_quanta.q_res(chips)"
			("LOCATION" "R1328")
		)
		("@t6g_mb_lib.t6g(sch_1):page251_i46@pure_quanta.q_res(chips)"
			("LOCATION" "R1329")
		)
		("@t6g_mb_lib.t6g(sch_1):page251_i18@pure_quanta.q_res(chips)"
			("LOCATION" "R3599")
		)
		("@t6g_mb_lib.t6g(sch_1):page251_i38@pure_quanta.q_res(chips)"
			("LOCATION" "R3601")
		)
		("@t6g_mb_lib.t6g(sch_1):page251_i12@pure_quanta.q_res(chips)"
			("LOCATION" "R3603")
		)
		("@t6g_mb_lib.t6g(sch_1):page251_i28@pure_quanta.q_res(chips)"
			("LOCATION" "R3605")
		)
		("@t6g_mb_lib.t6g(sch_1):page251_i9@pure_quanta.q_res(chips)"
			("LOCATION" "R3607")
		)
		("@t6g_mb_lib.t6g(sch_1):page251_i25@pure_quanta.q_res(chips)"
			("LOCATION" "R3609")
		)
		("@t6g_mb_lib.t6g(sch_1):page251_i50@pure_quanta.q_res(chips)"
			("LOCATION" "R3847")
		)
		("@t6g_mb_lib.t6g(sch_1):page260_i14@pure_quanta.q_cap(chips)"
			("LOCATION" "C4485")
		)
		("@t6g_mb_lib.t6g(sch_1):page260_i24@pure_quanta.q_diode(chips)"
			("LOCATION" "D78")
		)
		("@t6g_mb_lib.t6g(sch_1):page260_i19@pure_quanta.sconn10_504290054n001(chips)"
			("LOCATION" "JP21")
		)
		("@t6g_mb_lib.t6g(sch_1):page260_i10@pure_quanta.mosfet_nch_dual(chips)"
			("LOCATION" "Q66")
		)
		("@t6g_mb_lib.t6g(sch_1):page260_i11@pure_quanta.mosfet_nch_dual(chips)"
			("LOCATION" "Q66")
		)
		("@t6g_mb_lib.t6g(sch_1):page260_i5@pure_quanta.q_res(chips)"
			("LOCATION" "R2458")
		)
		("@t6g_mb_lib.t6g(sch_1):page260_i27@pure_quanta.q_res(chips)"
			("LOCATION" "R4106")
		)
		("@t6g_mb_lib.t6g(sch_1):page260_i21@pure_quanta.q_res(chips)"
			("LOCATION" "R4225")
		)
		("@t6g_mb_lib.t6g(sch_1):page260_i20@pure_quanta.q_res(chips)"
			("LOCATION" "R4226")
		)
		("@t6g_mb_lib.t6g(sch_1):page241_i246@pure_quanta.q_led(chips)"
			("LOCATION" "D6")
		)
		("@t6g_mb_lib.t6g(sch_1):page241_i239@pure_quanta.mosfet_pch_gds_esd_protected(chips)"
			("LOCATION" "Q114")
		)
		("@t6g_mb_lib.t6g(sch_1):page241_i240@pure_quanta.q_res(chips)"
			("LOCATION" "R365")
		)
		("@t6g_mb_lib.t6g(sch_1):page241_i241@pure_quanta.q_res(chips)"
			("LOCATION" "R366")
		)
		("@t6g_mb_lib.t6g(sch_1):page241_i234@pure_quanta.q_res(chips)"
			("LOCATION" "R700")
		)
		("@t6g_mb_lib.t6g(sch_1):page241_i265@pure_quanta.q_res(chips)"
			("LOCATION" "R1549")
		)
		("@t6g_mb_lib.t6g(sch_1):page241_i264@pure_quanta.q_res(chips)"
			("LOCATION" "R1550")
		)
		("@t6g_mb_lib.t6g(sch_1):page241_i268@pure_quanta.q_res(chips)"
			("LOCATION" "R1559")
		)
		("@t6g_mb_lib.t6g(sch_1):page241_i269@pure_quanta.q_res(chips)"
			("LOCATION" "R1560")
		)
		("@t6g_mb_lib.t6g(sch_1):page241_i209@pure_quanta.q_res(chips)"
			("LOCATION" "R1725")
		)
		("@t6g_mb_lib.t6g(sch_1):page241_i245@pure_quanta.q_res(chips)"
			("LOCATION" "R1841")
		)
		("@t6g_mb_lib.t6g(sch_1):page241_i273@pure_quanta.q_res(chips)"
			("LOCATION" "R3495")
		)
		("@t6g_mb_lib.t6g(sch_1):page241_i276@pure_quanta.q_res(chips)"
			("LOCATION" "R3654")
		)
		("@t6g_mb_lib.t6g(sch_1):page241_i288@pure_quanta.q_res(chips)"
			("LOCATION" "R3704")
		)
		("@t6g_mb_lib.t6g(sch_1):page241_i235@pure_quanta.\\10m25daf484c7g\\(chips)"
			("LOCATION" "U3")
		)
		("@t6g_mb_lib.t6g(sch_1):page174_i79@pure_quanta.q_diode(chips)"
			("LOCATION" "D61")
		)
		("@t6g_mb_lib.t6g(sch_1):page174_i78@pure_quanta.q_diode(chips)"
			("LOCATION" "D62")
		)
		("@t6g_mb_lib.t6g(sch_1):page174_i77@pure_quanta.q_diode(chips)"
			("LOCATION" "D63")
		)
		("@t6g_mb_lib.t6g(sch_1):page174_i76@pure_quanta.q_diode(chips)"
			("LOCATION" "D64")
		)
		("@t6g_mb_lib.t6g(sch_1):page174_i66@pure_quanta.q_diode(chips)"
			("LOCATION" "D65")
		)
		("@t6g_mb_lib.t6g(sch_1):page174_i65@pure_quanta.q_diode(chips)"
			("LOCATION" "D66")
		)
		("@t6g_mb_lib.t6g(sch_1):page174_i64@pure_quanta.q_diode(chips)"
			("LOCATION" "D67")
		)
		("@t6g_mb_lib.t6g(sch_1):page174_i63@pure_quanta.q_diode(chips)"
			("LOCATION" "D68")
		)
		("@t6g_mb_lib.t6g(sch_1):page174_i58@pure_quanta.q_diode(chips)"
			("LOCATION" "D69")
		)
		("@t6g_mb_lib.t6g(sch_1):page174_i57@pure_quanta.q_diode(chips)"
			("LOCATION" "D70")
		)
		("@t6g_mb_lib.t6g(sch_1):page174_i56@pure_quanta.q_diode(chips)"
			("LOCATION" "D71")
		)
		("@t6g_mb_lib.t6g(sch_1):page174_i55@pure_quanta.q_diode(chips)"
			("LOCATION" "D72")
		)
		("@t6g_mb_lib.t6g(sch_1):page174_i98@pure_quanta.q_diode(chips)"
			("LOCATION" "D73")
		)
		("@t6g_mb_lib.t6g(sch_1):page174_i97@pure_quanta.q_diode(chips)"
			("LOCATION" "D74")
		)
		("@t6g_mb_lib.t6g(sch_1):page174_i96@pure_quanta.q_diode(chips)"
			("LOCATION" "D75")
		)
		("@t6g_mb_lib.t6g(sch_1):page174_i95@pure_quanta.q_diode(chips)"
			("LOCATION" "D77")
		)
		("@t6g_mb_lib.t6g(sch_1):page174_i108@pure_quanta.q_diode(chips)"
			("LOCATION" "D81")
		)
		("@t6g_mb_lib.t6g(sch_1):page174_i107@pure_quanta.q_diode(chips)"
			("LOCATION" "D82")
		)
		("@t6g_mb_lib.t6g(sch_1):page174_i136@pure_quanta.q_diode(chips)"
			("LOCATION" "D85")
		)
		("@t6g_mb_lib.t6g(sch_1):page174_i135@pure_quanta.q_diode(chips)"
			("LOCATION" "D86")
		)
		("@t6g_mb_lib.t6g(sch_1):page174_i139@pure_quanta.q_diode(chips)"
			("LOCATION" "D89")
		)
		("@t6g_mb_lib.t6g(sch_1):page174_i142@pure_quanta.q_diode(chips)"
			("LOCATION" "D90")
		)
		("@t6g_mb_lib.t6g(sch_1):page174_i84@pure_quanta.q_res(chips)"
			("LOCATION" "R1724")
		)
		("@t6g_mb_lib.t6g(sch_1):page174_i82@pure_quanta.q_res(chips)"
			("LOCATION" "R1726")
		)
		("@t6g_mb_lib.t6g(sch_1):page174_i72@pure_quanta.q_res(chips)"
			("LOCATION" "R3489")
		)
		("@t6g_mb_lib.t6g(sch_1):page174_i69@pure_quanta.q_res(chips)"
			("LOCATION" "R3490")
		)
		("@t6g_mb_lib.t6g(sch_1):page174_i67@pure_quanta.q_res(chips)"
			("LOCATION" "R3491")
		)
		("@t6g_mb_lib.t6g(sch_1):page174_i61@pure_quanta.q_res(chips)"
			("LOCATION" "R3492")
		)
		("@t6g_mb_lib.t6g(sch_1):page174_i103@pure_quanta.q_res(chips)"
			("LOCATION" "R3562")
		)
		("@t6g_mb_lib.t6g(sch_1):page174_i100@pure_quanta.q_res(chips)"
			("LOCATION" "R3563")
		)
		("@t6g_mb_lib.t6g(sch_1):page174_i111@pure_quanta.q_res(chips)"
			("LOCATION" "R3612")
		)
		("@t6g_mb_lib.t6g(sch_1):page174_i120@pure_quanta.q_res(chips)"
			("LOCATION" "R3614")
		)
		("@t6g_mb_lib.t6g(sch_1):page174_i138@pure_quanta.q_res(chips)"
			("LOCATION" "R3655")
		)
		("@t6g_mb_lib.t6g(sch_1):page211_i142@pure_quanta.q_diode(chips)"
			("LOCATION" "D80")
		)
		("@t6g_mb_lib.t6g(sch_1):page211_i159@pure_quanta.q_diode(chips)"
			("LOCATION" "D91")
		)
		("@t6g_mb_lib.t6g(sch_1):page211_i160@pure_quanta.q_diode(chips)"
			("LOCATION" "D92")
		)
		("@t6g_mb_lib.t6g(sch_1):page211_i161@pure_quanta.q_diode(chips)"
			("LOCATION" "D93")
		)
		("@t6g_mb_lib.t6g(sch_1):page211_i179@pure_quanta.q_diode(chips)"
			("LOCATION" "D94")
		)
		("@t6g_mb_lib.t6g(sch_1):page211_i180@pure_quanta.q_diode(chips)"
			("LOCATION" "D95")
		)
		("@t6g_mb_lib.t6g(sch_1):page211_i181@pure_quanta.q_diode(chips)"
			("LOCATION" "D96")
		)
		("@t6g_mb_lib.t6g(sch_1):page211_i182@pure_quanta.q_diode(chips)"
			("LOCATION" "D97")
		)
		("@t6g_mb_lib.t6g(sch_1):page211_i85@pure_quanta.q_res(chips)"
			("LOCATION" "R2118")
		)
		("@t6g_mb_lib.t6g(sch_1):page211_i7@pure_quanta.q_res(chips)"
			("LOCATION" "R2120")
		)
		("@t6g_mb_lib.t6g(sch_1):page211_i139@pure_quanta.q_res(chips)"
			("LOCATION" "R2121")
		)
		("@t6g_mb_lib.t6g(sch_1):page211_i104@pure_quanta.q_res(chips)"
			("LOCATION" "R2123")
		)
		("@t6g_mb_lib.t6g(sch_1):page211_i133@pure_quanta.q_res(chips)"
			("LOCATION" "R2945")
		)
		("@t6g_mb_lib.t6g(sch_1):page211_i136@pure_quanta.q_res(chips)"
			("LOCATION" "R2946")
		)
		("@t6g_mb_lib.t6g(sch_1):page211_i141@pure_quanta.q_res(chips)"
			("LOCATION" "R2954")
		)
		("@t6g_mb_lib.t6g(sch_1):page211_i137@pure_quanta.q_res(chips)"
			("LOCATION" "R2955")
		)
		("@t6g_mb_lib.t6g(sch_1):page211_i143@pure_quanta.q_res(chips)"
			("LOCATION" "R3564")
		)
		("@t6g_mb_lib.t6g(sch_1):page211_i147@pure_quanta.q_res(chips)"
			("LOCATION" "R3565")
		)
		("@t6g_mb_lib.t6g(sch_1):page211_i148@pure_quanta.q_res(chips)"
			("LOCATION" "R3566")
		)
		("@t6g_mb_lib.t6g(sch_1):page211_i146@pure_quanta.q_res(chips)"
			("LOCATION" "R3567")
		)
		("@t6g_mb_lib.t6g(sch_1):page211_i144@pure_quanta.q_res(chips)"
			("LOCATION" "R3568")
		)
		("@t6g_mb_lib.t6g(sch_1):page211_i145@pure_quanta.q_res(chips)"
			("LOCATION" "R3569")
		)
		("@t6g_mb_lib.t6g(sch_1):page211_i150@pure_quanta.q_res(chips)"
			("LOCATION" "R3570")
		)
		("@t6g_mb_lib.t6g(sch_1):page211_i149@pure_quanta.q_res(chips)"
			("LOCATION" "R3571")
		)
		("@t6g_mb_lib.t6g(sch_1):page211_i163@pure_quanta.q_res(chips)"
			("LOCATION" "R3591")
		)
		("@t6g_mb_lib.t6g(sch_1):page211_i165@pure_quanta.q_res(chips)"
			("LOCATION" "R3592")
		)
		("@t6g_mb_lib.t6g(sch_1):page211_i164@pure_quanta.q_res(chips)"
			("LOCATION" "R3593")
		)
		("@t6g_mb_lib.t6g(sch_1):page211_i168@pure_quanta.q_res(chips)"
			("LOCATION" "R3594")
		)
		("@t6g_mb_lib.t6g(sch_1):page211_i166@pure_quanta.q_res(chips)"
			("LOCATION" "R3595")
		)
		("@t6g_mb_lib.t6g(sch_1):page211_i167@pure_quanta.q_res(chips)"
			("LOCATION" "R3596")
		)
		("@t6g_mb_lib.t6g(sch_1):page211_i169@pure_quanta.q_res(chips)"
			("LOCATION" "R3597")
		)
		("@t6g_mb_lib.t6g(sch_1):page211_i170@pure_quanta.q_res(chips)"
			("LOCATION" "R3598")
		)
		("@t6g_mb_lib.t6g(sch_1):page253_i50@pure_quanta.q_diode(chips)"
			("LOCATION" "D98")
		)
		("@t6g_mb_lib.t6g(sch_1):page253_i49@pure_quanta.q_diode(chips)"
			("LOCATION" "D99")
		)
		("@t6g_mb_lib.t6g(sch_1):page253_i58@pure_quanta.q_diode(chips)"
			("LOCATION" "D100")
		)
		("@t6g_mb_lib.t6g(sch_1):page253_i15@pure_quanta.sconn20_5011902017(chips)"
			("LOCATION" "J35")
		)
		("@t6g_mb_lib.t6g(sch_1):page253_i25@pure_quanta.sconn20_5011902017(chips)"
			("LOCATION" "J37")
		)
		("@t6g_mb_lib.t6g(sch_1):page253_i8@pure_quanta.q_res(chips)"
			("LOCATION" "R1454")
		)
		("@t6g_mb_lib.t6g(sch_1):page253_i9@pure_quanta.q_res(chips)"
			("LOCATION" "R2849")
		)
		("@t6g_mb_lib.t6g(sch_1):page253_i61@pure_quanta.q_res(chips)"
			("LOCATION" "R3705")
		)
		("@t6g_mb_lib.t6g(sch_1):page253_i36@pure_quanta.q_res(chips)"
			("LOCATION" "R3717")
		)
		("@t6g_mb_lib.t6g(sch_1):page253_i33@pure_quanta.q_res(chips)"
			("LOCATION" "R3718")
		)
		("@t6g_mb_lib.t6g(sch_1):page253_i11@pure_quanta.q_res(chips)"
			("LOCATION" "R3730")
		)
		("@t6g_mb_lib.t6g(sch_1):page253_i10@pure_quanta.q_res(chips)"
			("LOCATION" "R3731")
		)
		("@t6g_mb_lib.t6g(sch_1):page253_i13@pure_quanta.q_res(chips)"
			("LOCATION" "R3732")
		)
		("@t6g_mb_lib.t6g(sch_1):page253_i12@pure_quanta.q_res(chips)"
			("LOCATION" "R3733")
		)
		("@t6g_mb_lib.t6g(sch_1):page253_i35@pure_quanta.q_res(chips)"
			("LOCATION" "R3734")
		)
		("@t6g_mb_lib.t6g(sch_1):page253_i34@pure_quanta.q_res(chips)"
			("LOCATION" "R3735")
		)
		("@t6g_mb_lib.t6g(sch_1):page253_i37@pure_quanta.q_res(chips)"
			("LOCATION" "R3736")
		)
		("@t6g_mb_lib.t6g(sch_1):page253_i38@pure_quanta.q_res(chips)"
			("LOCATION" "R3737")
		)
		("@t6g_mb_lib.t6g(sch_1):page253_i63@pure_quanta.q_res(chips)"
			("LOCATION" "R3741")
		)
		("@t6g_mb_lib.t6g(sch_1):page253_i64@pure_quanta.q_res(chips)"
			("LOCATION" "R3742")
		)
		("@t6g_mb_lib.t6g(sch_1):page253_i66@pure_quanta.q_res(chips)"
			("LOCATION" "R3743")
		)
		("@t6g_mb_lib.t6g(sch_1):page338_i2@pure_quanta.dummy_symbol(chips)"
			("LOCATION" "DM2")
		)
		("@t6g_mb_lib.t6g(sch_1):page338_i3@pure_quanta.dummy_symbol(chips)"
			("LOCATION" "DM3")
		)
		("@t6g_mb_lib.t6g(sch_1):page338_i4@pure_quanta.dummy_symbol(chips)"
			("LOCATION" "DM4")
		)
		("@t6g_mb_lib.t6g(sch_1):page338_i5@pure_quanta.dummy_symbol(chips)"
			("LOCATION" "DM5")
		)
		("@t6g_mb_lib.t6g(sch_1):page338_i6@pure_quanta.dummy_symbol(chips)"
			("LOCATION" "DM11")
		)
		("@t6g_mb_lib.t6g(sch_1):page335_i15@pure_quanta.hole(chips)"
			("LOCATION" "H1")
		)
		("@t6g_mb_lib.t6g(sch_1):page335_i11@pure_quanta.hole(chips)"
			("LOCATION" "H2")
		)
		("@t6g_mb_lib.t6g(sch_1):page335_i7@pure_quanta.hole(chips)"
			("LOCATION" "H3")
		)
		("@t6g_mb_lib.t6g(sch_1):page335_i3@pure_quanta.hole(chips)"
			("LOCATION" "H4")
		)
		("@t6g_mb_lib.t6g(sch_1):page335_i1@pure_quanta.hole(chips)"
			("LOCATION" "H5")
		)
		("@t6g_mb_lib.t6g(sch_1):page335_i16@pure_quanta.hole(chips)"
			("LOCATION" "H6")
		)
		("@t6g_mb_lib.t6g(sch_1):page335_i13@pure_quanta.hole(chips)"
			("LOCATION" "H7")
		)
		("@t6g_mb_lib.t6g(sch_1):page335_i9@pure_quanta.hole(chips)"
			("LOCATION" "H8")
		)
		("@t6g_mb_lib.t6g(sch_1):page335_i5@pure_quanta.hole(chips)"
			("LOCATION" "H9")
		)
		("@t6g_mb_lib.t6g(sch_1):page335_i19@pure_quanta.hole(chips)"
			("LOCATION" "H10")
		)
		("@t6g_mb_lib.t6g(sch_1):page335_i20@pure_quanta.hole(chips)"
			("LOCATION" "H11")
		)
		("@t6g_mb_lib.t6g(sch_1):page335_i21@pure_quanta.hole(chips)"
			("LOCATION" "H12")
		)
		("@t6g_mb_lib.t6g(sch_1):page335_i22@pure_quanta.hole(chips)"
			("LOCATION" "H13")
		)
		("@t6g_mb_lib.t6g(sch_1):page335_i23@pure_quanta.hole(chips)"
			("LOCATION" "H14")
		)
		("@t6g_mb_lib.t6g(sch_1):page335_i24@pure_quanta.hole(chips)"
			("LOCATION" "H15")
		)
		("@t6g_mb_lib.t6g(sch_1):page335_i30@pure_quanta.hole(chips)"
			("LOCATION" "H16")
		)
		("@t6g_mb_lib.t6g(sch_1):page335_i29@pure_quanta.hole(chips)"
			("LOCATION" "H17")
		)
		("@t6g_mb_lib.t6g(sch_1):page335_i28@pure_quanta.hole(chips)"
			("LOCATION" "H18")
		)
		("@t6g_mb_lib.t6g(sch_1):page335_i27@pure_quanta.hole(chips)"
			("LOCATION" "H19")
		)
		("@t6g_mb_lib.t6g(sch_1):page335_i25@pure_quanta.hole(chips)"
			("LOCATION" "H20")
		)
		("@t6g_mb_lib.t6g(sch_1):page335_i26@pure_quanta.hole(chips)"
			("LOCATION" "H21")
		)
		("@t6g_mb_lib.t6g(sch_1):page335_i31@pure_quanta.hole(chips)"
			("LOCATION" "H22")
		)
		("@t6g_mb_lib.t6g(sch_1):page335_i34@pure_quanta.hole(chips)"
			("LOCATION" "H23")
		)
		("@t6g_mb_lib.t6g(sch_1):page335_i79@pure_quanta.hole(chips)"
			("LOCATION" "H45")
		)
		("@t6g_mb_lib.t6g(sch_1):page335_i83@pure_quanta.hole(chips)"
			("LOCATION" "H101")
		)
		("@t6g_mb_lib.t6g(sch_1):page335_i81@pure_quanta.hole(chips)"
			("LOCATION" "H103")
		)
		("@t6g_mb_lib.t6g(sch_1):page335_i82@pure_quanta.hole(chips)"
			("LOCATION" "H104")
		)
		("@t6g_mb_lib.t6g(sch_1):page335_i91@pure_quanta.hole(chips)"
			("LOCATION" "H140")
		)
		("@t6g_mb_lib.t6g(sch_1):page335_i89@pure_quanta.hole(chips)"
			("LOCATION" "H141")
		)
		("@t6g_mb_lib.t6g(sch_1):page335_i99@pure_quanta.hole(chips)"
			("LOCATION" "H143")
		)
		("@t6g_mb_lib.t6g(sch_1):page335_i100@pure_quanta.hole(chips)"
			("LOCATION" "H144")
		)
		("@t6g_mb_lib.t6g(sch_1):page335_i104@pure_quanta.hole(chips)"
			("LOCATION" "H145")
		)
		("@t6g_mb_lib.t6g(sch_1):page335_i102@pure_quanta.hole(chips)"
			("LOCATION" "H146")
		)
		("@t6g_mb_lib.t6g(sch_1):page335_i106@pure_quanta.hole(chips)"
			("LOCATION" "H147")
		)
		("@t6g_mb_lib.t6g(sch_1):page335_i112@pure_quanta.hole(chips)"
			("LOCATION" "H148")
		)
		("@t6g_mb_lib.t6g(sch_1):page335_i113@pure_quanta.hole(chips)"
			("LOCATION" "H149")
		)
		("@t6g_mb_lib.t6g(sch_1):page335_i108@pure_quanta.hole(chips)"
			("LOCATION" "H150")
		)
		("@t6g_mb_lib.t6g(sch_1):page335_i110@pure_quanta.hole(chips)"
			("LOCATION" "H151")
		)
		("@t6g_mb_lib.t6g(sch_1):page203_i53@pure_quanta.conn4_532900480(chips)"
			("LOCATION" "J40")
		)
		("@t6g_mb_lib.t6g(sch_1):page203_i48@pure_quanta.q_res(chips)"
			("LOCATION" "R316")
		)
		("@t6g_mb_lib.t6g(sch_1):page203_i47@pure_quanta.q_res(chips)"
			("LOCATION" "R371")
		)
		("@t6g_mb_lib.t6g(sch_1):page203_i43@pure_quanta.q_res(chips)"
			("LOCATION" "R372")
		)
		("@t6g_mb_lib.t6g(sch_1):page203_i42@pure_quanta.q_res(chips)"
			("LOCATION" "R373")
		)
		("@t6g_mb_lib.t6g(sch_1):page203_i41@pure_quanta.q_res(chips)"
			("LOCATION" "R374")
		)
		("@t6g_mb_lib.t6g(sch_1):page203_i44@pure_quanta.q_res(chips)"
			("LOCATION" "R394")
		)
		("@t6g_mb_lib.t6g(sch_1):page203_i46@pure_quanta.q_res(chips)"
			("LOCATION" "R395")
		)
		("@t6g_mb_lib.t6g(sch_1):page203_i45@pure_quanta.q_res(chips)"
			("LOCATION" "R396")
		)
		("@t6g_mb_lib.t6g(sch_1):page203_i50@pure_quanta.q_res(chips)"
			("LOCATION" "R398")
		)
		("@t6g_mb_lib.t6g(sch_1):page203_i51@pure_quanta.q_res(chips)"
			("LOCATION" "R399")
		)
		("@t6g_mb_lib.t6g(sch_1):page203_i52@pure_quanta.q_res(chips)"
			("LOCATION" "R400")
		)
		("@t6g_mb_lib.t6g(sch_1):page203_i49@pure_quanta.q_res(chips)"
			("LOCATION" "R401")
		)
		("@t6g_mb_lib.t6g(sch_1):page203_i55@pure_quanta.q_res(chips)"
			("LOCATION" "R677")
		)
		("@t6g_mb_lib.t6g(sch_1):page203_i58@pure_quanta.q_res(chips)"
			("LOCATION" "R678")
		)
		("@t6g_mb_lib.t6g(sch_1):page203_i57@pure_quanta.q_res(chips)"
			("LOCATION" "R705")
		)
		("@t6g_mb_lib.t6g(sch_1):page134_i1243@pure_quanta.sconn280_me1028040102011(chips)"
			("LOCATION" "J55")
		)
		("@t6g_mb_lib.t6g(sch_1):page135_i51@pure_quanta.sconn280_me1028040102011(chips)"
			("LOCATION" "J55")
		)
		("@t6g_mb_lib.t6g(sch_1):page135_i127@pure_quanta.q_res(chips)"
			("LOCATION" "R3853")
		)
		("@t6g_mb_lib.t6g(sch_1):page135_i130@pure_quanta.q_res(chips)"
			("LOCATION" "R3854")
		)
		("@t6g_mb_lib.t6g(sch_1):page136_i929@pure_quanta.sconn280_me1028040102011(chips)"
			("LOCATION" "J56")
		)
		("@t6g_mb_lib.t6g(sch_1):page137_i27@pure_quanta.sconn280_me1028040102011(chips)"
			("LOCATION" "J56")
		)
		("@t6g_mb_lib.t6g(sch_1):page137_i123@pure_quanta.q_res(chips)"
			("LOCATION" "R3855")
		)
		("@t6g_mb_lib.t6g(sch_1):page137_i125@pure_quanta.q_res(chips)"
			("LOCATION" "R3856")
		)
		("@t6g_mb_lib.t6g(sch_1):page334_i24@pure_quanta.delta_l(chips)"
			("LOCATION" "J63")
		)
		("@t6g_mb_lib.t6g(sch_1):page334_i23@pure_quanta.delta_l(chips)"
			("LOCATION" "J64")
		)
		("@t6g_mb_lib.t6g(sch_1):page334_i9@pure_quanta.delta_l(chips)"
			("LOCATION" "J67")
		)
		("@t6g_mb_lib.t6g(sch_1):page334_i7@pure_quanta.delta_l(chips)"
			("LOCATION" "J68")
		)
		("@t6g_mb_lib.t6g(sch_1):page334_i26@pure_quanta.delta_l(chips)"
			("LOCATION" "J69")
		)
		("@t6g_mb_lib.t6g(sch_1):page334_i14@pure_quanta.delta_l(chips)"
			("LOCATION" "J71")
		)
		("@t6g_mb_lib.t6g(sch_1):page334_i13@pure_quanta.delta_l(chips)"
			("LOCATION" "J72")
		)
		("@t6g_mb_lib.t6g(sch_1):page334_i12@pure_quanta.delta_l(chips)"
			("LOCATION" "J73")
		)
		("@t6g_mb_lib.t6g(sch_1):page334_i43@pure_quanta.delta_l(chips)"
			("LOCATION" "J76")
		)
		("@t6g_mb_lib.t6g(sch_1):page334_i35@pure_quanta.delta_l(chips)"
			("LOCATION" "J77")
		)
		("@t6g_mb_lib.t6g(sch_1):page334_i34@pure_quanta.delta_l(chips)"
			("LOCATION" "J78")
		)
		("@t6g_mb_lib.t6g(sch_1):page334_i33@pure_quanta.delta_l(chips)"
			("LOCATION" "J79")
		)
		("@t6g_mb_lib.t6g(sch_1):page334_i37@pure_quanta.delta_l(chips)"
			("LOCATION" "J84")
		)
		("@t6g_mb_lib.t6g(sch_1):page334_i36@pure_quanta.delta_l(chips)"
			("LOCATION" "J85")
		)
		("@t6g_mb_lib.t6g(sch_1):page334_i32@pure_quanta.delta_l(chips)"
			("LOCATION" "J86")
		)
		("@t6g_mb_lib.t6g(sch_1):page334_i11@pure_quanta.delta_l(chips)"
			("LOCATION" "J279")
		)
		("@t6g_mb_lib.t6g(sch_1):page334_i10@pure_quanta.delta_l(chips)"
			("LOCATION" "J280")
		)
		("@t6g_mb_lib.t6g(sch_1):page334_i25@pure_quanta.delta_l(chips)"
			("LOCATION" "J281")
		)
		("@t6g_mb_lib.t6g(sch_1):page334_i8@pure_quanta.delta_l(chips)"
			("LOCATION" "J282")
		)
		("@t6g_mb_lib.t6g(sch_1):page334_i44@pure_quanta.delta_l(chips)"
			("LOCATION" "J283")
		)
		("@t6g_mb_lib.t6g(sch_1):page334_i31@pure_quanta.delta_l(chips)"
			("LOCATION" "J284")
		)
		("@t6g_mb_lib.t6g(sch_1):page334_i46@pure_quanta.delta_l(chips)"
			("LOCATION" "J285")
		)
		("@t6g_mb_lib.t6g(sch_1):page334_i45@pure_quanta.delta_l(chips)"
			("LOCATION" "J286")
		)
		("@t6g_mb_lib.t6g(sch_1):page334_i38@pure_quanta.delta_l(chips)"
			("LOCATION" "J287")
		)
		("@t6g_mb_lib.t6g(sch_1):page158_i68@pure_quanta.sconn56_g64v31312hr(chips)"
			("LOCATION" "J199")
		)
		("@t6g_mb_lib.t6g(sch_1):page159_i45@pure_quanta.sconn56_g64v31312hr(chips)"
			("LOCATION" "J200")
		)
		("@t6g_mb_lib.t6g(sch_1):page162_i45@pure_quanta.sconn56_g64v31312hr(chips)"
			("LOCATION" "J201")
		)
		("@t6g_mb_lib.t6g(sch_1):page163_i90@pure_quanta.sconn56_g64v31312hr(chips)"
			("LOCATION" "J202")
		)
		("@t6g_mb_lib.t6g(sch_1):page166_i45@pure_quanta.sconn56_g64v31312hr(chips)"
			("LOCATION" "J203")
		)
		("@t6g_mb_lib.t6g(sch_1):page167_i15@pure_quanta.sconn56_g64v31312hr(chips)"
			("LOCATION" "J204")
		)
		("@t6g_mb_lib.t6g(sch_1):page170_i47@pure_quanta.sconn56_g64v31312hr(chips)"
			("LOCATION" "J205")
		)
		("@t6g_mb_lib.t6g(sch_1):page171_i90@pure_quanta.sconn56_g64v31312hr(chips)"
			("LOCATION" "J206")
		)
		("@t6g_mb_lib.t6g(sch_1):page99_i66@pure_quanta.conn3_210hp1030br1(chips)"
			("LOCATION" "JP7")
		)
		("@t6g_mb_lib.t6g(sch_1):page99_i35@pure_quanta.mosfet_nch_dual(chips)"
			("LOCATION" "Q21")
		)
		("@t6g_mb_lib.t6g(sch_1):page99_i25@pure_quanta.mosfet_nch_dual(chips)"
			("LOCATION" "Q21")
		)
		("@t6g_mb_lib.t6g(sch_1):page99_i36@pure_quanta.mosfet_nch_dual(chips)"
			("LOCATION" "Q22")
		)
		("@t6g_mb_lib.t6g(sch_1):page99_i33@pure_quanta.mosfet_nch_dual(chips)"
			("LOCATION" "Q22")
		)
		("@t6g_mb_lib.t6g(sch_1):page99_i113@pure_quanta.mosfet_nch_dual(chips)"
			("LOCATION" "Q23")
		)
		("@t6g_mb_lib.t6g(sch_1):page99_i120@pure_quanta.mosfet_nch_dual(chips)"
			("LOCATION" "Q23")
		)
		("@t6g_mb_lib.t6g(sch_1):page99_i125@pure_quanta.mosfet_nch_dual(chips)"
			("LOCATION" "Q232")
		)
		("@t6g_mb_lib.t6g(sch_1):page99_i122@pure_quanta.mosfet_nch_dual(chips)"
			("LOCATION" "Q232")
		)
		("@t6g_mb_lib.t6g(sch_1):page99_i50@pure_quanta.q_res(chips)"
			("LOCATION" "R331")
		)
		("@t6g_mb_lib.t6g(sch_1):page99_i51@pure_quanta.q_res(chips)"
			("LOCATION" "R332")
		)
		("@t6g_mb_lib.t6g(sch_1):page99_i41@pure_quanta.q_res(chips)"
			("LOCATION" "R333")
		)
		("@t6g_mb_lib.t6g(sch_1):page99_i44@pure_quanta.q_res(chips)"
			("LOCATION" "R334")
		)
		("@t6g_mb_lib.t6g(sch_1):page99_i40@pure_quanta.q_res(chips)"
			("LOCATION" "R335")
		)
		("@t6g_mb_lib.t6g(sch_1):page99_i42@pure_quanta.q_res(chips)"
			("LOCATION" "R515")
		)
		("@t6g_mb_lib.t6g(sch_1):page99_i11@pure_quanta.q_res(chips)"
			("LOCATION" "R625")
		)
		("@t6g_mb_lib.t6g(sch_1):page99_i16@pure_quanta.q_res(chips)"
			("LOCATION" "R626")
		)
		("@t6g_mb_lib.t6g(sch_1):page99_i10@pure_quanta.q_res(chips)"
			("LOCATION" "R627")
		)
		("@t6g_mb_lib.t6g(sch_1):page99_i14@pure_quanta.q_res(chips)"
			("LOCATION" "R628")
		)
		("@t6g_mb_lib.t6g(sch_1):page99_i8@pure_quanta.q_res(chips)"
			("LOCATION" "R629")
		)
		("@t6g_mb_lib.t6g(sch_1):page99_i12@pure_quanta.q_res(chips)"
			("LOCATION" "R630")
		)
		("@t6g_mb_lib.t6g(sch_1):page99_i110@pure_quanta.q_res(chips)"
			("LOCATION" "R650")
		)
		("@t6g_mb_lib.t6g(sch_1):page99_i111@pure_quanta.q_res(chips)"
			("LOCATION" "R997")
		)
		("@t6g_mb_lib.t6g(sch_1):page99_i57@pure_quanta.q_res(chips)"
			("LOCATION" "R998")
		)
		("@t6g_mb_lib.t6g(sch_1):page99_i62@pure_quanta.q_res(chips)"
			("LOCATION" "R999")
		)
		("@t6g_mb_lib.t6g(sch_1):page99_i48@pure_quanta.q_res(chips)"
			("LOCATION" "R1000")
		)
		("@t6g_mb_lib.t6g(sch_1):page99_i59@pure_quanta.q_res(chips)"
			("LOCATION" "R1001")
		)
		("@t6g_mb_lib.t6g(sch_1):page99_i23@pure_quanta.q_res(chips)"
			("LOCATION" "R1002")
		)
		("@t6g_mb_lib.t6g(sch_1):page99_i32@pure_quanta.q_res(chips)"
			("LOCATION" "R1003")
		)
		("@t6g_mb_lib.t6g(sch_1):page99_i19@pure_quanta.q_res(chips)"
			("LOCATION" "R1004")
		)
		("@t6g_mb_lib.t6g(sch_1):page99_i20@pure_quanta.q_res(chips)"
			("LOCATION" "R1005")
		)
		("@t6g_mb_lib.t6g(sch_1):page99_i7@pure_quanta.q_res(chips)"
			("LOCATION" "R1006")
		)
		("@t6g_mb_lib.t6g(sch_1):page99_i28@pure_quanta.q_res(chips)"
			("LOCATION" "R1007")
		)
		("@t6g_mb_lib.t6g(sch_1):page99_i116@pure_quanta.q_res(chips)"
			("LOCATION" "R3548")
		)
		("@t6g_mb_lib.t6g(sch_1):page99_i128@pure_quanta.q_res(chips)"
			("LOCATION" "R3739")
		)
		("@t6g_mb_lib.t6g(sch_1):page99_i130@pure_quanta.q_res(chips)"
			("LOCATION" "R3740")
		)
		("@t6g_mb_lib.t6g(sch_1):page273_i333@pure_quanta.conn3_210hp1030br1(chips)"
			("LOCATION" "JP29")
		)
		("@t6g_mb_lib.t6g(sch_1):page273_i248@pure_quanta.q_res(chips)"
			("LOCATION" "R107")
		)
		("@t6g_mb_lib.t6g(sch_1):page273_i249@pure_quanta.q_res(chips)"
			("LOCATION" "R108")
		)
		("@t6g_mb_lib.t6g(sch_1):page273_i247@pure_quanta.q_res(chips)"
			("LOCATION" "R582")
		)
		("@t6g_mb_lib.t6g(sch_1):page273_i326@pure_quanta.q_res(chips)"
			("LOCATION" "R1319")
		)
		("@t6g_mb_lib.t6g(sch_1):page273_i325@pure_quanta.q_res(chips)"
			("LOCATION" "R1321")
		)
		("@t6g_mb_lib.t6g(sch_1):page273_i250@pure_quanta.q_res(chips)"
			("LOCATION" "R1525")
		)
		("@t6g_mb_lib.t6g(sch_1):page273_i251@pure_quanta.q_res(chips)"
			("LOCATION" "R1526")
		)
		("@t6g_mb_lib.t6g(sch_1):page273_i233@pure_quanta.q_res(chips)"
			("LOCATION" "R1661")
		)
		("@t6g_mb_lib.t6g(sch_1):page273_i232@pure_quanta.q_res(chips)"
			("LOCATION" "R1662")
		)
		("@t6g_mb_lib.t6g(sch_1):page273_i228@pure_quanta.q_res(chips)"
			("LOCATION" "R1663")
		)
		("@t6g_mb_lib.t6g(sch_1):page273_i229@pure_quanta.q_res(chips)"
			("LOCATION" "R1664")
		)
		("@t6g_mb_lib.t6g(sch_1):page273_i231@pure_quanta.q_res(chips)"
			("LOCATION" "R1668")
		)
		("@t6g_mb_lib.t6g(sch_1):page273_i230@pure_quanta.q_res(chips)"
			("LOCATION" "R1669")
		)
		("@t6g_mb_lib.t6g(sch_1):page273_i237@pure_quanta.q_res(chips)"
			("LOCATION" "R1670")
		)
		("@t6g_mb_lib.t6g(sch_1):page273_i236@pure_quanta.q_res(chips)"
			("LOCATION" "R1730")
		)
		("@t6g_mb_lib.t6g(sch_1):page273_i320@pure_quanta.q_res(chips)"
			("LOCATION" "R1731")
		)
		("@t6g_mb_lib.t6g(sch_1):page273_i226@pure_quanta.q_res(chips)"
			("LOCATION" "R1761")
		)
		("@t6g_mb_lib.t6g(sch_1):page273_i227@pure_quanta.q_res(chips)"
			("LOCATION" "R1762")
		)
		("@t6g_mb_lib.t6g(sch_1):page273_i253@pure_quanta.q_res(chips)"
			("LOCATION" "R2781")
		)
		("@t6g_mb_lib.t6g(sch_1):page273_i254@pure_quanta.q_res(chips)"
			("LOCATION" "R2782")
		)
		("@t6g_mb_lib.t6g(sch_1):page273_i328@pure_quanta.q_res(chips)"
			("LOCATION" "R2784")
		)
		("@t6g_mb_lib.t6g(sch_1):page273_i252@pure_quanta.q_res(chips)"
			("LOCATION" "R2785")
		)
		("@t6g_mb_lib.t6g(sch_1):page273_i246@pure_quanta.q_res(chips)"
			("LOCATION" "R2786")
		)
		("@t6g_mb_lib.t6g(sch_1):page273_i238@pure_quanta.q_res(chips)"
			("LOCATION" "R2818")
		)
		("@t6g_mb_lib.t6g(sch_1):page273_i239@pure_quanta.q_res(chips)"
			("LOCATION" "R2819")
		)
		("@t6g_mb_lib.t6g(sch_1):page273_i235@pure_quanta.q_res(chips)"
			("LOCATION" "R2820")
		)
		("@t6g_mb_lib.t6g(sch_1):page273_i234@pure_quanta.q_res(chips)"
			("LOCATION" "R2821")
		)
		("@t6g_mb_lib.t6g(sch_1):page273_i284@pure_quanta.q_res(chips)"
			("LOCATION" "R2822")
		)
		("@t6g_mb_lib.t6g(sch_1):page273_i283@pure_quanta.q_res(chips)"
			("LOCATION" "R2823")
		)
		("@t6g_mb_lib.t6g(sch_1):page273_i282@pure_quanta.q_res(chips)"
			("LOCATION" "R2824")
		)
		("@t6g_mb_lib.t6g(sch_1):page273_i281@pure_quanta.q_res(chips)"
			("LOCATION" "R2825")
		)
		("@t6g_mb_lib.t6g(sch_1):page273_i280@pure_quanta.q_res(chips)"
			("LOCATION" "R2826")
		)
		("@t6g_mb_lib.t6g(sch_1):page273_i279@pure_quanta.q_res(chips)"
			("LOCATION" "R2827")
		)
		("@t6g_mb_lib.t6g(sch_1):page273_i277@pure_quanta.q_res(chips)"
			("LOCATION" "R2828")
		)
		("@t6g_mb_lib.t6g(sch_1):page273_i278@pure_quanta.q_res(chips)"
			("LOCATION" "R2829")
		)
		("@t6g_mb_lib.t6g(sch_1):page273_i324@pure_quanta.q_res(chips)"
			("LOCATION" "R2830")
		)
		("@t6g_mb_lib.t6g(sch_1):page273_i323@pure_quanta.q_res(chips)"
			("LOCATION" "R2833")
		)
		("@t6g_mb_lib.t6g(sch_1):page273_i322@pure_quanta.q_res(chips)"
			("LOCATION" "R2840")
		)
		("@t6g_mb_lib.t6g(sch_1):page273_i321@pure_quanta.q_res(chips)"
			("LOCATION" "R2841")
		)
		("@t6g_mb_lib.t6g(sch_1):page273_i319@pure_quanta.q_res(chips)"
			("LOCATION" "R2842")
		)
		("@t6g_mb_lib.t6g(sch_1):page273_i317@pure_quanta.q_res(chips)"
			("LOCATION" "R2843")
		)
		("@t6g_mb_lib.t6g(sch_1):page273_i318@pure_quanta.q_res(chips)"
			("LOCATION" "R2844")
		)
		("@t6g_mb_lib.t6g(sch_1):page273_i316@pure_quanta.q_res(chips)"
			("LOCATION" "R2845")
		)
		("@t6g_mb_lib.t6g(sch_1):page273_i315@pure_quanta.q_res(chips)"
			("LOCATION" "R2846")
		)
		("@t6g_mb_lib.t6g(sch_1):page273_i336@pure_quanta.q_res(chips)"
			("LOCATION" "R3544")
		)
		("@t6g_mb_lib.t6g(sch_1):page273_i335@pure_quanta.q_res(chips)"
			("LOCATION" "R3545")
		)
		("@t6g_mb_lib.t6g(sch_1):page273_i341@pure_quanta.q_res(chips)"
			("LOCATION" "R3550")
		)
		("@t6g_mb_lib.t6g(sch_1):page273_i340@pure_quanta.q_res(chips)"
			("LOCATION" "R3551")
		)
		("@t6g_mb_lib.t6g(sch_1):page273_i346@pure_quanta.q_res(chips)"
			("LOCATION" "R3552")
		)
		("@t6g_mb_lib.t6g(sch_1):page273_i347@pure_quanta.q_res(chips)"
			("LOCATION" "R3553")
		)
		("@t6g_mb_lib.t6g(sch_1):page265_i42@pure_quanta.q_inductor4p_12(chips)"
			("LOCATION" "L74")
		)
		("@t6g_mb_lib.t6g(sch_1):page265_i4@pure_quanta.q_inductor4p_12(chips)"
			("LOCATION" "L75")
		)
		("@t6g_mb_lib.t6g(sch_1):page265_i32@pure_quanta.q_inductor4p_12(chips)"
			("LOCATION" "L76")
		)
		("@t6g_mb_lib.t6g(sch_1):page265_i31@pure_quanta.q_inductor4p_12(chips)"
			("LOCATION" "L104")
		)
		("@t6g_mb_lib.t6g(sch_1):page265_i41@pure_quanta.q_res(chips)"
			("LOCATION" "R1138")
		)
		("@t6g_mb_lib.t6g(sch_1):page265_i40@pure_quanta.q_res(chips)"
			("LOCATION" "R1139")
		)
		("@t6g_mb_lib.t6g(sch_1):page265_i45@pure_quanta.q_res(chips)"
			("LOCATION" "R1140")
		)
		("@t6g_mb_lib.t6g(sch_1):page265_i43@pure_quanta.q_res(chips)"
			("LOCATION" "R1141")
		)
		("@t6g_mb_lib.t6g(sch_1):page265_i9@pure_quanta.q_res(chips)"
			("LOCATION" "R1197")
		)
		("@t6g_mb_lib.t6g(sch_1):page265_i11@pure_quanta.q_res(chips)"
			("LOCATION" "R1198")
		)
		("@t6g_mb_lib.t6g(sch_1):page265_i10@pure_quanta.q_res(chips)"
			("LOCATION" "R1203")
		)
		("@t6g_mb_lib.t6g(sch_1):page265_i3@pure_quanta.q_res(chips)"
			("LOCATION" "R1206")
		)
		("@t6g_mb_lib.t6g(sch_1):page265_i35@pure_quanta.tpd2eusb30drtr(chips)"
			("LOCATION" "U85")
		)
		("@t6g_mb_lib.t6g(sch_1):page265_i44@pure_quanta.tpd2eusb30drtr(chips)"
			("LOCATION" "U86")
		)
		("@t6g_mb_lib.t6g(sch_1):page265_i18@pure_quanta.tpd2eusb30drtr(chips)"
			("LOCATION" "U113")
		)
		("@t6g_mb_lib.t6g(sch_1):page265_i22@pure_quanta.tpd2eusb30drtr(chips)"
			("LOCATION" "U162")
		)
		("@t6g_mb_lib.t6g(sch_1):page290_i130@pure_quanta.q_capp(chips)"
			("LOCATION" "PC16")
		)
		("@t6g_mb_lib.t6g(sch_1):page290_i8@pure_quanta.q_cap(chips)"
			("LOCATION" "PC292")
		)
		("@t6g_mb_lib.t6g(sch_1):page290_i30@pure_quanta.q_cap(chips)"
			("LOCATION" "PC293")
		)
		("@t6g_mb_lib.t6g(sch_1):page290_i18@pure_quanta.q_cap(chips)"
			("LOCATION" "PC294_P0_2")
		)
		("@t6g_mb_lib.t6g(sch_1):page290_i35@pure_quanta.q_cap(chips)"
			("LOCATION" "PC295_P0_1")
		)
		("@t6g_mb_lib.t6g(sch_1):page290_i22@pure_quanta.q_cap(chips)"
			("LOCATION" "PC296_P0_2")
		)
		("@t6g_mb_lib.t6g(sch_1):page290_i40@pure_quanta.q_cap(chips)"
			("LOCATION" "PC297_P0_1")
		)
		("@t6g_mb_lib.t6g(sch_1):page290_i23@pure_quanta.q_cap(chips)"
			("LOCATION" "PC298_P0_2")
		)
		("@t6g_mb_lib.t6g(sch_1):page290_i41@pure_quanta.q_cap(chips)"
			("LOCATION" "PC299_P0_1")
		)
		("@t6g_mb_lib.t6g(sch_1):page290_i44@pure_quanta.q_cap(chips)"
			("LOCATION" "PC300")
		)
		("@t6g_mb_lib.t6g(sch_1):page290_i62@pure_quanta.q_cap(chips)"
			("LOCATION" "PC301")
		)
		("@t6g_mb_lib.t6g(sch_1):page290_i24@pure_quanta.q_cap(chips)"
			("LOCATION" "PC302_P0_2")
		)
		("@t6g_mb_lib.t6g(sch_1):page290_i65@pure_quanta.q_cap(chips)"
			("LOCATION" "PC303_P0_1")
		)
		("@t6g_mb_lib.t6g(sch_1):page290_i46@pure_quanta.q_cap(chips)"
			("LOCATION" "PC304_P0_2")
		)
		("@t6g_mb_lib.t6g(sch_1):page290_i66@pure_quanta.q_cap(chips)"
			("LOCATION" "PC305_P0_1")
		)
		("@t6g_mb_lib.t6g(sch_1):page290_i47@pure_quanta.q_cap(chips)"
			("LOCATION" "PC306_P0_2")
		)
		("@t6g_mb_lib.t6g(sch_1):page290_i67@pure_quanta.q_cap(chips)"
			("LOCATION" "PC307_P0_1")
		)
		("@t6g_mb_lib.t6g(sch_1):page290_i111@pure_quanta.q_cap(chips)"
			("LOCATION" "PC308_P0_1")
		)
		("@t6g_mb_lib.t6g(sch_1):page290_i110@pure_quanta.q_cap(chips)"
			("LOCATION" "PC310_P0_1")
		)
		("@t6g_mb_lib.t6g(sch_1):page290_i128@pure_quanta.q_cap(chips)"
			("LOCATION" "PC311_P0_2")
		)
		("@t6g_mb_lib.t6g(sch_1):page290_i109@pure_quanta.q_cap(chips)"
			("LOCATION" "PC312_P0_1")
		)
		("@t6g_mb_lib.t6g(sch_1):page290_i127@pure_quanta.q_cap(chips)"
			("LOCATION" "PC313_P0_2")
		)
		("@t6g_mb_lib.t6g(sch_1):page290_i108@pure_quanta.q_cap(chips)"
			("LOCATION" "PC314_P0_1")
		)
		("@t6g_mb_lib.t6g(sch_1):page290_i74@pure_quanta.q_capp(chips)"
			("LOCATION" "PC315")
		)
		("@t6g_mb_lib.t6g(sch_1):page290_i56@pure_quanta.q_capp(chips)"
			("LOCATION" "PC316")
		)
		("@t6g_mb_lib.t6g(sch_1):page290_i76@pure_quanta.q_capp(chips)"
			("LOCATION" "PC318")
		)
		("@t6g_mb_lib.t6g(sch_1):page290_i58@pure_quanta.q_capp(chips)"
			("LOCATION" "PC319")
		)
		("@t6g_mb_lib.t6g(sch_1):page290_i77@pure_quanta.q_capp(chips)"
			("LOCATION" "PC321")
		)
		("@t6g_mb_lib.t6g(sch_1):page290_i59@pure_quanta.q_capp(chips)"
			("LOCATION" "PC322")
		)
		("@t6g_mb_lib.t6g(sch_1):page290_i55@pure_quanta.q_capp(chips)"
			("LOCATION" "PC323")
		)
		("@t6g_mb_lib.t6g(sch_1):page290_i84@pure_quanta.q_capp(chips)"
			("LOCATION" "PC324")
		)
		("@t6g_mb_lib.t6g(sch_1):page290_i81@pure_quanta.q_capp(chips)"
			("LOCATION" "PC325")
		)
		("@t6g_mb_lib.t6g(sch_1):page290_i79@pure_quanta.q_capp(chips)"
			("LOCATION" "PC326")
		)
		("@t6g_mb_lib.t6g(sch_1):page290_i54@pure_quanta.q_capp(chips)"
			("LOCATION" "PC1920")
		)
		("@t6g_mb_lib.t6g(sch_1):page290_i53@pure_quanta.q_capp(chips)"
			("LOCATION" "PC2336")
		)
		("@t6g_mb_lib.t6g(sch_1):page290_i122@pure_quanta.q_inductor4p_14(chips)"
			("LOCATION" "PL13")
		)
		("@t6g_mb_lib.t6g(sch_1):page290_i75@pure_quanta.q_inductor(chips)"
			("LOCATION" "PL15")
		)
		("@t6g_mb_lib.t6g(sch_1):page290_i104@pure_quanta.q_inductor4p_14(chips)"
			("LOCATION" "PL114")
		)
		("@t6g_mb_lib.t6g(sch_1):page290_i2@pure_quanta.q_res(chips)"
			("LOCATION" "PR150")
		)
		("@t6g_mb_lib.t6g(sch_1):page290_i14@pure_quanta.q_res(chips)"
			("LOCATION" "PR151")
		)
		("@t6g_mb_lib.t6g(sch_1):page290_i11@pure_quanta.q_res(chips)"
			("LOCATION" "PR152")
		)
		("@t6g_mb_lib.t6g(sch_1):page290_i32@pure_quanta.q_res(chips)"
			("LOCATION" "PR153")
		)
		("@t6g_mb_lib.t6g(sch_1):page290_i124@pure_quanta.q_res(chips)"
			("LOCATION" "PR154")
		)
		("@t6g_mb_lib.t6g(sch_1):page290_i112@pure_quanta.q_res(chips)"
			("LOCATION" "PR155")
		)
		("@t6g_mb_lib.t6g(sch_1):page290_i87@pure_quanta.isl99390frztr5935(chips)"
			("LOCATION" "PU12_P0_2")
		)
		("@t6g_mb_lib.t6g(sch_1):page290_i21@pure_quanta.isl99390frztr5935(chips)"
			("LOCATION" "PU13_P0_1")
		)
		("@t6g_mb_lib.t6g(sch_1):page330_i8@pure_quanta.q_cap(chips)"
			("LOCATION" "PC21")
		)
		("@t6g_mb_lib.t6g(sch_1):page330_i5@pure_quanta.q_cap(chips)"
			("LOCATION" "PC22")
		)
		("@t6g_mb_lib.t6g(sch_1):page330_i7@pure_quanta.q_cap(chips)"
			("LOCATION" "PC23")
		)
		("@t6g_mb_lib.t6g(sch_1):page330_i9@pure_quanta.q_cap(chips)"
			("LOCATION" "PC29")
		)
		("@t6g_mb_lib.t6g(sch_1):page330_i20@pure_quanta.q_cap(chips)"
			("LOCATION" "PC31")
		)
		("@t6g_mb_lib.t6g(sch_1):page330_i17@pure_quanta.q_cap(chips)"
			("LOCATION" "PC32")
		)
		("@t6g_mb_lib.t6g(sch_1):page330_i15@pure_quanta.q_cap(chips)"
			("LOCATION" "PC33")
		)
		("@t6g_mb_lib.t6g(sch_1):page330_i12@pure_quanta.q_cap(chips)"
			("LOCATION" "PC34")
		)
		("@t6g_mb_lib.t6g(sch_1):page330_i11@pure_quanta.q_cap(chips)"
			("LOCATION" "PC35")
		)
		("@t6g_mb_lib.t6g(sch_1):page330_i18@pure_quanta.q_cap(chips)"
			("LOCATION" "PC36")
		)
		("@t6g_mb_lib.t6g(sch_1):page330_i16@pure_quanta.q_cap(chips)"
			("LOCATION" "PC37")
		)
		("@t6g_mb_lib.t6g(sch_1):page330_i14@pure_quanta.q_cap(chips)"
			("LOCATION" "PC38")
		)
		("@t6g_mb_lib.t6g(sch_1):page330_i13@pure_quanta.q_cap(chips)"
			("LOCATION" "PC39")
		)
		("@t6g_mb_lib.t6g(sch_1):page330_i23@pure_quanta.q_cap(chips)"
			("LOCATION" "PC239")
		)
		("@t6g_mb_lib.t6g(sch_1):page330_i31@pure_quanta.q_cap(chips)"
			("LOCATION" "PC272")
		)
		("@t6g_mb_lib.t6g(sch_1):page330_i26@pure_quanta.q_cap(chips)"
			("LOCATION" "PC273")
		)
		("@t6g_mb_lib.t6g(sch_1):page330_i40@pure_quanta.q_cap(chips)"
			("LOCATION" "PC693")
		)
		("@t6g_mb_lib.t6g(sch_1):page330_i3@pure_quanta.q_inductor(chips)"
			("LOCATION" "PL1")
		)
		("@t6g_mb_lib.t6g(sch_1):page330_i37@pure_quanta.q_inductor(chips)"
			("LOCATION" "PL200")
		)
		("@t6g_mb_lib.t6g(sch_1):page330_i6@pure_quanta.q_res(chips)"
			("LOCATION" "PR24")
		)
		("@t6g_mb_lib.t6g(sch_1):page330_i44@pure_quanta.q_res(chips)"
			("LOCATION" "PR27")
		)
		("@t6g_mb_lib.t6g(sch_1):page330_i34@pure_quanta.q_res(chips)"
			("LOCATION" "PR532")
		)
		("@t6g_mb_lib.t6g(sch_1):page330_i22@pure_quanta.q_res(chips)"
			("LOCATION" "PR533")
		)
		("@t6g_mb_lib.t6g(sch_1):page330_i24@pure_quanta.q_res(chips)"
			("LOCATION" "PR534")
		)
		("@t6g_mb_lib.t6g(sch_1):page330_i39@pure_quanta.q_res(chips)"
			("LOCATION" "PR1036")
		)
		("@t6g_mb_lib.t6g(sch_1):page330_i42@pure_quanta.q_res(chips)"
			("LOCATION" "PR1037")
		)
		("@t6g_mb_lib.t6g(sch_1):page330_i29@pure_quanta.mpq8626gdz(chips)"
			("LOCATION" "PU100")
		)
		("@t6g_mb_lib.t6g(sch_1):page308_i105@pure_quanta.q_capp(chips)"
			("LOCATION" "PC83")
		)
		("@t6g_mb_lib.t6g(sch_1):page308_i54@pure_quanta.q_capp(chips)"
			("LOCATION" "PC189")
		)
		("@t6g_mb_lib.t6g(sch_1):page308_i8@pure_quanta.q_cap(chips)"
			("LOCATION" "PC556")
		)
		("@t6g_mb_lib.t6g(sch_1):page308_i29@pure_quanta.q_cap(chips)"
			("LOCATION" "PC557")
		)
		("@t6g_mb_lib.t6g(sch_1):page308_i16@pure_quanta.q_cap(chips)"
			("LOCATION" "PC558_P1_2")
		)
		("@t6g_mb_lib.t6g(sch_1):page308_i32@pure_quanta.q_cap(chips)"
			("LOCATION" "PC559_P1_1")
		)
		("@t6g_mb_lib.t6g(sch_1):page308_i21@pure_quanta.q_cap(chips)"
			("LOCATION" "PC560_P1_2")
		)
		("@t6g_mb_lib.t6g(sch_1):page308_i38@pure_quanta.q_cap(chips)"
			("LOCATION" "PC561_P1_1")
		)
		("@t6g_mb_lib.t6g(sch_1):page308_i39@pure_quanta.q_cap(chips)"
			("LOCATION" "PC562_P1_2")
		)
		("@t6g_mb_lib.t6g(sch_1):page308_i40@pure_quanta.q_cap(chips)"
			("LOCATION" "PC563_P1_1")
		)
		("@t6g_mb_lib.t6g(sch_1):page308_i42@pure_quanta.q_cap(chips)"
			("LOCATION" "PC564")
		)
		("@t6g_mb_lib.t6g(sch_1):page308_i60@pure_quanta.q_cap(chips)"
			("LOCATION" "PC565")
		)
		("@t6g_mb_lib.t6g(sch_1):page308_i44@pure_quanta.q_cap(chips)"
			("LOCATION" "PC566_P1_2")
		)
		("@t6g_mb_lib.t6g(sch_1):page308_i61@pure_quanta.q_cap(chips)"
			("LOCATION" "PC567_P1_1")
		)
		("@t6g_mb_lib.t6g(sch_1):page308_i45@pure_quanta.q_cap(chips)"
			("LOCATION" "PC568_P1_2")
		)
		("@t6g_mb_lib.t6g(sch_1):page308_i62@pure_quanta.q_cap(chips)"
			("LOCATION" "PC569_P1_1")
		)
		("@t6g_mb_lib.t6g(sch_1):page308_i46@pure_quanta.q_cap(chips)"
			("LOCATION" "PC570_P1_2")
		)
		("@t6g_mb_lib.t6g(sch_1):page308_i66@pure_quanta.q_cap(chips)"
			("LOCATION" "PC571_P1_1")
		)
		("@t6g_mb_lib.t6g(sch_1):page308_i64@pure_quanta.q_cap(chips)"
			("LOCATION" "PC572_P1_1")
		)
		("@t6g_mb_lib.t6g(sch_1):page308_i65@pure_quanta.q_cap(chips)"
			("LOCATION" "PC574_P1_1")
		)
		("@t6g_mb_lib.t6g(sch_1):page308_i100@pure_quanta.q_cap(chips)"
			("LOCATION" "PC575_P1_2")
		)
		("@t6g_mb_lib.t6g(sch_1):page308_i68@pure_quanta.q_cap(chips)"
			("LOCATION" "PC576_P1_1")
		)
		("@t6g_mb_lib.t6g(sch_1):page308_i99@pure_quanta.q_cap(chips)"
			("LOCATION" "PC577_P1_2")
		)
		("@t6g_mb_lib.t6g(sch_1):page308_i69@pure_quanta.q_cap(chips)"
			("LOCATION" "PC578_P1_1")
		)
		("@t6g_mb_lib.t6g(sch_1):page308_i73@pure_quanta.q_capp(chips)"
			("LOCATION" "PC579")
		)
		("@t6g_mb_lib.t6g(sch_1):page308_i55@pure_quanta.q_capp(chips)"
			("LOCATION" "PC580")
		)
		("@t6g_mb_lib.t6g(sch_1):page308_i74@pure_quanta.q_capp(chips)"
			("LOCATION" "PC582")
		)
		("@t6g_mb_lib.t6g(sch_1):page308_i56@pure_quanta.q_capp(chips)"
			("LOCATION" "PC583")
		)
		("@t6g_mb_lib.t6g(sch_1):page308_i83@pure_quanta.q_capp(chips)"
			("LOCATION" "PC585")
		)
		("@t6g_mb_lib.t6g(sch_1):page308_i79@pure_quanta.q_capp(chips)"
			("LOCATION" "PC586")
		)
		("@t6g_mb_lib.t6g(sch_1):page308_i75@pure_quanta.q_capp(chips)"
			("LOCATION" "PC587")
		)
		("@t6g_mb_lib.t6g(sch_1):page308_i84@pure_quanta.q_capp(chips)"
			("LOCATION" "PC588")
		)
		("@t6g_mb_lib.t6g(sch_1):page308_i81@pure_quanta.q_capp(chips)"
			("LOCATION" "PC589")
		)
		("@t6g_mb_lib.t6g(sch_1):page308_i77@pure_quanta.q_capp(chips)"
			("LOCATION" "PC590")
		)
		("@t6g_mb_lib.t6g(sch_1):page308_i53@pure_quanta.q_capp(chips)"
			("LOCATION" "PC1990")
		)
		("@t6g_mb_lib.t6g(sch_1):page308_i103@pure_quanta.q_inductor4p_14(chips)"
			("LOCATION" "PL30")
		)
		("@t6g_mb_lib.t6g(sch_1):page308_i89@pure_quanta.q_inductor4p_14(chips)"
			("LOCATION" "PL31")
		)
		("@t6g_mb_lib.t6g(sch_1):page308_i71@pure_quanta.q_inductor(chips)"
			("LOCATION" "PL32")
		)
		("@t6g_mb_lib.t6g(sch_1):page308_i2@pure_quanta.q_res(chips)"
			("LOCATION" "PR325")
		)
		("@t6g_mb_lib.t6g(sch_1):page308_i12@pure_quanta.q_res(chips)"
			("LOCATION" "PR326")
		)
		("@t6g_mb_lib.t6g(sch_1):page308_i13@pure_quanta.q_res(chips)"
			("LOCATION" "PR327")
		)
		("@t6g_mb_lib.t6g(sch_1):page308_i31@pure_quanta.q_res(chips)"
			("LOCATION" "PR328")
		)
		("@t6g_mb_lib.t6g(sch_1):page308_i102@pure_quanta.q_res(chips)"
			("LOCATION" "PR329")
		)
		("@t6g_mb_lib.t6g(sch_1):page308_i90@pure_quanta.q_res(chips)"
			("LOCATION" "PR330")
		)
		("@t6g_mb_lib.t6g(sch_1):page308_i18@pure_quanta.isl99390frztr5935(chips)"
			("LOCATION" "PU30_P1_2")
		)
		("@t6g_mb_lib.t6g(sch_1):page308_i20@pure_quanta.isl99390frztr5935(chips)"
			("LOCATION" "PU31_P1_1")
		)
		("@t6g_mb_lib.t6g(sch_1):page299_i10@pure_quanta.q_cap(chips)"
			("LOCATION" "PC175")
		)
		("@t6g_mb_lib.t6g(sch_1):page299_i18@pure_quanta.q_cap(chips)"
			("LOCATION" "PC176")
		)
		("@t6g_mb_lib.t6g(sch_1):page299_i31@pure_quanta.q_cap(chips)"
			("LOCATION" "PC177")
		)
		("@t6g_mb_lib.t6g(sch_1):page299_i21@pure_quanta.q_cap(chips)"
			("LOCATION" "PC178")
		)
		("@t6g_mb_lib.t6g(sch_1):page299_i35@pure_quanta.q_cap(chips)"
			("LOCATION" "PC179")
		)
		("@t6g_mb_lib.t6g(sch_1):page299_i32@pure_quanta.q_cap(chips)"
			("LOCATION" "PC180")
		)
		("@t6g_mb_lib.t6g(sch_1):page299_i22@pure_quanta.q_cap(chips)"
			("LOCATION" "PC181")
		)
		("@t6g_mb_lib.t6g(sch_1):page299_i24@pure_quanta.q_cap(chips)"
			("LOCATION" "PC184")
		)
		("@t6g_mb_lib.t6g(sch_1):page299_i25@pure_quanta.q_cap(chips)"
			("LOCATION" "PC186")
		)
		("@t6g_mb_lib.t6g(sch_1):page299_i28@pure_quanta.q_capp(chips)"
			("LOCATION" "PC1900")
		)
		("@t6g_mb_lib.t6g(sch_1):page299_i27@pure_quanta.q_capp(chips)"
			("LOCATION" "PC2180")
		)
		("@t6g_mb_lib.t6g(sch_1):page299_i23@pure_quanta.q_inductor(chips)"
			("LOCATION" "PL3")
		)
		("@t6g_mb_lib.t6g(sch_1):page299_i14@pure_quanta.q_res(chips)"
			("LOCATION" "PR97")
		)
		("@t6g_mb_lib.t6g(sch_1):page299_i2@pure_quanta.q_res(chips)"
			("LOCATION" "PR1709")
		)
		("@t6g_mb_lib.t6g(sch_1):page298_i174@pure_quanta.q_cap(chips)"
			("LOCATION" "PC187")
		)
		("@t6g_mb_lib.t6g(sch_1):page298_i153@pure_quanta.q_cap(chips)"
			("LOCATION" "PC188")
		)
		("@t6g_mb_lib.t6g(sch_1):page298_i178@pure_quanta.q_cap(chips)"
			("LOCATION" "PC189_P0_1")
		)
		("@t6g_mb_lib.t6g(sch_1):page298_i167@pure_quanta.q_cap(chips)"
			("LOCATION" "PC190_P0_2")
		)
		("@t6g_mb_lib.t6g(sch_1):page298_i179@pure_quanta.q_cap(chips)"
			("LOCATION" "PC191_P0_1")
		)
		("@t6g_mb_lib.t6g(sch_1):page298_i168@pure_quanta.q_cap(chips)"
			("LOCATION" "PC192_P0_2")
		)
		("@t6g_mb_lib.t6g(sch_1):page298_i205@pure_quanta.q_cap(chips)"
			("LOCATION" "PC193")
		)
		("@t6g_mb_lib.t6g(sch_1):page298_i183@pure_quanta.q_cap(chips)"
			("LOCATION" "PC194")
		)
		("@t6g_mb_lib.t6g(sch_1):page298_i204@pure_quanta.q_cap(chips)"
			("LOCATION" "PC195_P0_1")
		)
		("@t6g_mb_lib.t6g(sch_1):page298_i186@pure_quanta.q_cap(chips)"
			("LOCATION" "PC196_P0_2")
		)
		("@t6g_mb_lib.t6g(sch_1):page298_i206@pure_quanta.q_cap(chips)"
			("LOCATION" "PC197_P0_1")
		)
		("@t6g_mb_lib.t6g(sch_1):page298_i187@pure_quanta.q_cap(chips)"
			("LOCATION" "PC198_P0_2")
		)
		("@t6g_mb_lib.t6g(sch_1):page298_i191@pure_quanta.q_cap(chips)"
			("LOCATION" "PC199_P0_1")
		)
		("@t6g_mb_lib.t6g(sch_1):page298_i192@pure_quanta.q_cap(chips)"
			("LOCATION" "PC202_P0_1")
		)
		("@t6g_mb_lib.t6g(sch_1):page298_i194@pure_quanta.q_cap(chips)"
			("LOCATION" "PC203_P0_2")
		)
		("@t6g_mb_lib.t6g(sch_1):page298_i197@pure_quanta.q_cap(chips)"
			("LOCATION" "PC204_P0_1")
		)
		("@t6g_mb_lib.t6g(sch_1):page298_i195@pure_quanta.q_cap(chips)"
			("LOCATION" "PC205_P0_2")
		)
		("@t6g_mb_lib.t6g(sch_1):page298_i213@pure_quanta.q_capp(chips)"
			("LOCATION" "PC207")
		)
		("@t6g_mb_lib.t6g(sch_1):page298_i214@pure_quanta.q_capp(chips)"
			("LOCATION" "PC208")
		)
		("@t6g_mb_lib.t6g(sch_1):page298_i201@pure_quanta.q_capp(chips)"
			("LOCATION" "PC1573")
		)
		("@t6g_mb_lib.t6g(sch_1):page298_i199@pure_quanta.q_capp(chips)"
			("LOCATION" "PC1574")
		)
		("@t6g_mb_lib.t6g(sch_1):page298_i202@pure_quanta.q_capp(chips)"
			("LOCATION" "PC1575")
		)
		("@t6g_mb_lib.t6g(sch_1):page298_i200@pure_quanta.q_capp(chips)"
			("LOCATION" "PC1576")
		)
		("@t6g_mb_lib.t6g(sch_1):page298_i215@pure_quanta.q_capp(chips)"
			("LOCATION" "PC1579")
		)
		("@t6g_mb_lib.t6g(sch_1):page298_i207@pure_quanta.q_inductor(chips)"
			("LOCATION" "PL4")
		)
		("@t6g_mb_lib.t6g(sch_1):page298_i184@pure_quanta.q_inductor(chips)"
			("LOCATION" "PL5")
		)
		("@t6g_mb_lib.t6g(sch_1):page298_i211@pure_quanta.q_inductor(chips)"
			("LOCATION" "PL6")
		)
		("@t6g_mb_lib.t6g(sch_1):page298_i175@pure_quanta.q_res(chips)"
			("LOCATION" "PR101")
		)
		("@t6g_mb_lib.t6g(sch_1):page298_i158@pure_quanta.q_res(chips)"
			("LOCATION" "PR102")
		)
		("@t6g_mb_lib.t6g(sch_1):page298_i146@pure_quanta.q_res(chips)"
			("LOCATION" "PR1707")
		)
		("@t6g_mb_lib.t6g(sch_1):page298_i156@pure_quanta.q_res(chips)"
			("LOCATION" "PR1708")
		)
		("@t6g_mb_lib.t6g(sch_1):page297_i35@pure_quanta.q_cap(chips)"
			("LOCATION" "PC214")
		)
		("@t6g_mb_lib.t6g(sch_1):page297_i65@pure_quanta.q_cap(chips)"
			("LOCATION" "PC217")
		)
		("@t6g_mb_lib.t6g(sch_1):page297_i69@pure_quanta.q_cap(chips)"
			("LOCATION" "PC218")
		)
		("@t6g_mb_lib.t6g(sch_1):page297_i37@pure_quanta.q_cap(chips)"
			("LOCATION" "PC219")
		)
		("@t6g_mb_lib.t6g(sch_1):page297_i38@pure_quanta.q_cap(chips)"
			("LOCATION" "PC220")
		)
		("@t6g_mb_lib.t6g(sch_1):page297_i49@pure_quanta.q_cap(chips)"
			("LOCATION" "PC221")
		)
		("@t6g_mb_lib.t6g(sch_1):page297_i88@pure_quanta.q_cap(chips)"
			("LOCATION" "PC223")
		)
		("@t6g_mb_lib.t6g(sch_1):page297_i92@pure_quanta.q_cap(chips)"
			("LOCATION" "PC225")
		)
		("@t6g_mb_lib.t6g(sch_1):page297_i90@pure_quanta.q_cap(chips)"
			("LOCATION" "PC1372")
		)
		("@t6g_mb_lib.t6g(sch_1):page297_i15@pure_quanta.q_short(chips)"
			("LOCATION" "PJ45")
		)
		("@t6g_mb_lib.t6g(sch_1):page297_i9@pure_quanta.q_short(chips)"
			("LOCATION" "PJ46")
		)
		("@t6g_mb_lib.t6g(sch_1):page297_i3@pure_quanta.q_res(chips)"
			("LOCATION" "PR105")
		)
		("@t6g_mb_lib.t6g(sch_1):page297_i28@pure_quanta.q_res(chips)"
			("LOCATION" "PR107")
		)
		("@t6g_mb_lib.t6g(sch_1):page297_i68@pure_quanta.q_res(chips)"
			("LOCATION" "PR109")
		)
		("@t6g_mb_lib.t6g(sch_1):page297_i67@pure_quanta.q_res(chips)"
			("LOCATION" "PR110")
		)
		("@t6g_mb_lib.t6g(sch_1):page297_i64@pure_quanta.q_res(chips)"
			("LOCATION" "PR111")
		)
		("@t6g_mb_lib.t6g(sch_1):page297_i63@pure_quanta.q_res(chips)"
			("LOCATION" "PR112")
		)
		("@t6g_mb_lib.t6g(sch_1):page297_i62@pure_quanta.q_res(chips)"
			("LOCATION" "PR113")
		)
		("@t6g_mb_lib.t6g(sch_1):page297_i61@pure_quanta.q_res(chips)"
			("LOCATION" "PR114")
		)
		("@t6g_mb_lib.t6g(sch_1):page297_i60@pure_quanta.q_res(chips)"
			("LOCATION" "PR115")
		)
		("@t6g_mb_lib.t6g(sch_1):page297_i59@pure_quanta.q_res(chips)"
			("LOCATION" "PR116")
		)
		("@t6g_mb_lib.t6g(sch_1):page297_i31@pure_quanta.q_res(chips)"
			("LOCATION" "PR117")
		)
		("@t6g_mb_lib.t6g(sch_1):page297_i30@pure_quanta.q_res(chips)"
			("LOCATION" "PR118")
		)
		("@t6g_mb_lib.t6g(sch_1):page297_i32@pure_quanta.q_res(chips)"
			("LOCATION" "PR119")
		)
		("@t6g_mb_lib.t6g(sch_1):page297_i58@pure_quanta.q_res(chips)"
			("LOCATION" "PR120")
		)
		("@t6g_mb_lib.t6g(sch_1):page297_i45@pure_quanta.q_res(chips)"
			("LOCATION" "PR121")
		)
		("@t6g_mb_lib.t6g(sch_1):page297_i33@pure_quanta.q_res(chips)"
			("LOCATION" "PR122")
		)
		("@t6g_mb_lib.t6g(sch_1):page297_i95@pure_quanta.q_res(chips)"
			("LOCATION" "PR130")
		)
		("@t6g_mb_lib.t6g(sch_1):page297_i80@pure_quanta.q_res(chips)"
			("LOCATION" "PR131")
		)
		("@t6g_mb_lib.t6g(sch_1):page297_i11@pure_quanta.q_res(chips)"
			("LOCATION" "PR519")
		)
		("@t6g_mb_lib.t6g(sch_1):page297_i8@pure_quanta.q_res(chips)"
			("LOCATION" "PR520")
		)
		("@t6g_mb_lib.t6g(sch_1):page297_i16@pure_quanta.q_res(chips)"
			("LOCATION" "PR521")
		)
		("@t6g_mb_lib.t6g(sch_1):page297_i10@pure_quanta.q_res(chips)"
			("LOCATION" "PR522")
		)
		("@t6g_mb_lib.t6g(sch_1):page297_i41@pure_quanta.q_res(chips)"
			("LOCATION" "PR523")
		)
		("@t6g_mb_lib.t6g(sch_1):page297_i42@pure_quanta.q_res(chips)"
			("LOCATION" "PR524")
		)
		("@t6g_mb_lib.t6g(sch_1):page297_i51@pure_quanta.isl69260irazt(chips)"
			("LOCATION" "PU5")
		)
		("@t6g_mb_lib.t6g(sch_1):page297_i21@pure_quanta.q_res(chips)"
			("LOCATION" "R561")
		)
		("@t6g_mb_lib.t6g(sch_1):page297_i22@pure_quanta.q_res(chips)"
			("LOCATION" "R2322")
		)
		("@t6g_mb_lib.t6g(sch_1):page293_i9@pure_quanta.q_cap(chips)"
			("LOCATION" "PC226")
		)
		("@t6g_mb_lib.t6g(sch_1):page293_i25@pure_quanta.q_cap(chips)"
			("LOCATION" "PC227")
		)
		("@t6g_mb_lib.t6g(sch_1):page293_i19@pure_quanta.q_cap(chips)"
			("LOCATION" "PC228_P0_8")
		)
		("@t6g_mb_lib.t6g(sch_1):page293_i30@pure_quanta.q_cap(chips)"
			("LOCATION" "PC229_P0_7")
		)
		("@t6g_mb_lib.t6g(sch_1):page293_i36@pure_quanta.q_cap(chips)"
			("LOCATION" "PC230_P0_8")
		)
		("@t6g_mb_lib.t6g(sch_1):page293_i50@pure_quanta.q_cap(chips)"
			("LOCATION" "PC231_P0_7")
		)
		("@t6g_mb_lib.t6g(sch_1):page293_i37@pure_quanta.q_cap(chips)"
			("LOCATION" "PC232_P0_8")
		)
		("@t6g_mb_lib.t6g(sch_1):page293_i51@pure_quanta.q_cap(chips)"
			("LOCATION" "PC233_P0_7")
		)
		("@t6g_mb_lib.t6g(sch_1):page293_i33@pure_quanta.q_cap(chips)"
			("LOCATION" "PC234")
		)
		("@t6g_mb_lib.t6g(sch_1):page293_i55@pure_quanta.q_cap(chips)"
			("LOCATION" "PC235")
		)
		("@t6g_mb_lib.t6g(sch_1):page293_i38@pure_quanta.q_cap(chips)"
			("LOCATION" "PC236_P0_8")
		)
		("@t6g_mb_lib.t6g(sch_1):page293_i52@pure_quanta.q_cap(chips)"
			("LOCATION" "PC237_P0_7")
		)
		("@t6g_mb_lib.t6g(sch_1):page293_i39@pure_quanta.q_cap(chips)"
			("LOCATION" "PC238_P0_8")
		)
		("@t6g_mb_lib.t6g(sch_1):page293_i57@pure_quanta.q_cap(chips)"
			("LOCATION" "PC239_P0_7")
		)
		("@t6g_mb_lib.t6g(sch_1):page293_i40@pure_quanta.q_cap(chips)"
			("LOCATION" "PC240_P0_8")
		)
		("@t6g_mb_lib.t6g(sch_1):page293_i58@pure_quanta.q_cap(chips)"
			("LOCATION" "PC241_P0_7")
		)
		("@t6g_mb_lib.t6g(sch_1):page293_i104@pure_quanta.q_cap(chips)"
			("LOCATION" "PC242_P0_8")
		)
		("@t6g_mb_lib.t6g(sch_1):page293_i79@pure_quanta.q_cap(chips)"
			("LOCATION" "PC243_P0_7")
		)
		("@t6g_mb_lib.t6g(sch_1):page293_i103@pure_quanta.q_cap(chips)"
			("LOCATION" "PC244_P0_8")
		)
		("@t6g_mb_lib.t6g(sch_1):page293_i78@pure_quanta.q_cap(chips)"
			("LOCATION" "PC245_P0_7")
		)
		("@t6g_mb_lib.t6g(sch_1):page293_i101@pure_quanta.q_cap(chips)"
			("LOCATION" "PC246_P0_8")
		)
		("@t6g_mb_lib.t6g(sch_1):page293_i77@pure_quanta.q_cap(chips)"
			("LOCATION" "PC247_P0_7")
		)
		("@t6g_mb_lib.t6g(sch_1):page293_i117@pure_quanta.q_inductor4p_14(chips)"
			("LOCATION" "PL7")
		)
		("@t6g_mb_lib.t6g(sch_1):page293_i81@pure_quanta.q_inductor4p_14(chips)"
			("LOCATION" "PL8")
		)
		("@t6g_mb_lib.t6g(sch_1):page293_i110@pure_quanta.q_inductor(chips)"
			("LOCATION" "PL105")
		)
		("@t6g_mb_lib.t6g(sch_1):page293_i2@pure_quanta.q_res(chips)"
			("LOCATION" "PR132")
		)
		("@t6g_mb_lib.t6g(sch_1):page293_i13@pure_quanta.q_res(chips)"
			("LOCATION" "PR133")
		)
		("@t6g_mb_lib.t6g(sch_1):page293_i10@pure_quanta.q_res(chips)"
			("LOCATION" "PR134")
		)
		("@t6g_mb_lib.t6g(sch_1):page293_i26@pure_quanta.q_res(chips)"
			("LOCATION" "PR135")
		)
		("@t6g_mb_lib.t6g(sch_1):page293_i99@pure_quanta.q_res(chips)"
			("LOCATION" "PR136")
		)
		("@t6g_mb_lib.t6g(sch_1):page293_i84@pure_quanta.q_res(chips)"
			("LOCATION" "PR137")
		)
		("@t6g_mb_lib.t6g(sch_1):page293_i64@pure_quanta.isl99390frztr5935(chips)"
			("LOCATION" "PU6_P0_8")
		)
		("@t6g_mb_lib.t6g(sch_1):page293_i20@pure_quanta.isl99390frztr5935(chips)"
			("LOCATION" "PU7_P0_7")
		)
		("@t6g_mb_lib.t6g(sch_1):page292_i10@pure_quanta.q_cap(chips)"
			("LOCATION" "PC248")
		)
		("@t6g_mb_lib.t6g(sch_1):page292_i30@pure_quanta.q_cap(chips)"
			("LOCATION" "PC249")
		)
		("@t6g_mb_lib.t6g(sch_1):page292_i12@pure_quanta.q_cap(chips)"
			("LOCATION" "PC250_P0_6")
		)
		("@t6g_mb_lib.t6g(sch_1):page292_i34@pure_quanta.q_cap(chips)"
			("LOCATION" "PC251_P0_5")
		)
		("@t6g_mb_lib.t6g(sch_1):page292_i15@pure_quanta.q_cap(chips)"
			("LOCATION" "PC252_P0_6")
		)
		("@t6g_mb_lib.t6g(sch_1):page292_i38@pure_quanta.q_cap(chips)"
			("LOCATION" "PC253_P0_5")
		)
		("@t6g_mb_lib.t6g(sch_1):page292_i18@pure_quanta.q_cap(chips)"
			("LOCATION" "PC254_P0_6")
		)
		("@t6g_mb_lib.t6g(sch_1):page292_i39@pure_quanta.q_cap(chips)"
			("LOCATION" "PC255_P0_5")
		)
		("@t6g_mb_lib.t6g(sch_1):page292_i16@pure_quanta.q_cap(chips)"
			("LOCATION" "PC256")
		)
		("@t6g_mb_lib.t6g(sch_1):page292_i42@pure_quanta.q_cap(chips)"
			("LOCATION" "PC257")
		)
		("@t6g_mb_lib.t6g(sch_1):page292_i19@pure_quanta.q_cap(chips)"
			("LOCATION" "PC258_P0_6")
		)
		("@t6g_mb_lib.t6g(sch_1):page292_i40@pure_quanta.q_cap(chips)"
			("LOCATION" "PC259_P0_5")
		)
		("@t6g_mb_lib.t6g(sch_1):page292_i41@pure_quanta.q_cap(chips)"
			("LOCATION" "PC260_P0_6")
		)
		("@t6g_mb_lib.t6g(sch_1):page292_i59@pure_quanta.q_cap(chips)"
			("LOCATION" "PC261_P0_5")
		)
		("@t6g_mb_lib.t6g(sch_1):page292_i45@pure_quanta.q_cap(chips)"
			("LOCATION" "PC262_P0_6")
		)
		("@t6g_mb_lib.t6g(sch_1):page292_i60@pure_quanta.q_cap(chips)"
			("LOCATION" "PC263_P0_5")
		)
		("@t6g_mb_lib.t6g(sch_1):page292_i95@pure_quanta.q_cap(chips)"
			("LOCATION" "PC266_P0_6")
		)
		("@t6g_mb_lib.t6g(sch_1):page292_i80@pure_quanta.q_cap(chips)"
			("LOCATION" "PC267_P0_5")
		)
		("@t6g_mb_lib.t6g(sch_1):page292_i94@pure_quanta.q_cap(chips)"
			("LOCATION" "PC268_P0_6")
		)
		("@t6g_mb_lib.t6g(sch_1):page292_i79@pure_quanta.q_cap(chips)"
			("LOCATION" "PC269_P0_5")
		)
		("@t6g_mb_lib.t6g(sch_1):page292_i90@pure_quanta.q_inductor4p_14(chips)"
			("LOCATION" "PL9")
		)
		("@t6g_mb_lib.t6g(sch_1):page292_i74@pure_quanta.q_inductor4p_14(chips)"
			("LOCATION" "PL10")
		)
		("@t6g_mb_lib.t6g(sch_1):page292_i2@pure_quanta.q_res(chips)"
			("LOCATION" "PR138")
		)
		("@t6g_mb_lib.t6g(sch_1):page292_i21@pure_quanta.q_res(chips)"
			("LOCATION" "PR139")
		)
		("@t6g_mb_lib.t6g(sch_1):page292_i11@pure_quanta.q_res(chips)"
			("LOCATION" "PR140")
		)
		("@t6g_mb_lib.t6g(sch_1):page292_i32@pure_quanta.q_res(chips)"
			("LOCATION" "PR141")
		)
		("@t6g_mb_lib.t6g(sch_1):page292_i92@pure_quanta.q_res(chips)"
			("LOCATION" "PR142")
		)
		("@t6g_mb_lib.t6g(sch_1):page292_i76@pure_quanta.q_res(chips)"
			("LOCATION" "PR143")
		)
		("@t6g_mb_lib.t6g(sch_1):page292_i62@pure_quanta.isl99390frztr5935(chips)"
			("LOCATION" "PU8_P0_6")
		)
		("@t6g_mb_lib.t6g(sch_1):page292_i31@pure_quanta.isl99390frztr5935(chips)"
			("LOCATION" "PU9_P0_5")
		)
		("@t6g_mb_lib.t6g(sch_1):page291_i8@pure_quanta.q_cap(chips)"
			("LOCATION" "PC270")
		)
		("@t6g_mb_lib.t6g(sch_1):page291_i26@pure_quanta.q_cap(chips)"
			("LOCATION" "PC271")
		)
		("@t6g_mb_lib.t6g(sch_1):page291_i17@pure_quanta.q_cap(chips)"
			("LOCATION" "PC272_P0_4")
		)
		("@t6g_mb_lib.t6g(sch_1):page291_i32@pure_quanta.q_cap(chips)"
			("LOCATION" "PC273_P0_3")
		)
		("@t6g_mb_lib.t6g(sch_1):page291_i36@pure_quanta.q_cap(chips)"
			("LOCATION" "PC274_P0_4")
		)
		("@t6g_mb_lib.t6g(sch_1):page291_i48@pure_quanta.q_cap(chips)"
			("LOCATION" "PC275_P0_3")
		)
		("@t6g_mb_lib.t6g(sch_1):page291_i37@pure_quanta.q_cap(chips)"
			("LOCATION" "PC276_P0_4")
		)
		("@t6g_mb_lib.t6g(sch_1):page291_i50@pure_quanta.q_cap(chips)"
			("LOCATION" "PC277_P0_3")
		)
		("@t6g_mb_lib.t6g(sch_1):page291_i39@pure_quanta.q_cap(chips)"
			("LOCATION" "PC278")
		)
		("@t6g_mb_lib.t6g(sch_1):page291_i53@pure_quanta.q_cap(chips)"
			("LOCATION" "PC279")
		)
		("@t6g_mb_lib.t6g(sch_1):page291_i38@pure_quanta.q_cap(chips)"
			("LOCATION" "PC280_P0_4")
		)
		("@t6g_mb_lib.t6g(sch_1):page291_i51@pure_quanta.q_cap(chips)"
			("LOCATION" "PC281_P0_3")
		)
		("@t6g_mb_lib.t6g(sch_1):page291_i40@pure_quanta.q_cap(chips)"
			("LOCATION" "PC282_P0_4")
		)
		("@t6g_mb_lib.t6g(sch_1):page291_i55@pure_quanta.q_cap(chips)"
			("LOCATION" "PC283_P0_3")
		)
		("@t6g_mb_lib.t6g(sch_1):page291_i42@pure_quanta.q_cap(chips)"
			("LOCATION" "PC284_P0_4")
		)
		("@t6g_mb_lib.t6g(sch_1):page291_i56@pure_quanta.q_cap(chips)"
			("LOCATION" "PC285_P0_3")
		)
		("@t6g_mb_lib.t6g(sch_1):page291_i96@pure_quanta.q_cap(chips)"
			("LOCATION" "PC288_P0_4")
		)
		("@t6g_mb_lib.t6g(sch_1):page291_i79@pure_quanta.q_cap(chips)"
			("LOCATION" "PC289_P0_3")
		)
		("@t6g_mb_lib.t6g(sch_1):page291_i95@pure_quanta.q_cap(chips)"
			("LOCATION" "PC290_P0_4")
		)
		("@t6g_mb_lib.t6g(sch_1):page291_i78@pure_quanta.q_cap(chips)"
			("LOCATION" "PC291_P0_3")
		)
		("@t6g_mb_lib.t6g(sch_1):page291_i90@pure_quanta.q_inductor4p_14(chips)"
			("LOCATION" "PL11")
		)
		("@t6g_mb_lib.t6g(sch_1):page291_i74@pure_quanta.q_inductor4p_14(chips)"
			("LOCATION" "PL112")
		)
		("@t6g_mb_lib.t6g(sch_1):page291_i2@pure_quanta.q_res(chips)"
			("LOCATION" "PR144")
		)
		("@t6g_mb_lib.t6g(sch_1):page291_i19@pure_quanta.q_res(chips)"
			("LOCATION" "PR145")
		)
		("@t6g_mb_lib.t6g(sch_1):page291_i10@pure_quanta.q_res(chips)"
			("LOCATION" "PR146")
		)
		("@t6g_mb_lib.t6g(sch_1):page291_i27@pure_quanta.q_res(chips)"
			("LOCATION" "PR147")
		)
		("@t6g_mb_lib.t6g(sch_1):page291_i92@pure_quanta.q_res(chips)"
			("LOCATION" "PR148")
		)
		("@t6g_mb_lib.t6g(sch_1):page291_i76@pure_quanta.q_res(chips)"
			("LOCATION" "PR149")
		)
		("@t6g_mb_lib.t6g(sch_1):page291_i14@pure_quanta.isl99390frztr5935(chips)"
			("LOCATION" "PU10_P0_4")
		)
		("@t6g_mb_lib.t6g(sch_1):page291_i30@pure_quanta.isl99390frztr5935(chips)"
			("LOCATION" "PU11_P0_3")
		)
		("@t6g_mb_lib.t6g(sch_1):page289_i330@pure_quanta.q_cap(chips)"
			("LOCATION" "PC327")
		)
		("@t6g_mb_lib.t6g(sch_1):page289_i334@pure_quanta.q_cap(chips)"
			("LOCATION" "PC328")
		)
		("@t6g_mb_lib.t6g(sch_1):page289_i228@pure_quanta.q_cap(chips)"
			("LOCATION" "PC329")
		)
		("@t6g_mb_lib.t6g(sch_1):page289_i281@pure_quanta.q_cap(chips)"
			("LOCATION" "PC330")
		)
		("@t6g_mb_lib.t6g(sch_1):page289_i274@pure_quanta.q_cap(chips)"
			("LOCATION" "PC332")
		)
		("@t6g_mb_lib.t6g(sch_1):page289_i279@pure_quanta.q_cap(chips)"
			("LOCATION" "PC333")
		)
		("@t6g_mb_lib.t6g(sch_1):page289_i318@pure_quanta.q_cap(chips)"
			("LOCATION" "PC334")
		)
		("@t6g_mb_lib.t6g(sch_1):page289_i322@pure_quanta.q_cap(chips)"
			("LOCATION" "PC337")
		)
		("@t6g_mb_lib.t6g(sch_1):page289_i231@pure_quanta.q_cap(chips)"
			("LOCATION" "PC592")
		)
		("@t6g_mb_lib.t6g(sch_1):page289_i230@pure_quanta.q_cap(chips)"
			("LOCATION" "PC593")
		)
		("@t6g_mb_lib.t6g(sch_1):page289_i319@pure_quanta.q_cap(chips)"
			("LOCATION" "PC1173")
		)
		("@t6g_mb_lib.t6g(sch_1):page289_i252@pure_quanta.q_short(chips)"
			("LOCATION" "PJ47")
		)
		("@t6g_mb_lib.t6g(sch_1):page289_i216@pure_quanta.q_short(chips)"
			("LOCATION" "PJ53")
		)
		("@t6g_mb_lib.t6g(sch_1):page289_i219@pure_quanta.q_res(chips)"
			("LOCATION" "PR157")
		)
		("@t6g_mb_lib.t6g(sch_1):page289_i227@pure_quanta.q_res(chips)"
			("LOCATION" "PR158")
		)
		("@t6g_mb_lib.t6g(sch_1):page289_i212@pure_quanta.q_res(chips)"
			("LOCATION" "PR159")
		)
		("@t6g_mb_lib.t6g(sch_1):page289_i278@pure_quanta.q_res(chips)"
			("LOCATION" "PR160")
		)
		("@t6g_mb_lib.t6g(sch_1):page289_i277@pure_quanta.q_res(chips)"
			("LOCATION" "PR161")
		)
		("@t6g_mb_lib.t6g(sch_1):page289_i275@pure_quanta.q_res(chips)"
			("LOCATION" "PR162")
		)
		("@t6g_mb_lib.t6g(sch_1):page289_i270@pure_quanta.q_res(chips)"
			("LOCATION" "PR163")
		)
		("@t6g_mb_lib.t6g(sch_1):page289_i269@pure_quanta.q_res(chips)"
			("LOCATION" "PR164")
		)
		("@t6g_mb_lib.t6g(sch_1):page289_i267@pure_quanta.q_res(chips)"
			("LOCATION" "PR165")
		)
		("@t6g_mb_lib.t6g(sch_1):page289_i273@pure_quanta.q_res(chips)"
			("LOCATION" "PR167")
		)
		("@t6g_mb_lib.t6g(sch_1):page289_i272@pure_quanta.q_res(chips)"
			("LOCATION" "PR168")
		)
		("@t6g_mb_lib.t6g(sch_1):page289_i236@pure_quanta.q_res(chips)"
			("LOCATION" "PR169")
		)
		("@t6g_mb_lib.t6g(sch_1):page289_i271@pure_quanta.q_res(chips)"
			("LOCATION" "PR170")
		)
		("@t6g_mb_lib.t6g(sch_1):page289_i218@pure_quanta.q_res(chips)"
			("LOCATION" "PR171")
		)
		("@t6g_mb_lib.t6g(sch_1):page289_i235@pure_quanta.q_res(chips)"
			("LOCATION" "PR172")
		)
		("@t6g_mb_lib.t6g(sch_1):page289_i325@pure_quanta.q_res(chips)"
			("LOCATION" "PR176")
		)
		("@t6g_mb_lib.t6g(sch_1):page289_i244@pure_quanta.q_res(chips)"
			("LOCATION" "PR177")
		)
		("@t6g_mb_lib.t6g(sch_1):page289_i224@pure_quanta.q_res(chips)"
			("LOCATION" "PR335")
		)
		("@t6g_mb_lib.t6g(sch_1):page289_i223@pure_quanta.q_res(chips)"
			("LOCATION" "PR336")
		)
		("@t6g_mb_lib.t6g(sch_1):page289_i225@pure_quanta.q_res(chips)"
			("LOCATION" "PR337")
		)
		("@t6g_mb_lib.t6g(sch_1):page289_i246@pure_quanta.q_res(chips)"
			("LOCATION" "PR345")
		)
		("@t6g_mb_lib.t6g(sch_1):page289_i293@pure_quanta.q_res(chips)"
			("LOCATION" "PR450")
		)
		("@t6g_mb_lib.t6g(sch_1):page289_i292@pure_quanta.q_res(chips)"
			("LOCATION" "PR451")
		)
		("@t6g_mb_lib.t6g(sch_1):page289_i240@pure_quanta.q_res(chips)"
			("LOCATION" "PR527")
		)
		("@t6g_mb_lib.t6g(sch_1):page289_i333@pure_quanta.q_res(chips)"
			("LOCATION" "PR528")
		)
		("@t6g_mb_lib.t6g(sch_1):page289_i332@pure_quanta.q_res(chips)"
			("LOCATION" "PR529")
		)
		("@t6g_mb_lib.t6g(sch_1):page289_i331@pure_quanta.q_res(chips)"
			("LOCATION" "PR530")
		)
		("@t6g_mb_lib.t6g(sch_1):page289_i261@pure_quanta.q_res(chips)"
			("LOCATION" "PR531")
		)
		("@t6g_mb_lib.t6g(sch_1):page289_i233@pure_quanta.q_res(chips)"
			("LOCATION" "PR586")
		)
		("@t6g_mb_lib.t6g(sch_1):page289_i239@pure_quanta.q_res(chips)"
			("LOCATION" "PR587")
		)
		("@t6g_mb_lib.t6g(sch_1):page289_i339@pure_quanta.raa229126gnpha0(chips)"
			("LOCATION" "PU14")
		)
		("@t6g_mb_lib.t6g(sch_1):page289_i232@pure_quanta.q_res(chips)"
			("LOCATION" "R541")
		)
		("@t6g_mb_lib.t6g(sch_1):page320_i10@pure_quanta.q_cap(chips)"
			("LOCATION" "PC373")
		)
		("@t6g_mb_lib.t6g(sch_1):page320_i18@pure_quanta.q_cap(chips)"
			("LOCATION" "PC374")
		)
		("@t6g_mb_lib.t6g(sch_1):page320_i20@pure_quanta.q_cap(chips)"
			("LOCATION" "PC375")
		)
		("@t6g_mb_lib.t6g(sch_1):page320_i25@pure_quanta.q_cap(chips)"
			("LOCATION" "PC376")
		)
		("@t6g_mb_lib.t6g(sch_1):page320_i29@pure_quanta.q_cap(chips)"
			("LOCATION" "PC377")
		)
		("@t6g_mb_lib.t6g(sch_1):page320_i30@pure_quanta.q_cap(chips)"
			("LOCATION" "PC378")
		)
		("@t6g_mb_lib.t6g(sch_1):page320_i27@pure_quanta.q_cap(chips)"
			("LOCATION" "PC379")
		)
		("@t6g_mb_lib.t6g(sch_1):page320_i28@pure_quanta.q_cap(chips)"
			("LOCATION" "PC381")
		)
		("@t6g_mb_lib.t6g(sch_1):page320_i34@pure_quanta.q_cap(chips)"
			("LOCATION" "PC382")
		)
		("@t6g_mb_lib.t6g(sch_1):page320_i21@pure_quanta.q_capp(chips)"
			("LOCATION" "PC384")
		)
		("@t6g_mb_lib.t6g(sch_1):page320_i23@pure_quanta.q_capp(chips)"
			("LOCATION" "PC385")
		)
		("@t6g_mb_lib.t6g(sch_1):page320_i37@pure_quanta.q_capp(chips)"
			("LOCATION" "PC1940")
		)
		("@t6g_mb_lib.t6g(sch_1):page320_i26@pure_quanta.q_inductor(chips)"
			("LOCATION" "PL17")
		)
		("@t6g_mb_lib.t6g(sch_1):page320_i13@pure_quanta.q_res(chips)"
			("LOCATION" "PR200")
		)
		("@t6g_mb_lib.t6g(sch_1):page320_i2@pure_quanta.q_res(chips)"
			("LOCATION" "PR1746")
		)
		("@t6g_mb_lib.t6g(sch_1):page319_i253@pure_quanta.q_cap(chips)"
			("LOCATION" "PC388")
		)
		("@t6g_mb_lib.t6g(sch_1):page319_i240@pure_quanta.q_cap(chips)"
			("LOCATION" "PC390")
		)
		("@t6g_mb_lib.t6g(sch_1):page319_i257@pure_quanta.q_cap(chips)"
			("LOCATION" "PC391")
		)
		("@t6g_mb_lib.t6g(sch_1):page319_i258@pure_quanta.q_cap(chips)"
			("LOCATION" "PC394")
		)
		("@t6g_mb_lib.t6g(sch_1):page319_i256@pure_quanta.q_cap(chips)"
			("LOCATION" "PC1289")
		)
		("@t6g_mb_lib.t6g(sch_1):page319_i210@pure_quanta.q_cap(chips)"
			("LOCATION" "PC1336")
		)
		("@t6g_mb_lib.t6g(sch_1):page319_i215@pure_quanta.q_cap(chips)"
			("LOCATION" "PC1337")
		)
		("@t6g_mb_lib.t6g(sch_1):page319_i207@pure_quanta.q_short(chips)"
			("LOCATION" "PJ48")
		)
		("@t6g_mb_lib.t6g(sch_1):page319_i233@pure_quanta.q_res(chips)"
			("LOCATION" "PR206")
		)
		("@t6g_mb_lib.t6g(sch_1):page319_i232@pure_quanta.q_res(chips)"
			("LOCATION" "PR207")
		)
		("@t6g_mb_lib.t6g(sch_1):page319_i230@pure_quanta.q_res(chips)"
			("LOCATION" "PR208")
		)
		("@t6g_mb_lib.t6g(sch_1):page319_i229@pure_quanta.q_res(chips)"
			("LOCATION" "PR209")
		)
		("@t6g_mb_lib.t6g(sch_1):page319_i228@pure_quanta.q_res(chips)"
			("LOCATION" "PR210")
		)
		("@t6g_mb_lib.t6g(sch_1):page319_i227@pure_quanta.q_res(chips)"
			("LOCATION" "PR211")
		)
		("@t6g_mb_lib.t6g(sch_1):page319_i225@pure_quanta.q_res(chips)"
			("LOCATION" "PR212")
		)
		("@t6g_mb_lib.t6g(sch_1):page319_i226@pure_quanta.q_res(chips)"
			("LOCATION" "PR213")
		)
		("@t6g_mb_lib.t6g(sch_1):page319_i245@pure_quanta.q_res(chips)"
			("LOCATION" "PR215")
		)
		("@t6g_mb_lib.t6g(sch_1):page319_i252@pure_quanta.q_res(chips)"
			("LOCATION" "PR216")
		)
		("@t6g_mb_lib.t6g(sch_1):page319_i247@pure_quanta.q_res(chips)"
			("LOCATION" "PR217")
		)
		("@t6g_mb_lib.t6g(sch_1):page319_i274@pure_quanta.q_res(chips)"
			("LOCATION" "PR220")
		)
		("@t6g_mb_lib.t6g(sch_1):page319_i261@pure_quanta.q_res(chips)"
			("LOCATION" "PR223")
		)
		("@t6g_mb_lib.t6g(sch_1):page319_i206@pure_quanta.q_res(chips)"
			("LOCATION" "PR558")
		)
		("@t6g_mb_lib.t6g(sch_1):page319_i223@pure_quanta.q_res(chips)"
			("LOCATION" "PR559")
		)
		("@t6g_mb_lib.t6g(sch_1):page319_i216@pure_quanta.q_res(chips)"
			("LOCATION" "PR1718")
		)
		("@t6g_mb_lib.t6g(sch_1):page319_i217@pure_quanta.q_res(chips)"
			("LOCATION" "PR1747")
		)
		("@t6g_mb_lib.t6g(sch_1):page319_i243@pure_quanta.isl69260irazt(chips)"
			("LOCATION" "PU18")
		)
		("@t6g_mb_lib.t6g(sch_1):page312_i230@pure_quanta.q_cap(chips)"
			("LOCATION" "PC395")
		)
		("@t6g_mb_lib.t6g(sch_1):page312_i214@pure_quanta.q_cap(chips)"
			("LOCATION" "PC396")
		)
		("@t6g_mb_lib.t6g(sch_1):page312_i238@pure_quanta.q_cap(chips)"
			("LOCATION" "PC397_P1_1")
		)
		("@t6g_mb_lib.t6g(sch_1):page312_i223@pure_quanta.q_cap(chips)"
			("LOCATION" "PC398_P1_2")
		)
		("@t6g_mb_lib.t6g(sch_1):page312_i257@pure_quanta.q_cap(chips)"
			("LOCATION" "PC399_P1_1")
		)
		("@t6g_mb_lib.t6g(sch_1):page312_i243@pure_quanta.q_cap(chips)"
			("LOCATION" "PC400_P1_2")
		)
		("@t6g_mb_lib.t6g(sch_1):page312_i261@pure_quanta.q_cap(chips)"
			("LOCATION" "PC401")
		)
		("@t6g_mb_lib.t6g(sch_1):page312_i241@pure_quanta.q_cap(chips)"
			("LOCATION" "PC402")
		)
		("@t6g_mb_lib.t6g(sch_1):page312_i258@pure_quanta.q_cap(chips)"
			("LOCATION" "PC403_P1_1")
		)
		("@t6g_mb_lib.t6g(sch_1):page312_i244@pure_quanta.q_cap(chips)"
			("LOCATION" "PC404_P1_2")
		)
		("@t6g_mb_lib.t6g(sch_1):page312_i259@pure_quanta.q_cap(chips)"
			("LOCATION" "PC405_P1_1")
		)
		("@t6g_mb_lib.t6g(sch_1):page312_i245@pure_quanta.q_cap(chips)"
			("LOCATION" "PC406_P1_2")
		)
		("@t6g_mb_lib.t6g(sch_1):page312_i282@pure_quanta.q_cap(chips)"
			("LOCATION" "PC408_P1_2")
		)
		("@t6g_mb_lib.t6g(sch_1):page312_i265@pure_quanta.q_cap(chips)"
			("LOCATION" "PC410_P1_1")
		)
		("@t6g_mb_lib.t6g(sch_1):page312_i248@pure_quanta.q_cap(chips)"
			("LOCATION" "PC411_P1_2")
		)
		("@t6g_mb_lib.t6g(sch_1):page312_i268@pure_quanta.q_cap(chips)"
			("LOCATION" "PC412_P1_1")
		)
		("@t6g_mb_lib.t6g(sch_1):page312_i249@pure_quanta.q_cap(chips)"
			("LOCATION" "PC413_P1_2")
		)
		("@t6g_mb_lib.t6g(sch_1):page312_i252@pure_quanta.q_capp(chips)"
			("LOCATION" "PC414")
		)
		("@t6g_mb_lib.t6g(sch_1):page312_i253@pure_quanta.q_capp(chips)"
			("LOCATION" "PC415")
		)
		("@t6g_mb_lib.t6g(sch_1):page312_i254@pure_quanta.q_capp(chips)"
			("LOCATION" "PC416")
		)
		("@t6g_mb_lib.t6g(sch_1):page312_i275@pure_quanta.q_capp(chips)"
			("LOCATION" "PC417")
		)
		("@t6g_mb_lib.t6g(sch_1):page312_i270@pure_quanta.q_capp(chips)"
			("LOCATION" "PC418")
		)
		("@t6g_mb_lib.t6g(sch_1):page312_i281@pure_quanta.q_cap(chips)"
			("LOCATION" "PC621_P1_1")
		)
		("@t6g_mb_lib.t6g(sch_1):page312_i234@pure_quanta.q_cap(chips)"
			("LOCATION" "PC1242_P1_1")
		)
		("@t6g_mb_lib.t6g(sch_1):page312_i217@pure_quanta.q_cap(chips)"
			("LOCATION" "PC1243_P1_2")
		)
		("@t6g_mb_lib.t6g(sch_1):page312_i272@pure_quanta.q_capp(chips)"
			("LOCATION" "PC2171")
		)
		("@t6g_mb_lib.t6g(sch_1):page312_i279@pure_quanta.q_inductor(chips)"
			("LOCATION" "PL18")
		)
		("@t6g_mb_lib.t6g(sch_1):page312_i280@pure_quanta.q_inductor(chips)"
			("LOCATION" "PL19")
		)
		("@t6g_mb_lib.t6g(sch_1):page312_i266@pure_quanta.q_inductor(chips)"
			("LOCATION" "PL43")
		)
		("@t6g_mb_lib.t6g(sch_1):page312_i202@pure_quanta.q_res(chips)"
			("LOCATION" "PR224")
		)
		("@t6g_mb_lib.t6g(sch_1):page312_i213@pure_quanta.q_res(chips)"
			("LOCATION" "PR225")
		)
		("@t6g_mb_lib.t6g(sch_1):page312_i232@pure_quanta.q_res(chips)"
			("LOCATION" "PR226")
		)
		("@t6g_mb_lib.t6g(sch_1):page312_i215@pure_quanta.q_res(chips)"
			("LOCATION" "PR227")
		)
		("@t6g_mb_lib.t6g(sch_1):page312_i278@pure_quanta.isl99390frztr5935(chips)"
			("LOCATION" "PU75_P1_1")
		)
		("@t6g_mb_lib.t6g(sch_1):page312_i221@pure_quanta.isl99390frztr5935(chips)"
			("LOCATION" "PU76_P1_2")
		)
		("@t6g_mb_lib.t6g(sch_1):page307_i206@pure_quanta.q_cap(chips)"
			("LOCATION" "PC420")
		)
		("@t6g_mb_lib.t6g(sch_1):page307_i205@pure_quanta.q_cap(chips)"
			("LOCATION" "PC421")
		)
		("@t6g_mb_lib.t6g(sch_1):page307_i271@pure_quanta.q_cap(chips)"
			("LOCATION" "PC545")
		)
		("@t6g_mb_lib.t6g(sch_1):page307_i273@pure_quanta.q_cap(chips)"
			("LOCATION" "PC546")
		)
		("@t6g_mb_lib.t6g(sch_1):page307_i201@pure_quanta.q_cap(chips)"
			("LOCATION" "PC547")
		)
		("@t6g_mb_lib.t6g(sch_1):page307_i209@pure_quanta.q_cap(chips)"
			("LOCATION" "PC548")
		)
		("@t6g_mb_lib.t6g(sch_1):page307_i242@pure_quanta.q_cap(chips)"
			("LOCATION" "PC550")
		)
		("@t6g_mb_lib.t6g(sch_1):page307_i244@pure_quanta.q_cap(chips)"
			("LOCATION" "PC551")
		)
		("@t6g_mb_lib.t6g(sch_1):page307_i254@pure_quanta.q_cap(chips)"
			("LOCATION" "PC552")
		)
		("@t6g_mb_lib.t6g(sch_1):page307_i258@pure_quanta.q_cap(chips)"
			("LOCATION" "PC555")
		)
		("@t6g_mb_lib.t6g(sch_1):page307_i255@pure_quanta.q_cap(chips)"
			("LOCATION" "PC1194")
		)
		("@t6g_mb_lib.t6g(sch_1):page307_i174@pure_quanta.q_short(chips)"
			("LOCATION" "PJ49")
		)
		("@t6g_mb_lib.t6g(sch_1):page307_i187@pure_quanta.q_short(chips)"
			("LOCATION" "PJ52")
		)
		("@t6g_mb_lib.t6g(sch_1):page307_i203@pure_quanta.q_res(chips)"
			("LOCATION" "PR232")
		)
		("@t6g_mb_lib.t6g(sch_1):page307_i202@pure_quanta.q_res(chips)"
			("LOCATION" "PR233")
		)
		("@t6g_mb_lib.t6g(sch_1):page307_i204@pure_quanta.q_res(chips)"
			("LOCATION" "PR234")
		)
		("@t6g_mb_lib.t6g(sch_1):page307_i214@pure_quanta.q_res(chips)"
			("LOCATION" "PR241")
		)
		("@t6g_mb_lib.t6g(sch_1):page307_i220@pure_quanta.q_res(chips)"
			("LOCATION" "PR242")
		)
		("@t6g_mb_lib.t6g(sch_1):page307_i215@pure_quanta.q_res(chips)"
			("LOCATION" "PR243")
		)
		("@t6g_mb_lib.t6g(sch_1):page307_i218@pure_quanta.q_res(chips)"
			("LOCATION" "PR249")
		)
		("@t6g_mb_lib.t6g(sch_1):page307_i167@pure_quanta.q_res(chips)"
			("LOCATION" "PR304")
		)
		("@t6g_mb_lib.t6g(sch_1):page307_i199@pure_quanta.q_res(chips)"
			("LOCATION" "PR305")
		)
		("@t6g_mb_lib.t6g(sch_1):page307_i198@pure_quanta.q_res(chips)"
			("LOCATION" "PR307")
		)
		("@t6g_mb_lib.t6g(sch_1):page307_i197@pure_quanta.q_res(chips)"
			("LOCATION" "PR308")
		)
		("@t6g_mb_lib.t6g(sch_1):page307_i196@pure_quanta.q_res(chips)"
			("LOCATION" "PR309")
		)
		("@t6g_mb_lib.t6g(sch_1):page307_i192@pure_quanta.q_res(chips)"
			("LOCATION" "PR310")
		)
		("@t6g_mb_lib.t6g(sch_1):page307_i191@pure_quanta.q_res(chips)"
			("LOCATION" "PR311")
		)
		("@t6g_mb_lib.t6g(sch_1):page307_i190@pure_quanta.q_res(chips)"
			("LOCATION" "PR312")
		)
		("@t6g_mb_lib.t6g(sch_1):page307_i241@pure_quanta.q_res(chips)"
			("LOCATION" "PR314")
		)
		("@t6g_mb_lib.t6g(sch_1):page307_i239@pure_quanta.q_res(chips)"
			("LOCATION" "PR315")
		)
		("@t6g_mb_lib.t6g(sch_1):page307_i238@pure_quanta.q_res(chips)"
			("LOCATION" "PR317")
		)
		("@t6g_mb_lib.t6g(sch_1):page307_i278@pure_quanta.q_res(chips)"
			("LOCATION" "PR323")
		)
		("@t6g_mb_lib.t6g(sch_1):page307_i263@pure_quanta.q_res(chips)"
			("LOCATION" "PR452")
		)
		("@t6g_mb_lib.t6g(sch_1):page307_i262@pure_quanta.q_res(chips)"
			("LOCATION" "PR453")
		)
		("@t6g_mb_lib.t6g(sch_1):page307_i171@pure_quanta.q_res(chips)"
			("LOCATION" "PR560")
		)
		("@t6g_mb_lib.t6g(sch_1):page307_i175@pure_quanta.q_res(chips)"
			("LOCATION" "PR561")
		)
		("@t6g_mb_lib.t6g(sch_1):page307_i176@pure_quanta.q_res(chips)"
			("LOCATION" "PR574")
		)
		("@t6g_mb_lib.t6g(sch_1):page307_i272@pure_quanta.q_res(chips)"
			("LOCATION" "PR575")
		)
		("@t6g_mb_lib.t6g(sch_1):page307_i269@pure_quanta.q_res(chips)"
			("LOCATION" "PR576")
		)
		("@t6g_mb_lib.t6g(sch_1):page307_i268@pure_quanta.q_res(chips)"
			("LOCATION" "PR577")
		)
		("@t6g_mb_lib.t6g(sch_1):page307_i188@pure_quanta.q_res(chips)"
			("LOCATION" "PR578")
		)
		("@t6g_mb_lib.t6g(sch_1):page307_i211@pure_quanta.raa229126gnpha0(chips)"
			("LOCATION" "PU29")
		)
		("@t6g_mb_lib.t6g(sch_1):page317_i9@pure_quanta.q_cap(chips)"
			("LOCATION" "PC428")
		)
		("@t6g_mb_lib.t6g(sch_1):page317_i20@pure_quanta.q_cap(chips)"
			("LOCATION" "PC429")
		)
		("@t6g_mb_lib.t6g(sch_1):page317_i21@pure_quanta.q_cap(chips)"
			("LOCATION" "PC430")
		)
		("@t6g_mb_lib.t6g(sch_1):page317_i24@pure_quanta.q_cap(chips)"
			("LOCATION" "PC431")
		)
		("@t6g_mb_lib.t6g(sch_1):page317_i22@pure_quanta.q_cap(chips)"
			("LOCATION" "PC432")
		)
		("@t6g_mb_lib.t6g(sch_1):page317_i27@pure_quanta.q_cap(chips)"
			("LOCATION" "PC433")
		)
		("@t6g_mb_lib.t6g(sch_1):page317_i25@pure_quanta.q_cap(chips)"
			("LOCATION" "PC434")
		)
		("@t6g_mb_lib.t6g(sch_1):page317_i30@pure_quanta.q_cap(chips)"
			("LOCATION" "PC435")
		)
		("@t6g_mb_lib.t6g(sch_1):page317_i31@pure_quanta.q_cap(chips)"
			("LOCATION" "PC437")
		)
		("@t6g_mb_lib.t6g(sch_1):page317_i33@pure_quanta.q_capp(chips)"
			("LOCATION" "PC1930")
		)
		("@t6g_mb_lib.t6g(sch_1):page317_i32@pure_quanta.q_capp(chips)"
			("LOCATION" "PC2199")
		)
		("@t6g_mb_lib.t6g(sch_1):page317_i23@pure_quanta.q_inductor(chips)"
			("LOCATION" "PL20")
		)
		("@t6g_mb_lib.t6g(sch_1):page317_i13@pure_quanta.q_res(chips)"
			("LOCATION" "PR250")
		)
		("@t6g_mb_lib.t6g(sch_1):page317_i2@pure_quanta.q_res(chips)"
			("LOCATION" "PR1728")
		)
		("@t6g_mb_lib.t6g(sch_1):page316_i26@pure_quanta.q_cap(chips)"
			("LOCATION" "PC440")
		)
		("@t6g_mb_lib.t6g(sch_1):page316_i14@pure_quanta.q_cap(chips)"
			("LOCATION" "PC441")
		)
		("@t6g_mb_lib.t6g(sch_1):page316_i50@pure_quanta.q_cap(chips)"
			("LOCATION" "PC442_P1_1")
		)
		("@t6g_mb_lib.t6g(sch_1):page316_i34@pure_quanta.q_cap(chips)"
			("LOCATION" "PC443_P1_2")
		)
		("@t6g_mb_lib.t6g(sch_1):page316_i51@pure_quanta.q_cap(chips)"
			("LOCATION" "PC444_P1_1")
		)
		("@t6g_mb_lib.t6g(sch_1):page316_i36@pure_quanta.q_cap(chips)"
			("LOCATION" "PC445_P1_2")
		)
		("@t6g_mb_lib.t6g(sch_1):page316_i54@pure_quanta.q_cap(chips)"
			("LOCATION" "PC446")
		)
		("@t6g_mb_lib.t6g(sch_1):page316_i40@pure_quanta.q_cap(chips)"
			("LOCATION" "PC447")
		)
		("@t6g_mb_lib.t6g(sch_1):page316_i56@pure_quanta.q_cap(chips)"
			("LOCATION" "PC448_P1_1")
		)
		("@t6g_mb_lib.t6g(sch_1):page316_i38@pure_quanta.q_cap(chips)"
			("LOCATION" "PC449_P1_2")
		)
		("@t6g_mb_lib.t6g(sch_1):page316_i57@pure_quanta.q_cap(chips)"
			("LOCATION" "PC450_P1_1")
		)
		("@t6g_mb_lib.t6g(sch_1):page316_i39@pure_quanta.q_cap(chips)"
			("LOCATION" "PC451_P1_2")
		)
		("@t6g_mb_lib.t6g(sch_1):page316_i58@pure_quanta.q_cap(chips)"
			("LOCATION" "PC452_P1_1")
		)
		("@t6g_mb_lib.t6g(sch_1):page316_i59@pure_quanta.q_cap(chips)"
			("LOCATION" "PC455_P1_1")
		)
		("@t6g_mb_lib.t6g(sch_1):page316_i41@pure_quanta.q_cap(chips)"
			("LOCATION" "PC456_P1_2")
		)
		("@t6g_mb_lib.t6g(sch_1):page316_i62@pure_quanta.q_cap(chips)"
			("LOCATION" "PC457_P1_1")
		)
		("@t6g_mb_lib.t6g(sch_1):page316_i43@pure_quanta.q_cap(chips)"
			("LOCATION" "PC458_P1_2")
		)
		("@t6g_mb_lib.t6g(sch_1):page316_i74@pure_quanta.q_capp(chips)"
			("LOCATION" "PC460")
		)
		("@t6g_mb_lib.t6g(sch_1):page316_i75@pure_quanta.q_capp(chips)"
			("LOCATION" "PC461")
		)
		("@t6g_mb_lib.t6g(sch_1):page316_i48@pure_quanta.q_capp(chips)"
			("LOCATION" "PC1588")
		)
		("@t6g_mb_lib.t6g(sch_1):page316_i47@pure_quanta.q_capp(chips)"
			("LOCATION" "PC1593")
		)
		("@t6g_mb_lib.t6g(sch_1):page316_i68@pure_quanta.q_capp(chips)"
			("LOCATION" "PC1594")
		)
		("@t6g_mb_lib.t6g(sch_1):page316_i67@pure_quanta.q_capp(chips)"
			("LOCATION" "PC1595")
		)
		("@t6g_mb_lib.t6g(sch_1):page316_i69@pure_quanta.q_capp(chips)"
			("LOCATION" "PC1596")
		)
		("@t6g_mb_lib.t6g(sch_1):page316_i55@pure_quanta.q_inductor(chips)"
			("LOCATION" "PL21")
		)
		("@t6g_mb_lib.t6g(sch_1):page316_i33@pure_quanta.q_inductor(chips)"
			("LOCATION" "PL22")
		)
		("@t6g_mb_lib.t6g(sch_1):page316_i65@pure_quanta.q_inductor(chips)"
			("LOCATION" "PL23")
		)
		("@t6g_mb_lib.t6g(sch_1):page316_i27@pure_quanta.q_res(chips)"
			("LOCATION" "PR254")
		)
		("@t6g_mb_lib.t6g(sch_1):page316_i15@pure_quanta.q_res(chips)"
			("LOCATION" "PR255")
		)
		("@t6g_mb_lib.t6g(sch_1):page316_i7@pure_quanta.q_res(chips)"
			("LOCATION" "PR1726")
		)
		("@t6g_mb_lib.t6g(sch_1):page316_i3@pure_quanta.q_res(chips)"
			("LOCATION" "PR1727")
		)
		("@t6g_mb_lib.t6g(sch_1):page315_i54@pure_quanta.q_cap(chips)"
			("LOCATION" "PC467")
		)
		("@t6g_mb_lib.t6g(sch_1):page315_i74@pure_quanta.q_cap(chips)"
			("LOCATION" "PC470")
		)
		("@t6g_mb_lib.t6g(sch_1):page315_i76@pure_quanta.q_cap(chips)"
			("LOCATION" "PC471")
		)
		("@t6g_mb_lib.t6g(sch_1):page315_i59@pure_quanta.q_cap(chips)"
			("LOCATION" "PC472")
		)
		("@t6g_mb_lib.t6g(sch_1):page315_i58@pure_quanta.q_cap(chips)"
			("LOCATION" "PC473")
		)
		("@t6g_mb_lib.t6g(sch_1):page315_i57@pure_quanta.q_cap(chips)"
			("LOCATION" "PC474")
		)
		("@t6g_mb_lib.t6g(sch_1):page315_i82@pure_quanta.q_cap(chips)"
			("LOCATION" "PC476")
		)
		("@t6g_mb_lib.t6g(sch_1):page315_i83@pure_quanta.q_cap(chips)"
			("LOCATION" "PC478")
		)
		("@t6g_mb_lib.t6g(sch_1):page315_i81@pure_quanta.q_cap(chips)"
			("LOCATION" "PC1193")
		)
		("@t6g_mb_lib.t6g(sch_1):page315_i33@pure_quanta.q_short(chips)"
			("LOCATION" "PJ50")
		)
		("@t6g_mb_lib.t6g(sch_1):page315_i20@pure_quanta.q_short(chips)"
			("LOCATION" "PJ51")
		)
		("@t6g_mb_lib.t6g(sch_1):page315_i12@pure_quanta.q_res(chips)"
			("LOCATION" "PR260")
		)
		("@t6g_mb_lib.t6g(sch_1):page315_i52@pure_quanta.q_res(chips)"
			("LOCATION" "PR262")
		)
		("@t6g_mb_lib.t6g(sch_1):page315_i50@pure_quanta.q_res(chips)"
			("LOCATION" "PR263")
		)
		("@t6g_mb_lib.t6g(sch_1):page315_i51@pure_quanta.q_res(chips)"
			("LOCATION" "PR264")
		)
		("@t6g_mb_lib.t6g(sch_1):page315_i45@pure_quanta.q_res(chips)"
			("LOCATION" "PR265")
		)
		("@t6g_mb_lib.t6g(sch_1):page315_i46@pure_quanta.q_res(chips)"
			("LOCATION" "PR266")
		)
		("@t6g_mb_lib.t6g(sch_1):page315_i44@pure_quanta.q_res(chips)"
			("LOCATION" "PR267")
		)
		("@t6g_mb_lib.t6g(sch_1):page315_i43@pure_quanta.q_res(chips)"
			("LOCATION" "PR268")
		)
		("@t6g_mb_lib.t6g(sch_1):page315_i41@pure_quanta.q_res(chips)"
			("LOCATION" "PR269")
		)
		("@t6g_mb_lib.t6g(sch_1):page315_i17@pure_quanta.q_res(chips)"
			("LOCATION" "PR270")
		)
		("@t6g_mb_lib.t6g(sch_1):page315_i16@pure_quanta.q_res(chips)"
			("LOCATION" "PR271")
		)
		("@t6g_mb_lib.t6g(sch_1):page315_i18@pure_quanta.q_res(chips)"
			("LOCATION" "PR272")
		)
		("@t6g_mb_lib.t6g(sch_1):page315_i42@pure_quanta.q_res(chips)"
			("LOCATION" "PR273")
		)
		("@t6g_mb_lib.t6g(sch_1):page315_i29@pure_quanta.q_res(chips)"
			("LOCATION" "PR274")
		)
		("@t6g_mb_lib.t6g(sch_1):page315_i13@pure_quanta.q_res(chips)"
			("LOCATION" "PR275")
		)
		("@t6g_mb_lib.t6g(sch_1):page315_i89@pure_quanta.q_res(chips)"
			("LOCATION" "PR283")
		)
		("@t6g_mb_lib.t6g(sch_1):page315_i92@pure_quanta.q_res(chips)"
			("LOCATION" "PR284")
		)
		("@t6g_mb_lib.t6g(sch_1):page315_i22@pure_quanta.q_res(chips)"
			("LOCATION" "PR566")
		)
		("@t6g_mb_lib.t6g(sch_1):page315_i19@pure_quanta.q_res(chips)"
			("LOCATION" "PR567")
		)
		("@t6g_mb_lib.t6g(sch_1):page315_i98@pure_quanta.q_res(chips)"
			("LOCATION" "PR568")
		)
		("@t6g_mb_lib.t6g(sch_1):page315_i21@pure_quanta.q_res(chips)"
			("LOCATION" "PR569")
		)
		("@t6g_mb_lib.t6g(sch_1):page315_i26@pure_quanta.q_res(chips)"
			("LOCATION" "PR570")
		)
		("@t6g_mb_lib.t6g(sch_1):page315_i25@pure_quanta.q_res(chips)"
			("LOCATION" "PR571")
		)
		("@t6g_mb_lib.t6g(sch_1):page315_i61@pure_quanta.isl69260irazt(chips)"
			("LOCATION" "PU22")
		)
		("@t6g_mb_lib.t6g(sch_1):page315_i39@pure_quanta.q_res(chips)"
			("LOCATION" "R2345")
		)
		("@t6g_mb_lib.t6g(sch_1):page315_i38@pure_quanta.q_res(chips)"
			("LOCATION" "R2354")
		)
		("@t6g_mb_lib.t6g(sch_1):page311_i25@pure_quanta.q_cap(chips)"
			("LOCATION" "PC479")
		)
		("@t6g_mb_lib.t6g(sch_1):page311_i32@pure_quanta.q_cap(chips)"
			("LOCATION" "PC480")
		)
		("@t6g_mb_lib.t6g(sch_1):page311_i28@pure_quanta.q_cap(chips)"
			("LOCATION" "PC481_P1_8")
		)
		("@t6g_mb_lib.t6g(sch_1):page311_i36@pure_quanta.q_cap(chips)"
			("LOCATION" "PC482_P1_7")
		)
		("@t6g_mb_lib.t6g(sch_1):page311_i38@pure_quanta.q_cap(chips)"
			("LOCATION" "PC483_P1_8")
		)
		("@t6g_mb_lib.t6g(sch_1):page311_i46@pure_quanta.q_cap(chips)"
			("LOCATION" "PC484_P1_7")
		)
		("@t6g_mb_lib.t6g(sch_1):page311_i40@pure_quanta.q_cap(chips)"
			("LOCATION" "PC485_P1_8")
		)
		("@t6g_mb_lib.t6g(sch_1):page311_i48@pure_quanta.q_cap(chips)"
			("LOCATION" "PC486_P1_7")
		)
		("@t6g_mb_lib.t6g(sch_1):page311_i41@pure_quanta.q_cap(chips)"
			("LOCATION" "PC487")
		)
		("@t6g_mb_lib.t6g(sch_1):page311_i49@pure_quanta.q_cap(chips)"
			("LOCATION" "PC488")
		)
		("@t6g_mb_lib.t6g(sch_1):page311_i42@pure_quanta.q_cap(chips)"
			("LOCATION" "PC489_P1_8")
		)
		("@t6g_mb_lib.t6g(sch_1):page311_i52@pure_quanta.q_cap(chips)"
			("LOCATION" "PC490_P1_7")
		)
		("@t6g_mb_lib.t6g(sch_1):page311_i43@pure_quanta.q_cap(chips)"
			("LOCATION" "PC491_P1_8")
		)
		("@t6g_mb_lib.t6g(sch_1):page311_i53@pure_quanta.q_cap(chips)"
			("LOCATION" "PC492_P1_7")
		)
		("@t6g_mb_lib.t6g(sch_1):page311_i44@pure_quanta.q_cap(chips)"
			("LOCATION" "PC493_P1_8")
		)
		("@t6g_mb_lib.t6g(sch_1):page311_i54@pure_quanta.q_cap(chips)"
			("LOCATION" "PC494_P1_7")
		)
		("@t6g_mb_lib.t6g(sch_1):page311_i103@pure_quanta.q_cap(chips)"
			("LOCATION" "PC495_P1_8")
		)
		("@t6g_mb_lib.t6g(sch_1):page311_i84@pure_quanta.q_cap(chips)"
			("LOCATION" "PC496_P1_7")
		)
		("@t6g_mb_lib.t6g(sch_1):page311_i102@pure_quanta.q_cap(chips)"
			("LOCATION" "PC497_P1_8")
		)
		("@t6g_mb_lib.t6g(sch_1):page311_i83@pure_quanta.q_cap(chips)"
			("LOCATION" "PC498_P1_7")
		)
		("@t6g_mb_lib.t6g(sch_1):page311_i101@pure_quanta.q_cap(chips)"
			("LOCATION" "PC499_P1_8")
		)
		("@t6g_mb_lib.t6g(sch_1):page311_i81@pure_quanta.q_cap(chips)"
			("LOCATION" "PC500_P1_7")
		)
		("@t6g_mb_lib.t6g(sch_1):page311_i95@pure_quanta.q_inductor4p_14(chips)"
			("LOCATION" "PL24")
		)
		("@t6g_mb_lib.t6g(sch_1):page311_i76@pure_quanta.q_inductor4p_14(chips)"
			("LOCATION" "PL25")
		)
		("@t6g_mb_lib.t6g(sch_1):page311_i107@pure_quanta.q_inductor(chips)"
			("LOCATION" "PL106")
		)
		("@t6g_mb_lib.t6g(sch_1):page311_i2@pure_quanta.q_res(chips)"
			("LOCATION" "PR285")
		)
		("@t6g_mb_lib.t6g(sch_1):page311_i18@pure_quanta.q_res(chips)"
			("LOCATION" "PR286")
		)
		("@t6g_mb_lib.t6g(sch_1):page311_i26@pure_quanta.q_res(chips)"
			("LOCATION" "PR287")
		)
		("@t6g_mb_lib.t6g(sch_1):page311_i34@pure_quanta.q_res(chips)"
			("LOCATION" "PR288")
		)
		("@t6g_mb_lib.t6g(sch_1):page311_i98@pure_quanta.q_res(chips)"
			("LOCATION" "PR289")
		)
		("@t6g_mb_lib.t6g(sch_1):page311_i79@pure_quanta.q_res(chips)"
			("LOCATION" "PR290")
		)
		("@t6g_mb_lib.t6g(sch_1):page311_i9@pure_quanta.isl99390frztr5935(chips)"
			("LOCATION" "PU23_P1_8")
		)
		("@t6g_mb_lib.t6g(sch_1):page311_i37@pure_quanta.isl99390frztr5935(chips)"
			("LOCATION" "PU24_P1_7")
		)
		("@t6g_mb_lib.t6g(sch_1):page310_i8@pure_quanta.q_cap(chips)"
			("LOCATION" "PC501")
		)
		("@t6g_mb_lib.t6g(sch_1):page310_i20@pure_quanta.q_cap(chips)"
			("LOCATION" "PC502")
		)
		("@t6g_mb_lib.t6g(sch_1):page310_i29@pure_quanta.q_cap(chips)"
			("LOCATION" "PC503_P1_6")
		)
		("@t6g_mb_lib.t6g(sch_1):page310_i34@pure_quanta.q_cap(chips)"
			("LOCATION" "PC504_P1_5")
		)
		("@t6g_mb_lib.t6g(sch_1):page310_i37@pure_quanta.q_cap(chips)"
			("LOCATION" "PC505_P1_6")
		)
		("@t6g_mb_lib.t6g(sch_1):page310_i48@pure_quanta.q_cap(chips)"
			("LOCATION" "PC506_P1_5")
		)
		("@t6g_mb_lib.t6g(sch_1):page310_i38@pure_quanta.q_cap(chips)"
			("LOCATION" "PC507_P1_6")
		)
		("@t6g_mb_lib.t6g(sch_1):page310_i49@pure_quanta.q_cap(chips)"
			("LOCATION" "PC508_P1_5")
		)
		("@t6g_mb_lib.t6g(sch_1):page310_i41@pure_quanta.q_cap(chips)"
			("LOCATION" "PC509")
		)
		("@t6g_mb_lib.t6g(sch_1):page310_i53@pure_quanta.q_cap(chips)"
			("LOCATION" "PC510")
		)
		("@t6g_mb_lib.t6g(sch_1):page310_i39@pure_quanta.q_cap(chips)"
			("LOCATION" "PC511_P1_6")
		)
		("@t6g_mb_lib.t6g(sch_1):page310_i50@pure_quanta.q_cap(chips)"
			("LOCATION" "PC512_P1_5")
		)
		("@t6g_mb_lib.t6g(sch_1):page310_i44@pure_quanta.q_cap(chips)"
			("LOCATION" "PC513_P1_6")
		)
		("@t6g_mb_lib.t6g(sch_1):page310_i54@pure_quanta.q_cap(chips)"
			("LOCATION" "PC514_P1_5")
		)
		("@t6g_mb_lib.t6g(sch_1):page310_i45@pure_quanta.q_cap(chips)"
			("LOCATION" "PC515_P1_6")
		)
		("@t6g_mb_lib.t6g(sch_1):page310_i56@pure_quanta.q_cap(chips)"
			("LOCATION" "PC516_P1_5")
		)
		("@t6g_mb_lib.t6g(sch_1):page310_i95@pure_quanta.q_cap(chips)"
			("LOCATION" "PC519_P1_6")
		)
		("@t6g_mb_lib.t6g(sch_1):page310_i79@pure_quanta.q_cap(chips)"
			("LOCATION" "PC520_P1_5")
		)
		("@t6g_mb_lib.t6g(sch_1):page310_i94@pure_quanta.q_cap(chips)"
			("LOCATION" "PC521_P1_6")
		)
		("@t6g_mb_lib.t6g(sch_1):page310_i78@pure_quanta.q_cap(chips)"
			("LOCATION" "PC522_P1_5")
		)
		("@t6g_mb_lib.t6g(sch_1):page310_i90@pure_quanta.q_inductor4p_14(chips)"
			("LOCATION" "PL26")
		)
		("@t6g_mb_lib.t6g(sch_1):page310_i73@pure_quanta.q_inductor4p_14(chips)"
			("LOCATION" "PL27")
		)
		("@t6g_mb_lib.t6g(sch_1):page310_i2@pure_quanta.q_res(chips)"
			("LOCATION" "PR291")
		)
		("@t6g_mb_lib.t6g(sch_1):page310_i13@pure_quanta.q_res(chips)"
			("LOCATION" "PR292")
		)
		("@t6g_mb_lib.t6g(sch_1):page310_i10@pure_quanta.q_res(chips)"
			("LOCATION" "PR293")
		)
		("@t6g_mb_lib.t6g(sch_1):page310_i21@pure_quanta.q_res(chips)"
			("LOCATION" "PR294")
		)
		("@t6g_mb_lib.t6g(sch_1):page310_i96@pure_quanta.q_res(chips)"
			("LOCATION" "PR295")
		)
		("@t6g_mb_lib.t6g(sch_1):page310_i80@pure_quanta.q_res(chips)"
			("LOCATION" "PR296")
		)
		("@t6g_mb_lib.t6g(sch_1):page310_i23@pure_quanta.isl99390frztr5935(chips)"
			("LOCATION" "PU25_P1_6")
		)
		("@t6g_mb_lib.t6g(sch_1):page310_i32@pure_quanta.isl99390frztr5935(chips)"
			("LOCATION" "PU26_P1_5")
		)
		("@t6g_mb_lib.t6g(sch_1):page309_i11@pure_quanta.q_cap(chips)"
			("LOCATION" "PC523")
		)
		("@t6g_mb_lib.t6g(sch_1):page309_i26@pure_quanta.q_cap(chips)"
			("LOCATION" "PC524")
		)
		("@t6g_mb_lib.t6g(sch_1):page309_i16@pure_quanta.q_cap(chips)"
			("LOCATION" "PC525_P1_4")
		)
		("@t6g_mb_lib.t6g(sch_1):page309_i30@pure_quanta.q_cap(chips)"
			("LOCATION" "PC526_P1_3")
		)
		("@t6g_mb_lib.t6g(sch_1):page309_i32@pure_quanta.q_cap(chips)"
			("LOCATION" "PC527_P1_4")
		)
		("@t6g_mb_lib.t6g(sch_1):page309_i46@pure_quanta.q_cap(chips)"
			("LOCATION" "PC528_P1_3")
		)
		("@t6g_mb_lib.t6g(sch_1):page309_i35@pure_quanta.q_cap(chips)"
			("LOCATION" "PC529_P1_4")
		)
		("@t6g_mb_lib.t6g(sch_1):page309_i48@pure_quanta.q_cap(chips)"
			("LOCATION" "PC530_P1_3")
		)
		("@t6g_mb_lib.t6g(sch_1):page309_i41@pure_quanta.q_cap(chips)"
			("LOCATION" "PC531")
		)
		("@t6g_mb_lib.t6g(sch_1):page309_i52@pure_quanta.q_cap(chips)"
			("LOCATION" "PC532")
		)
		("@t6g_mb_lib.t6g(sch_1):page309_i36@pure_quanta.q_cap(chips)"
			("LOCATION" "PC533_P1_4")
		)
		("@t6g_mb_lib.t6g(sch_1):page309_i49@pure_quanta.q_cap(chips)"
			("LOCATION" "PC534_P1_3")
		)
		("@t6g_mb_lib.t6g(sch_1):page309_i42@pure_quanta.q_cap(chips)"
			("LOCATION" "PC535_P1_4")
		)
		("@t6g_mb_lib.t6g(sch_1):page309_i53@pure_quanta.q_cap(chips)"
			("LOCATION" "PC536_P1_3")
		)
		("@t6g_mb_lib.t6g(sch_1):page309_i43@pure_quanta.q_cap(chips)"
			("LOCATION" "PC537_P1_4")
		)
		("@t6g_mb_lib.t6g(sch_1):page309_i54@pure_quanta.q_cap(chips)"
			("LOCATION" "PC538_P1_3")
		)
		("@t6g_mb_lib.t6g(sch_1):page309_i96@pure_quanta.q_cap(chips)"
			("LOCATION" "PC541_P1_4")
		)
		("@t6g_mb_lib.t6g(sch_1):page309_i79@pure_quanta.q_cap(chips)"
			("LOCATION" "PC542_P1_3")
		)
		("@t6g_mb_lib.t6g(sch_1):page309_i94@pure_quanta.q_cap(chips)"
			("LOCATION" "PC543_P1_4")
		)
		("@t6g_mb_lib.t6g(sch_1):page309_i77@pure_quanta.q_cap(chips)"
			("LOCATION" "PC544_P1_3")
		)
		("@t6g_mb_lib.t6g(sch_1):page309_i90@pure_quanta.q_inductor4p_14(chips)"
			("LOCATION" "PL28")
		)
		("@t6g_mb_lib.t6g(sch_1):page309_i74@pure_quanta.q_inductor4p_14(chips)"
			("LOCATION" "PL29")
		)
		("@t6g_mb_lib.t6g(sch_1):page309_i2@pure_quanta.q_res(chips)"
			("LOCATION" "PR297")
		)
		("@t6g_mb_lib.t6g(sch_1):page309_i20@pure_quanta.q_res(chips)"
			("LOCATION" "PR298")
		)
		("@t6g_mb_lib.t6g(sch_1):page309_i12@pure_quanta.q_res(chips)"
			("LOCATION" "PR299")
		)
		("@t6g_mb_lib.t6g(sch_1):page309_i27@pure_quanta.q_res(chips)"
			("LOCATION" "PR300")
		)
		("@t6g_mb_lib.t6g(sch_1):page309_i92@pure_quanta.q_res(chips)"
			("LOCATION" "PR301")
		)
		("@t6g_mb_lib.t6g(sch_1):page309_i80@pure_quanta.q_res(chips)"
			("LOCATION" "PR302")
		)
		("@t6g_mb_lib.t6g(sch_1):page309_i9@pure_quanta.isl99390frztr5935(chips)"
			("LOCATION" "PU27_P1_4")
		)
		("@t6g_mb_lib.t6g(sch_1):page309_i18@pure_quanta.isl99390frztr5935(chips)"
			("LOCATION" "PU28_P1_3")
		)
		("@t6g_mb_lib.t6g(sch_1):page294_i23@pure_quanta.q_cap(chips)"
			("LOCATION" "PC600")
		)
		("@t6g_mb_lib.t6g(sch_1):page294_i8@pure_quanta.q_cap(chips)"
			("LOCATION" "PC601")
		)
		("@t6g_mb_lib.t6g(sch_1):page294_i49@pure_quanta.q_cap(chips)"
			("LOCATION" "PC602_P0_1")
		)
		("@t6g_mb_lib.t6g(sch_1):page294_i38@pure_quanta.q_cap(chips)"
			("LOCATION" "PC603_P0_2")
		)
		("@t6g_mb_lib.t6g(sch_1):page294_i50@pure_quanta.q_cap(chips)"
			("LOCATION" "PC604_P0_1")
		)
		("@t6g_mb_lib.t6g(sch_1):page294_i39@pure_quanta.q_cap(chips)"
			("LOCATION" "PC605_P0_2")
		)
		("@t6g_mb_lib.t6g(sch_1):page294_i54@pure_quanta.q_cap(chips)"
			("LOCATION" "PC606")
		)
		("@t6g_mb_lib.t6g(sch_1):page294_i43@pure_quanta.q_cap(chips)"
			("LOCATION" "PC607")
		)
		("@t6g_mb_lib.t6g(sch_1):page294_i52@pure_quanta.q_cap(chips)"
			("LOCATION" "PC608_P0_1")
		)
		("@t6g_mb_lib.t6g(sch_1):page294_i41@pure_quanta.q_cap(chips)"
			("LOCATION" "PC609_P0_2")
		)
		("@t6g_mb_lib.t6g(sch_1):page294_i56@pure_quanta.q_cap(chips)"
			("LOCATION" "PC610_P0_1")
		)
		("@t6g_mb_lib.t6g(sch_1):page294_i42@pure_quanta.q_cap(chips)"
			("LOCATION" "PC611_P0_2")
		)
		("@t6g_mb_lib.t6g(sch_1):page294_i70@pure_quanta.q_cap(chips)"
			("LOCATION" "PC612_P0_1")
		)
		("@t6g_mb_lib.t6g(sch_1):page294_i59@pure_quanta.q_cap(chips)"
			("LOCATION" "PC613_P0_2")
		)
		("@t6g_mb_lib.t6g(sch_1):page294_i72@pure_quanta.q_cap(chips)"
			("LOCATION" "PC615_P0_1")
		)
		("@t6g_mb_lib.t6g(sch_1):page294_i60@pure_quanta.q_cap(chips)"
			("LOCATION" "PC616_P0_2")
		)
		("@t6g_mb_lib.t6g(sch_1):page294_i73@pure_quanta.q_cap(chips)"
			("LOCATION" "PC617_P0_1")
		)
		("@t6g_mb_lib.t6g(sch_1):page294_i61@pure_quanta.q_cap(chips)"
			("LOCATION" "PC618_P0_2")
		)
		("@t6g_mb_lib.t6g(sch_1):page294_i62@pure_quanta.q_capp(chips)"
			("LOCATION" "PC619")
		)
		("@t6g_mb_lib.t6g(sch_1):page294_i63@pure_quanta.q_capp(chips)"
			("LOCATION" "PC620")
		)
		("@t6g_mb_lib.t6g(sch_1):page294_i65@pure_quanta.q_capp(chips)"
			("LOCATION" "PC621")
		)
		("@t6g_mb_lib.t6g(sch_1):page294_i77@pure_quanta.q_capp(chips)"
			("LOCATION" "PC622")
		)
		("@t6g_mb_lib.t6g(sch_1):page294_i66@pure_quanta.q_capp(chips)"
			("LOCATION" "PC623")
		)
		("@t6g_mb_lib.t6g(sch_1):page294_i48@pure_quanta.q_cap(chips)"
			("LOCATION" "PC1211_P0_1")
		)
		("@t6g_mb_lib.t6g(sch_1):page294_i33@pure_quanta.q_cap(chips)"
			("LOCATION" "PC1212_P0_2")
		)
		("@t6g_mb_lib.t6g(sch_1):page294_i68@pure_quanta.q_capp(chips)"
			("LOCATION" "PC2645")
		)
		("@t6g_mb_lib.t6g(sch_1):page294_i81@pure_quanta.q_inductor(chips)"
			("LOCATION" "PL33")
		)
		("@t6g_mb_lib.t6g(sch_1):page294_i82@pure_quanta.q_inductor(chips)"
			("LOCATION" "PL34")
		)
		("@t6g_mb_lib.t6g(sch_1):page294_i74@pure_quanta.q_inductor(chips)"
			("LOCATION" "PL44")
		)
		("@t6g_mb_lib.t6g(sch_1):page294_i2@pure_quanta.q_res(chips)"
			("LOCATION" "PR353")
		)
		("@t6g_mb_lib.t6g(sch_1):page294_i17@pure_quanta.q_res(chips)"
			("LOCATION" "PR354")
		)
		("@t6g_mb_lib.t6g(sch_1):page294_i25@pure_quanta.q_res(chips)"
			("LOCATION" "PR355")
		)
		("@t6g_mb_lib.t6g(sch_1):page294_i10@pure_quanta.q_res(chips)"
			("LOCATION" "PR356")
		)
		("@t6g_mb_lib.t6g(sch_1):page294_i35@pure_quanta.isl99390frztr5935(chips)"
			("LOCATION" "PU69_P0_1")
		)
		("@t6g_mb_lib.t6g(sch_1):page294_i30@pure_quanta.isl99390frztr5935(chips)"
			("LOCATION" "PU70_P0_2")
		)
		("@t6g_mb_lib.t6g(sch_1):page302_i332@pure_quanta.q_cap(chips)"
			("LOCATION" "PC633")
		)
		("@t6g_mb_lib.t6g(sch_1):page302_i340@pure_quanta.q_cap(chips)"
			("LOCATION" "PC634")
		)
		("@t6g_mb_lib.t6g(sch_1):page302_i357@pure_quanta.q_cap(chips)"
			("LOCATION" "PC635")
		)
		("@t6g_mb_lib.t6g(sch_1):page302_i344@pure_quanta.q_cap(chips)"
			("LOCATION" "PC636")
		)
		("@t6g_mb_lib.t6g(sch_1):page302_i358@pure_quanta.q_cap(chips)"
			("LOCATION" "PC637")
		)
		("@t6g_mb_lib.t6g(sch_1):page302_i359@pure_quanta.q_cap(chips)"
			("LOCATION" "PC638")
		)
		("@t6g_mb_lib.t6g(sch_1):page302_i346@pure_quanta.q_cap(chips)"
			("LOCATION" "PC639")
		)
		("@t6g_mb_lib.t6g(sch_1):page302_i352@pure_quanta.q_cap(chips)"
			("LOCATION" "PC641")
		)
		("@t6g_mb_lib.t6g(sch_1):page302_i353@pure_quanta.q_cap(chips)"
			("LOCATION" "PC642")
		)
		("@t6g_mb_lib.t6g(sch_1):page302_i349@pure_quanta.q_capp(chips)"
			("LOCATION" "PC1644")
		)
		("@t6g_mb_lib.t6g(sch_1):page302_i350@pure_quanta.q_capp(chips)"
			("LOCATION" "PC1645")
		)
		("@t6g_mb_lib.t6g(sch_1):page302_i348@pure_quanta.q_capp(chips)"
			("LOCATION" "PC1910")
		)
		("@t6g_mb_lib.t6g(sch_1):page302_i345@pure_quanta.q_inductor(chips)"
			("LOCATION" "PL35")
		)
		("@t6g_mb_lib.t6g(sch_1):page302_i336@pure_quanta.q_res(chips)"
			("LOCATION" "PR380")
		)
		("@t6g_mb_lib.t6g(sch_1):page302_i325@pure_quanta.q_res(chips)"
			("LOCATION" "PR2718")
		)
		("@t6g_mb_lib.t6g(sch_1):page295_i20@pure_quanta.q_cap(chips)"
			("LOCATION" "PC1171")
		)
		("@t6g_mb_lib.t6g(sch_1):page295_i9@pure_quanta.q_cap(chips)"
			("LOCATION" "PC1172")
		)
		("@t6g_mb_lib.t6g(sch_1):page295_i43@pure_quanta.q_cap(chips)"
			("LOCATION" "PC1173_P0_3")
		)
		("@t6g_mb_lib.t6g(sch_1):page295_i31@pure_quanta.q_cap(chips)"
			("LOCATION" "PC1174_P0_4")
		)
		("@t6g_mb_lib.t6g(sch_1):page295_i44@pure_quanta.q_cap(chips)"
			("LOCATION" "PC1175_P0_3")
		)
		("@t6g_mb_lib.t6g(sch_1):page295_i32@pure_quanta.q_cap(chips)"
			("LOCATION" "PC1176_P0_4")
		)
		("@t6g_mb_lib.t6g(sch_1):page295_i48@pure_quanta.q_cap(chips)"
			("LOCATION" "PC1177")
		)
		("@t6g_mb_lib.t6g(sch_1):page295_i36@pure_quanta.q_cap(chips)"
			("LOCATION" "PC1178")
		)
		("@t6g_mb_lib.t6g(sch_1):page295_i46@pure_quanta.q_cap(chips)"
			("LOCATION" "PC1179_P0_3")
		)
		("@t6g_mb_lib.t6g(sch_1):page295_i34@pure_quanta.q_cap(chips)"
			("LOCATION" "PC1180_P0_4")
		)
		("@t6g_mb_lib.t6g(sch_1):page295_i50@pure_quanta.q_cap(chips)"
			("LOCATION" "PC1181_P0_3")
		)
		("@t6g_mb_lib.t6g(sch_1):page295_i35@pure_quanta.q_cap(chips)"
			("LOCATION" "PC1182_P0_4")
		)
		("@t6g_mb_lib.t6g(sch_1):page295_i56@pure_quanta.q_capp(chips)"
			("LOCATION" "PC1183")
		)
		("@t6g_mb_lib.t6g(sch_1):page295_i65@pure_quanta.q_cap(chips)"
			("LOCATION" "PC1183_P0_3")
		)
		("@t6g_mb_lib.t6g(sch_1):page295_i53@pure_quanta.q_cap(chips)"
			("LOCATION" "PC1183_P0_4")
		)
		("@t6g_mb_lib.t6g(sch_1):page295_i57@pure_quanta.q_capp(chips)"
			("LOCATION" "PC1185")
		)
		("@t6g_mb_lib.t6g(sch_1):page295_i67@pure_quanta.q_cap(chips)"
			("LOCATION" "PC1185_P0_3")
		)
		("@t6g_mb_lib.t6g(sch_1):page295_i60@pure_quanta.q_capp(chips)"
			("LOCATION" "PC1186")
		)
		("@t6g_mb_lib.t6g(sch_1):page295_i54@pure_quanta.q_cap(chips)"
			("LOCATION" "PC1186_P0_4")
		)
		("@t6g_mb_lib.t6g(sch_1):page295_i61@pure_quanta.q_capp(chips)"
			("LOCATION" "PC1187")
		)
		("@t6g_mb_lib.t6g(sch_1):page295_i68@pure_quanta.q_cap(chips)"
			("LOCATION" "PC1187_P0_3")
		)
		("@t6g_mb_lib.t6g(sch_1):page295_i55@pure_quanta.q_cap(chips)"
			("LOCATION" "PC1188_P0_4")
		)
		("@t6g_mb_lib.t6g(sch_1):page295_i73@pure_quanta.q_capp(chips)"
			("LOCATION" "PC1189")
		)
		("@t6g_mb_lib.t6g(sch_1):page295_i42@pure_quanta.q_cap(chips)"
			("LOCATION" "PC1213_P0_3")
		)
		("@t6g_mb_lib.t6g(sch_1):page295_i26@pure_quanta.q_cap(chips)"
			("LOCATION" "PC1214_P0_4")
		)
		("@t6g_mb_lib.t6g(sch_1):page295_i63@pure_quanta.q_capp(chips)"
			("LOCATION" "PC2170")
		)
		("@t6g_mb_lib.t6g(sch_1):page295_i75@pure_quanta.q_inductor(chips)"
			("LOCATION" "PL2")
		)
		("@t6g_mb_lib.t6g(sch_1):page295_i69@pure_quanta.q_inductor(chips)"
			("LOCATION" "PL101")
		)
		("@t6g_mb_lib.t6g(sch_1):page295_i30@pure_quanta.q_inductor(chips)"
			("LOCATION" "PL210")
		)
		("@t6g_mb_lib.t6g(sch_1):page295_i2@pure_quanta.q_res(chips)"
			("LOCATION" "PR1297")
		)
		("@t6g_mb_lib.t6g(sch_1):page295_i13@pure_quanta.q_res(chips)"
			("LOCATION" "PR1298")
		)
		("@t6g_mb_lib.t6g(sch_1):page295_i21@pure_quanta.q_res(chips)"
			("LOCATION" "PR1299")
		)
		("@t6g_mb_lib.t6g(sch_1):page295_i10@pure_quanta.q_res(chips)"
			("LOCATION" "PR1300")
		)
		("@t6g_mb_lib.t6g(sch_1):page295_i40@pure_quanta.isl99390frztr5935(chips)"
			("LOCATION" "PU71_P0_3")
		)
		("@t6g_mb_lib.t6g(sch_1):page295_i24@pure_quanta.isl99390frztr5935(chips)"
			("LOCATION" "PU72_P0_4")
		)
		("@t6g_mb_lib.t6g(sch_1):page313_i20@pure_quanta.q_cap(chips)"
			("LOCATION" "PC1191")
		)
		("@t6g_mb_lib.t6g(sch_1):page313_i9@pure_quanta.q_cap(chips)"
			("LOCATION" "PC1192")
		)
		("@t6g_mb_lib.t6g(sch_1):page313_i44@pure_quanta.q_cap(chips)"
			("LOCATION" "PC1193_P1_3")
		)
		("@t6g_mb_lib.t6g(sch_1):page313_i33@pure_quanta.q_cap(chips)"
			("LOCATION" "PC1194_P1_4")
		)
		("@t6g_mb_lib.t6g(sch_1):page313_i45@pure_quanta.q_cap(chips)"
			("LOCATION" "PC1195_P1_3")
		)
		("@t6g_mb_lib.t6g(sch_1):page313_i35@pure_quanta.q_cap(chips)"
			("LOCATION" "PC1196_P1_4")
		)
		("@t6g_mb_lib.t6g(sch_1):page313_i48@pure_quanta.q_cap(chips)"
			("LOCATION" "PC1197")
		)
		("@t6g_mb_lib.t6g(sch_1):page313_i31@pure_quanta.q_cap(chips)"
			("LOCATION" "PC1198")
		)
		("@t6g_mb_lib.t6g(sch_1):page313_i46@pure_quanta.q_cap(chips)"
			("LOCATION" "PC1199_P1_3")
		)
		("@t6g_mb_lib.t6g(sch_1):page313_i36@pure_quanta.q_cap(chips)"
			("LOCATION" "PC1200_P1_4")
		)
		("@t6g_mb_lib.t6g(sch_1):page313_i55@pure_quanta.q_capp(chips)"
			("LOCATION" "PC1201")
		)
		("@t6g_mb_lib.t6g(sch_1):page313_i51@pure_quanta.q_cap(chips)"
			("LOCATION" "PC1201_P1_3")
		)
		("@t6g_mb_lib.t6g(sch_1):page313_i37@pure_quanta.q_cap(chips)"
			("LOCATION" "PC1202_P1_4")
		)
		("@t6g_mb_lib.t6g(sch_1):page313_i56@pure_quanta.q_capp(chips)"
			("LOCATION" "PC1203")
		)
		("@t6g_mb_lib.t6g(sch_1):page313_i80@pure_quanta.q_cap(chips)"
			("LOCATION" "PC1203_P1_4")
		)
		("@t6g_mb_lib.t6g(sch_1):page313_i59@pure_quanta.q_capp(chips)"
			("LOCATION" "PC1204")
		)
		("@t6g_mb_lib.t6g(sch_1):page313_i66@pure_quanta.q_cap(chips)"
			("LOCATION" "PC1204_P1_3")
		)
		("@t6g_mb_lib.t6g(sch_1):page313_i61@pure_quanta.q_capp(chips)"
			("LOCATION" "PC1205")
		)
		("@t6g_mb_lib.t6g(sch_1):page313_i67@pure_quanta.q_cap(chips)"
			("LOCATION" "PC1206_P1_3")
		)
		("@t6g_mb_lib.t6g(sch_1):page313_i75@pure_quanta.q_cap(chips)"
			("LOCATION" "PC1207_P1_4")
		)
		("@t6g_mb_lib.t6g(sch_1):page313_i68@pure_quanta.q_cap(chips)"
			("LOCATION" "PC1208_P1_3")
		)
		("@t6g_mb_lib.t6g(sch_1):page313_i54@pure_quanta.q_cap(chips)"
			("LOCATION" "PC1209_P1_4")
		)
		("@t6g_mb_lib.t6g(sch_1):page313_i73@pure_quanta.q_capp(chips)"
			("LOCATION" "PC1210")
		)
		("@t6g_mb_lib.t6g(sch_1):page313_i42@pure_quanta.q_cap(chips)"
			("LOCATION" "PC1244_P1_3")
		)
		("@t6g_mb_lib.t6g(sch_1):page313_i26@pure_quanta.q_cap(chips)"
			("LOCATION" "PC1245_P1_4")
		)
		("@t6g_mb_lib.t6g(sch_1):page313_i63@pure_quanta.q_capp(chips)"
			("LOCATION" "PC2172")
		)
		("@t6g_mb_lib.t6g(sch_1):page313_i76@pure_quanta.q_inductor(chips)"
			("LOCATION" "PL12")
		)
		("@t6g_mb_lib.t6g(sch_1):page313_i69@pure_quanta.q_inductor(chips)"
			("LOCATION" "PL14")
		)
		("@t6g_mb_lib.t6g(sch_1):page313_i77@pure_quanta.q_inductor(chips)"
			("LOCATION" "PL113")
		)
		("@t6g_mb_lib.t6g(sch_1):page313_i2@pure_quanta.q_res(chips)"
			("LOCATION" "PR1304")
		)
		("@t6g_mb_lib.t6g(sch_1):page313_i13@pure_quanta.q_res(chips)"
			("LOCATION" "PR1305")
		)
		("@t6g_mb_lib.t6g(sch_1):page313_i21@pure_quanta.q_res(chips)"
			("LOCATION" "PR1306")
		)
		("@t6g_mb_lib.t6g(sch_1):page313_i10@pure_quanta.q_res(chips)"
			("LOCATION" "PR1307")
		)
		("@t6g_mb_lib.t6g(sch_1):page313_i27@pure_quanta.isl99390frztr5935(chips)"
			("LOCATION" "PU77_P1_3")
		)
		("@t6g_mb_lib.t6g(sch_1):page313_i24@pure_quanta.isl99390frztr5935(chips)"
			("LOCATION" "PU78_P1_4")
		)
		("@t6g_mb_lib.t6g(sch_1):page286_i44@pure_quanta.q_cap(chips)"
			("LOCATION" "PC1232")
		)
		("@t6g_mb_lib.t6g(sch_1):page286_i45@pure_quanta.q_cap(chips)"
			("LOCATION" "PC1233")
		)
		("@t6g_mb_lib.t6g(sch_1):page286_i32@pure_quanta.q_cap(chips)"
			("LOCATION" "PC1234")
		)
		("@t6g_mb_lib.t6g(sch_1):page286_i21@pure_quanta.q_cap(chips)"
			("LOCATION" "PC1235")
		)
		("@t6g_mb_lib.t6g(sch_1):page286_i23@pure_quanta.q_cap(chips)"
			("LOCATION" "PC1236")
		)
		("@t6g_mb_lib.t6g(sch_1):page286_i26@pure_quanta.q_cap(chips)"
			("LOCATION" "PC1237")
		)
		("@t6g_mb_lib.t6g(sch_1):page286_i36@pure_quanta.q_cap(chips)"
			("LOCATION" "PC1238")
		)
		("@t6g_mb_lib.t6g(sch_1):page286_i37@pure_quanta.q_cap(chips)"
			("LOCATION" "PC1239")
		)
		("@t6g_mb_lib.t6g(sch_1):page286_i38@pure_quanta.q_cap(chips)"
			("LOCATION" "PC1240")
		)
		("@t6g_mb_lib.t6g(sch_1):page286_i40@pure_quanta.q_cap(chips)"
			("LOCATION" "PC1241")
		)
		("@t6g_mb_lib.t6g(sch_1):page286_i6@pure_quanta.q_cap(chips)"
			("LOCATION" "PC1642")
		)
		("@t6g_mb_lib.t6g(sch_1):page286_i25@pure_quanta.q_cap(chips)"
			("LOCATION" "PC2287")
		)
		("@t6g_mb_lib.t6g(sch_1):page286_i28@pure_quanta.q_inductor(chips)"
			("LOCATION" "PL16")
		)
		("@t6g_mb_lib.t6g(sch_1):page286_i22@pure_quanta.q_inductor(chips)"
			("LOCATION" "PL170")
		)
		("@t6g_mb_lib.t6g(sch_1):page286_i4@pure_quanta.q_res(chips)"
			("LOCATION" "PR395")
		)
		("@t6g_mb_lib.t6g(sch_1):page286_i1@pure_quanta.q_res(chips)"
			("LOCATION" "PR396")
		)
		("@t6g_mb_lib.t6g(sch_1):page286_i15@pure_quanta.q_res(chips)"
			("LOCATION" "PR411")
		)
		("@t6g_mb_lib.t6g(sch_1):page286_i16@pure_quanta.q_res(chips)"
			("LOCATION" "PR412")
		)
		("@t6g_mb_lib.t6g(sch_1):page286_i33@pure_quanta.q_res(chips)"
			("LOCATION" "PR1302")
		)
		("@t6g_mb_lib.t6g(sch_1):page286_i7@pure_quanta.q_res(chips)"
			("LOCATION" "PR1329")
		)
		("@t6g_mb_lib.t6g(sch_1):page286_i13@pure_quanta.q_res(chips)"
			("LOCATION" "PR1330")
		)
		("@t6g_mb_lib.t6g(sch_1):page286_i35@pure_quanta.q_res(chips)"
			("LOCATION" "PR1651")
		)
		("@t6g_mb_lib.t6g(sch_1):page286_i43@pure_quanta.nb695gdz(chips)"
			("LOCATION" "PU74")
		)
		("@t6g_mb_lib.t6g(sch_1):page286_i17@pure_quanta.q_res(chips)"
			("LOCATION" "R1850")
		)
		("@t6g_mb_lib.t6g(sch_1):page287_i2@pure_quanta.q_cap(chips)"
			("LOCATION" "PC1323")
		)
		("@t6g_mb_lib.t6g(sch_1):page287_i23@pure_quanta.q_cap(chips)"
			("LOCATION" "PC1324")
		)
		("@t6g_mb_lib.t6g(sch_1):page287_i31@pure_quanta.q_cap(chips)"
			("LOCATION" "PC1325")
		)
		("@t6g_mb_lib.t6g(sch_1):page287_i32@pure_quanta.q_cap(chips)"
			("LOCATION" "PC1326")
		)
		("@t6g_mb_lib.t6g(sch_1):page287_i34@pure_quanta.q_cap(chips)"
			("LOCATION" "PC1327")
		)
		("@t6g_mb_lib.t6g(sch_1):page287_i36@pure_quanta.q_cap(chips)"
			("LOCATION" "PC1328")
		)
		("@t6g_mb_lib.t6g(sch_1):page287_i17@pure_quanta.q_cap(chips)"
			("LOCATION" "PC1329")
		)
		("@t6g_mb_lib.t6g(sch_1):page287_i18@pure_quanta.q_cap(chips)"
			("LOCATION" "PC1330")
		)
		("@t6g_mb_lib.t6g(sch_1):page287_i20@pure_quanta.q_cap(chips)"
			("LOCATION" "PC1331")
		)
		("@t6g_mb_lib.t6g(sch_1):page287_i30@pure_quanta.q_cap(chips)"
			("LOCATION" "PC1332")
		)
		("@t6g_mb_lib.t6g(sch_1):page287_i26@pure_quanta.q_cap(chips)"
			("LOCATION" "PC1333")
		)
		("@t6g_mb_lib.t6g(sch_1):page287_i7@pure_quanta.q_inductor(chips)"
			("LOCATION" "PL115")
		)
		("@t6g_mb_lib.t6g(sch_1):page287_i27@pure_quanta.q_inductor(chips)"
			("LOCATION" "PL116")
		)
		("@t6g_mb_lib.t6g(sch_1):page287_i39@pure_quanta.q_res(chips)"
			("LOCATION" "PR41")
		)
		("@t6g_mb_lib.t6g(sch_1):page287_i11@pure_quanta.q_res(chips)"
			("LOCATION" "PR398")
		)
		("@t6g_mb_lib.t6g(sch_1):page287_i10@pure_quanta.q_res(chips)"
			("LOCATION" "PR399")
		)
		("@t6g_mb_lib.t6g(sch_1):page287_i24@pure_quanta.q_res(chips)"
			("LOCATION" "PR923")
		)
		("@t6g_mb_lib.t6g(sch_1):page287_i3@pure_quanta.q_res(chips)"
			("LOCATION" "PR924")
		)
		("@t6g_mb_lib.t6g(sch_1):page287_i38@pure_quanta.q_res(chips)"
			("LOCATION" "PR925")
		)
		("@t6g_mb_lib.t6g(sch_1):page287_i28@pure_quanta.q_res(chips)"
			("LOCATION" "PR926")
		)
		("@t6g_mb_lib.t6g(sch_1):page287_i22@pure_quanta.nb695gdz(chips)"
			("LOCATION" "PU98")
		)
		("@t6g_mb_lib.t6g(sch_1):page282_i69@pure_quanta.q_capp(chips)"
			("LOCATION" "PC1845")
		)
		("@t6g_mb_lib.t6g(sch_1):page282_i55@pure_quanta.q_cap(chips)"
			("LOCATION" "PC1846")
		)
		("@t6g_mb_lib.t6g(sch_1):page282_i64@pure_quanta.q_cap(chips)"
			("LOCATION" "PC1847")
		)
		("@t6g_mb_lib.t6g(sch_1):page282_i47@pure_quanta.q_cap(chips)"
			("LOCATION" "PC1848")
		)
		("@t6g_mb_lib.t6g(sch_1):page282_i78@pure_quanta.q_cap(chips)"
			("LOCATION" "PC1849")
		)
		("@t6g_mb_lib.t6g(sch_1):page282_i77@pure_quanta.q_cap(chips)"
			("LOCATION" "PC1850")
		)
		("@t6g_mb_lib.t6g(sch_1):page282_i74@pure_quanta.q_cap(chips)"
			("LOCATION" "PC1852")
		)
		("@t6g_mb_lib.t6g(sch_1):page282_i59@pure_quanta.q_cap(chips)"
			("LOCATION" "PC1853")
		)
		("@t6g_mb_lib.t6g(sch_1):page282_i72@pure_quanta.q_cap(chips)"
			("LOCATION" "PC1855")
		)
		("@t6g_mb_lib.t6g(sch_1):page282_i73@pure_quanta.q_cap(chips)"
			("LOCATION" "PC1856")
		)
		("@t6g_mb_lib.t6g(sch_1):page282_i43@pure_quanta.q_cap(chips)"
			("LOCATION" "PC1870")
		)
		("@t6g_mb_lib.t6g(sch_1):page282_i65@pure_quanta.q_cap(chips)"
			("LOCATION" "PC1877")
		)
		("@t6g_mb_lib.t6g(sch_1):page282_i51@pure_quanta.q_cap(chips)"
			("LOCATION" "PC1898")
		)
		("@t6g_mb_lib.t6g(sch_1):page282_i57@pure_quanta.q_inductor(chips)"
			("LOCATION" "PL64")
		)
		("@t6g_mb_lib.t6g(sch_1):page282_i67@pure_quanta.q_inductor(chips)"
			("LOCATION" "PL65")
		)
		("@t6g_mb_lib.t6g(sch_1):page282_i53@pure_quanta.q_res(chips)"
			("LOCATION" "PR89")
		)
		("@t6g_mb_lib.t6g(sch_1):page282_i70@pure_quanta.q_res(chips)"
			("LOCATION" "PR90")
		)
		("@t6g_mb_lib.t6g(sch_1):page282_i63@pure_quanta.q_res(chips)"
			("LOCATION" "PR91")
		)
		("@t6g_mb_lib.t6g(sch_1):page282_i66@pure_quanta.q_res(chips)"
			("LOCATION" "PR92")
		)
		("@t6g_mb_lib.t6g(sch_1):page282_i41@pure_quanta.q_res(chips)"
			("LOCATION" "PR1945")
		)
		("@t6g_mb_lib.t6g(sch_1):page282_i40@pure_quanta.q_res(chips)"
			("LOCATION" "PR1948")
		)
		("@t6g_mb_lib.t6g(sch_1):page282_i54@pure_quanta.mpq8633bglec838z(chips)"
			("LOCATION" "PU181")
		)
		("@t6g_mb_lib.t6g(sch_1):page90_i62@pure_quanta.mosfet_nch_dual(chips)"
			("LOCATION" "Q3")
		)
		("@t6g_mb_lib.t6g(sch_1):page90_i41@pure_quanta.mosfet_nch_dual(chips)"
			("LOCATION" "Q3")
		)
		("@t6g_mb_lib.t6g(sch_1):page90_i68@pure_quanta.mosfet_nch_dual(chips)"
			("LOCATION" "Q4")
		)
		("@t6g_mb_lib.t6g(sch_1):page90_i51@pure_quanta.mosfet_nch_dual(chips)"
			("LOCATION" "Q4")
		)
		("@t6g_mb_lib.t6g(sch_1):page90_i74@pure_quanta.mosfet_nch_dual(chips)"
			("LOCATION" "Q5")
		)
		("@t6g_mb_lib.t6g(sch_1):page90_i56@pure_quanta.mosfet_nch_dual(chips)"
			("LOCATION" "Q5")
		)
		("@t6g_mb_lib.t6g(sch_1):page90_i78@pure_quanta.mosfet_nch_dual(chips)"
			("LOCATION" "Q6")
		)
		("@t6g_mb_lib.t6g(sch_1):page90_i57@pure_quanta.mosfet_nch_dual(chips)"
			("LOCATION" "Q6")
		)
		("@t6g_mb_lib.t6g(sch_1):page90_i64@pure_quanta.q_res(chips)"
			("LOCATION" "R229")
		)
		("@t6g_mb_lib.t6g(sch_1):page90_i79@pure_quanta.q_res(chips)"
			("LOCATION" "R230")
		)
		("@t6g_mb_lib.t6g(sch_1):page90_i81@pure_quanta.q_res(chips)"
			("LOCATION" "R231")
		)
		("@t6g_mb_lib.t6g(sch_1):page90_i82@pure_quanta.q_res(chips)"
			("LOCATION" "R232")
		)
		("@t6g_mb_lib.t6g(sch_1):page90_i60@pure_quanta.q_res(chips)"
			("LOCATION" "R233")
		)
		("@t6g_mb_lib.t6g(sch_1):page90_i67@pure_quanta.q_res(chips)"
			("LOCATION" "R234")
		)
		("@t6g_mb_lib.t6g(sch_1):page90_i72@pure_quanta.q_res(chips)"
			("LOCATION" "R235")
		)
		("@t6g_mb_lib.t6g(sch_1):page90_i77@pure_quanta.q_res(chips)"
			("LOCATION" "R236")
		)
		("@t6g_mb_lib.t6g(sch_1):page90_i61@pure_quanta.q_res(chips)"
			("LOCATION" "R237")
		)
		("@t6g_mb_lib.t6g(sch_1):page90_i69@pure_quanta.q_res(chips)"
			("LOCATION" "R238")
		)
		("@t6g_mb_lib.t6g(sch_1):page90_i73@pure_quanta.q_res(chips)"
			("LOCATION" "R239")
		)
		("@t6g_mb_lib.t6g(sch_1):page90_i85@pure_quanta.q_res(chips)"
			("LOCATION" "R240")
		)
		("@t6g_mb_lib.t6g(sch_1):page90_i88@pure_quanta.q_res(chips)"
			("LOCATION" "R241")
		)
		("@t6g_mb_lib.t6g(sch_1):page90_i90@pure_quanta.q_res(chips)"
			("LOCATION" "R242")
		)
		("@t6g_mb_lib.t6g(sch_1):page90_i96@pure_quanta.q_res(chips)"
			("LOCATION" "R243")
		)
		("@t6g_mb_lib.t6g(sch_1):page90_i98@pure_quanta.q_res(chips)"
			("LOCATION" "R244")
		)
		("@t6g_mb_lib.t6g(sch_1):page90_i39@pure_quanta.q_res(chips)"
			("LOCATION" "R245")
		)
		("@t6g_mb_lib.t6g(sch_1):page90_i50@pure_quanta.q_res(chips)"
			("LOCATION" "R246")
		)
		("@t6g_mb_lib.t6g(sch_1):page90_i53@pure_quanta.q_res(chips)"
			("LOCATION" "R247")
		)
		("@t6g_mb_lib.t6g(sch_1):page90_i54@pure_quanta.q_res(chips)"
			("LOCATION" "R248")
		)
		("@t6g_mb_lib.t6g(sch_1):page259_i6@pure_quanta.mosfet_nch_dual(chips)"
			("LOCATION" "Q27")
		)
		("@t6g_mb_lib.t6g(sch_1):page259_i7@pure_quanta.mosfet_pch_gds_esd_protected(chips)"
			("LOCATION" "Q28")
		)
		("@t6g_mb_lib.t6g(sch_1):page259_i3@pure_quanta.mosfet_nch_dual(chips)"
			("LOCATION" "Q29")
		)
		("@t6g_mb_lib.t6g(sch_1):page259_i11@pure_quanta.mosfet_pch_gds_esd_protected(chips)"
			("LOCATION" "Q285")
		)
		("@t6g_mb_lib.t6g(sch_1):page259_i4@pure_quanta.q_res(chips)"
			("LOCATION" "R1023")
		)
		("@t6g_mb_lib.t6g(sch_1):page259_i9@pure_quanta.q_res(chips)"
			("LOCATION" "R1024")
		)
		("@t6g_mb_lib.t6g(sch_1):page259_i12@pure_quanta.q_res(chips)"
			("LOCATION" "R1025")
		)
		("@t6g_mb_lib.t6g(sch_1):page259_i16@pure_quanta.q_res(chips)"
			("LOCATION" "R1344")
		)
		("@t6g_mb_lib.t6g(sch_1):page259_i17@pure_quanta.q_res(chips)"
			("LOCATION" "R3752")
		)
		("@t6g_mb_lib.t6g(sch_1):page339_i37@pure_quanta.mosfet_nch_dual(chips)"
			("LOCATION" "Q40")
		)
		("@t6g_mb_lib.t6g(sch_1):page339_i42@pure_quanta.mosfet_nch_dual(chips)"
			("LOCATION" "Q40")
		)
		("@t6g_mb_lib.t6g(sch_1):page339_i29@pure_quanta.mosfet_nch_dual(chips)"
			("LOCATION" "Q41")
		)
		("@t6g_mb_lib.t6g(sch_1):page339_i32@pure_quanta.mosfet_nch_dual(chips)"
			("LOCATION" "Q41")
		)
		("@t6g_mb_lib.t6g(sch_1):page339_i20@pure_quanta.mosfet_nch_dual(chips)"
			("LOCATION" "Q46")
		)
		("@t6g_mb_lib.t6g(sch_1):page339_i24@pure_quanta.mosfet_nch_dual(chips)"
			("LOCATION" "Q46")
		)
		("@t6g_mb_lib.t6g(sch_1):page339_i50@pure_quanta.mosfet_nch_dual(chips)"
			("LOCATION" "Q80")
		)
		("@t6g_mb_lib.t6g(sch_1):page339_i56@pure_quanta.mosfet_nch_dual(chips)"
			("LOCATION" "Q80")
		)
		("@t6g_mb_lib.t6g(sch_1):page339_i22@pure_quanta.q_res(chips)"
			("LOCATION" "R3744")
		)
		("@t6g_mb_lib.t6g(sch_1):page339_i11@pure_quanta.q_res(chips)"
			("LOCATION" "R3745")
		)
		("@t6g_mb_lib.t6g(sch_1):page339_i34@pure_quanta.q_res(chips)"
			("LOCATION" "R3746")
		)
		("@t6g_mb_lib.t6g(sch_1):page339_i31@pure_quanta.q_res(chips)"
			("LOCATION" "R3747")
		)
		("@t6g_mb_lib.t6g(sch_1):page339_i53@pure_quanta.q_res(chips)"
			("LOCATION" "R3748")
		)
		("@t6g_mb_lib.t6g(sch_1):page339_i18@pure_quanta.q_res(chips)"
			("LOCATION" "R3919")
		)
		("@t6g_mb_lib.t6g(sch_1):page339_i16@pure_quanta.q_res(chips)"
			("LOCATION" "R3927")
		)
		("@t6g_mb_lib.t6g(sch_1):page339_i59@pure_quanta.q_res(chips)"
			("LOCATION" "R3931")
		)
		("@t6g_mb_lib.t6g(sch_1):page339_i52@pure_quanta.q_res(chips)"
			("LOCATION" "R3933")
		)
		("@t6g_mb_lib.t6g(sch_1):page339_i39@pure_quanta.q_res(chips)"
			("LOCATION" "R4086")
		)
		("@t6g_mb_lib.t6g(sch_1):page248_i132@pure_quanta.mosfet_nch_dual(chips)"
			("LOCATION" "Q98")
		)
		("@t6g_mb_lib.t6g(sch_1):page248_i137@pure_quanta.mosfet_nch_dual(chips)"
			("LOCATION" "Q98")
		)
		("@t6g_mb_lib.t6g(sch_1):page248_i145@pure_quanta.mosfet_nch_dual(chips)"
			("LOCATION" "Q99")
		)
		("@t6g_mb_lib.t6g(sch_1):page248_i151@pure_quanta.mosfet_nch_dual(chips)"
			("LOCATION" "Q99")
		)
		("@t6g_mb_lib.t6g(sch_1):page248_i188@pure_quanta.mosfet_nch_dual(chips)"
			("LOCATION" "Q121")
		)
		("@t6g_mb_lib.t6g(sch_1):page248_i184@pure_quanta.mosfet_nch_dual(chips)"
			("LOCATION" "Q121")
		)
		("@t6g_mb_lib.t6g(sch_1):page248_i199@pure_quanta.mosfet_nch_dual(chips)"
			("LOCATION" "Q122")
		)
		("@t6g_mb_lib.t6g(sch_1):page248_i195@pure_quanta.mosfet_nch_dual(chips)"
			("LOCATION" "Q122")
		)
		("@t6g_mb_lib.t6g(sch_1):page248_i204@pure_quanta.mosfet_nch_dual(chips)"
			("LOCATION" "Q123")
		)
		("@t6g_mb_lib.t6g(sch_1):page248_i208@pure_quanta.mosfet_nch_dual(chips)"
			("LOCATION" "Q123")
		)
		("@t6g_mb_lib.t6g(sch_1):page248_i215@pure_quanta.mosfet_nch_dual(chips)"
			("LOCATION" "Q124")
		)
		("@t6g_mb_lib.t6g(sch_1):page248_i219@pure_quanta.mosfet_nch_dual(chips)"
			("LOCATION" "Q124")
		)
		("@t6g_mb_lib.t6g(sch_1):page248_i226@pure_quanta.mosfet_nch_dual(chips)"
			("LOCATION" "Q125")
		)
		("@t6g_mb_lib.t6g(sch_1):page248_i230@pure_quanta.mosfet_nch_dual(chips)"
			("LOCATION" "Q125")
		)
		("@t6g_mb_lib.t6g(sch_1):page248_i237@pure_quanta.mosfet_nch_dual(chips)"
			("LOCATION" "Q126")
		)
		("@t6g_mb_lib.t6g(sch_1):page248_i241@pure_quanta.mosfet_nch_dual(chips)"
			("LOCATION" "Q126")
		)
		("@t6g_mb_lib.t6g(sch_1):page248_i256@pure_quanta.q_res(chips)"
			("LOCATION" "R526")
		)
		("@t6g_mb_lib.t6g(sch_1):page248_i247@pure_quanta.q_res(chips)"
			("LOCATION" "R527")
		)
		("@t6g_mb_lib.t6g(sch_1):page248_i249@pure_quanta.q_res(chips)"
			("LOCATION" "R528")
		)
		("@t6g_mb_lib.t6g(sch_1):page248_i253@pure_quanta.q_res(chips)"
			("LOCATION" "R633")
		)
		("@t6g_mb_lib.t6g(sch_1):page248_i254@pure_quanta.q_res(chips)"
			("LOCATION" "R634")
		)
		("@t6g_mb_lib.t6g(sch_1):page248_i255@pure_quanta.q_res(chips)"
			("LOCATION" "R635")
		)
		("@t6g_mb_lib.t6g(sch_1):page248_i95@pure_quanta.q_res(chips)"
			("LOCATION" "R3132")
		)
		("@t6g_mb_lib.t6g(sch_1):page248_i149@pure_quanta.q_res(chips)"
			("LOCATION" "R3499")
		)
		("@t6g_mb_lib.t6g(sch_1):page248_i131@pure_quanta.q_res(chips)"
			("LOCATION" "R3557")
		)
		("@t6g_mb_lib.t6g(sch_1):page248_i134@pure_quanta.q_res(chips)"
			("LOCATION" "R3558")
		)
		("@t6g_mb_lib.t6g(sch_1):page248_i138@pure_quanta.q_res(chips)"
			("LOCATION" "R3559")
		)
		("@t6g_mb_lib.t6g(sch_1):page248_i142@pure_quanta.q_res(chips)"
			("LOCATION" "R3560")
		)
		("@t6g_mb_lib.t6g(sch_1):page248_i152@pure_quanta.q_res(chips)"
			("LOCATION" "R3561")
		)
		("@t6g_mb_lib.t6g(sch_1):page248_i186@pure_quanta.q_res(chips)"
			("LOCATION" "R3572")
		)
		("@t6g_mb_lib.t6g(sch_1):page248_i197@pure_quanta.q_res(chips)"
			("LOCATION" "R3573")
		)
		("@t6g_mb_lib.t6g(sch_1):page248_i206@pure_quanta.q_res(chips)"
			("LOCATION" "R3574")
		)
		("@t6g_mb_lib.t6g(sch_1):page248_i182@pure_quanta.q_res(chips)"
			("LOCATION" "R3575")
		)
		("@t6g_mb_lib.t6g(sch_1):page248_i193@pure_quanta.q_res(chips)"
			("LOCATION" "R3576")
		)
		("@t6g_mb_lib.t6g(sch_1):page248_i210@pure_quanta.q_res(chips)"
			("LOCATION" "R3577")
		)
		("@t6g_mb_lib.t6g(sch_1):page248_i217@pure_quanta.q_res(chips)"
			("LOCATION" "R3578")
		)
		("@t6g_mb_lib.t6g(sch_1):page248_i228@pure_quanta.q_res(chips)"
			("LOCATION" "R3579")
		)
		("@t6g_mb_lib.t6g(sch_1):page248_i239@pure_quanta.q_res(chips)"
			("LOCATION" "R3580")
		)
		("@t6g_mb_lib.t6g(sch_1):page248_i221@pure_quanta.q_res(chips)"
			("LOCATION" "R3581")
		)
		("@t6g_mb_lib.t6g(sch_1):page248_i232@pure_quanta.q_res(chips)"
			("LOCATION" "R3582")
		)
		("@t6g_mb_lib.t6g(sch_1):page248_i243@pure_quanta.q_res(chips)"
			("LOCATION" "R3583")
		)
		("@t6g_mb_lib.t6g(sch_1):page196_i70@pure_quanta.mosfet_nch_dual(chips)"
			("LOCATION" "Q100")
		)
		("@t6g_mb_lib.t6g(sch_1):page196_i57@pure_quanta.mosfet_nch_dual(chips)"
			("LOCATION" "Q100")
		)
		("@t6g_mb_lib.t6g(sch_1):page196_i63@pure_quanta.mosfet_n_123(chips)"
			("LOCATION" "Q115")
		)
		("@t6g_mb_lib.t6g(sch_1):page196_i73@pure_quanta.q_res(chips)"
			("LOCATION" "R1246")
		)
		("@t6g_mb_lib.t6g(sch_1):page196_i74@pure_quanta.q_res(chips)"
			("LOCATION" "R1247")
		)
		("@t6g_mb_lib.t6g(sch_1):page196_i65@pure_quanta.q_res(chips)"
			("LOCATION" "R1249")
		)
		("@t6g_mb_lib.t6g(sch_1):page196_i68@pure_quanta.q_res(chips)"
			("LOCATION" "R1265")
		)
		("@t6g_mb_lib.t6g(sch_1):page196_i59@pure_quanta.q_res(chips)"
			("LOCATION" "R1266")
		)
		("@t6g_mb_lib.t6g(sch_1):page196_i76@pure_quanta.q_res(chips)"
			("LOCATION" "R1820")
		)
		("@t6g_mb_lib.t6g(sch_1):page196_i60@pure_quanta.q_res(chips)"
			("LOCATION" "R1924")
		)
		("@t6g_mb_lib.t6g(sch_1):page196_i66@pure_quanta.q_res(chips)"
			("LOCATION" "R1925")
		)
		("@t6g_mb_lib.t6g(sch_1):page196_i72@pure_quanta.q_res(chips)"
			("LOCATION" "R1926")
		)
		("@t6g_mb_lib.t6g(sch_1):page196_i53@pure_quanta.q_res(chips)"
			("LOCATION" "R1927")
		)
		("@t6g_mb_lib.t6g(sch_1):page196_i55@pure_quanta.q_res(chips)"
			("LOCATION" "R1930")
		)
		("@t6g_mb_lib.t6g(sch_1):page181_i548@pure_quanta.mosfet_nch_dual(chips)"
			("LOCATION" "Q131")
		)
		("@t6g_mb_lib.t6g(sch_1):page181_i543@pure_quanta.mosfet_nch_dual(chips)"
			("LOCATION" "Q131")
		)
		("@t6g_mb_lib.t6g(sch_1):page181_i558@pure_quanta.mosfet_nch_dual(chips)"
			("LOCATION" "Q132")
		)
		("@t6g_mb_lib.t6g(sch_1):page181_i555@pure_quanta.mosfet_nch_dual(chips)"
			("LOCATION" "Q132")
		)
		("@t6g_mb_lib.t6g(sch_1):page181_i570@pure_quanta.mosfet_nch_dual(chips)"
			("LOCATION" "Q133")
		)
		("@t6g_mb_lib.t6g(sch_1):page181_i568@pure_quanta.mosfet_nch_dual(chips)"
			("LOCATION" "Q133")
		)
		("@t6g_mb_lib.t6g(sch_1):page181_i577@pure_quanta.mosfet_nch_dual(chips)"
			("LOCATION" "Q134")
		)
		("@t6g_mb_lib.t6g(sch_1):page181_i572@pure_quanta.mosfet_nch_dual(chips)"
			("LOCATION" "Q134")
		)
		("@t6g_mb_lib.t6g(sch_1):page181_i462@pure_quanta.q_res(chips)"
			("LOCATION" "R3657")
		)
		("@t6g_mb_lib.t6g(sch_1):page181_i461@pure_quanta.q_res(chips)"
			("LOCATION" "R3658")
		)
		("@t6g_mb_lib.t6g(sch_1):page181_i460@pure_quanta.q_res(chips)"
			("LOCATION" "R3659")
		)
		("@t6g_mb_lib.t6g(sch_1):page181_i459@pure_quanta.q_res(chips)"
			("LOCATION" "R3660")
		)
		("@t6g_mb_lib.t6g(sch_1):page181_i458@pure_quanta.q_res(chips)"
			("LOCATION" "R3661")
		)
		("@t6g_mb_lib.t6g(sch_1):page181_i457@pure_quanta.q_res(chips)"
			("LOCATION" "R3662")
		)
		("@t6g_mb_lib.t6g(sch_1):page181_i455@pure_quanta.q_res(chips)"
			("LOCATION" "R3664")
		)
		("@t6g_mb_lib.t6g(sch_1):page181_i463@pure_quanta.q_res(chips)"
			("LOCATION" "R3670")
		)
		("@t6g_mb_lib.t6g(sch_1):page181_i542@pure_quanta.q_res(chips)"
			("LOCATION" "R3724")
		)
		("@t6g_mb_lib.t6g(sch_1):page181_i552@pure_quanta.q_res(chips)"
			("LOCATION" "R3725")
		)
		("@t6g_mb_lib.t6g(sch_1):page181_i562@pure_quanta.q_res(chips)"
			("LOCATION" "R3727")
		)
		("@t6g_mb_lib.t6g(sch_1):page181_i566@pure_quanta.q_res(chips)"
			("LOCATION" "R3728")
		)
		("@t6g_mb_lib.t6g(sch_1):page181_i546@pure_quanta.q_res(chips)"
			("LOCATION" "R3838")
		)
		("@t6g_mb_lib.t6g(sch_1):page181_i556@pure_quanta.q_res(chips)"
			("LOCATION" "R3839")
		)
		("@t6g_mb_lib.t6g(sch_1):page181_i569@pure_quanta.q_res(chips)"
			("LOCATION" "R3840")
		)
		("@t6g_mb_lib.t6g(sch_1):page181_i574@pure_quanta.q_res(chips)"
			("LOCATION" "R3841")
		)
		("@t6g_mb_lib.t6g(sch_1):page181_i401@pure_quanta.emmitsburg_rev0p9(chips)"
			("LOCATION" "U8")
		)
		("@t6g_mb_lib.t6g(sch_1):page187_i41@pure_quanta.mosfet_nch_dual(chips)"
			("LOCATION" "Q227")
		)
		("@t6g_mb_lib.t6g(sch_1):page187_i40@pure_quanta.mosfet_nch_dual(chips)"
			("LOCATION" "Q227")
		)
		("@t6g_mb_lib.t6g(sch_1):page187_i6@pure_quanta.q_res(chips)"
			("LOCATION" "R488")
		)
		("@t6g_mb_lib.t6g(sch_1):page187_i14@pure_quanta.q_res(chips)"
			("LOCATION" "R492")
		)
		("@t6g_mb_lib.t6g(sch_1):page187_i36@pure_quanta.q_res(chips)"
			("LOCATION" "R1584")
		)
		("@t6g_mb_lib.t6g(sch_1):page187_i21@pure_quanta.q_res(chips)"
			("LOCATION" "R3554")
		)
		("@t6g_mb_lib.t6g(sch_1):page187_i24@pure_quanta.q_res(chips)"
			("LOCATION" "R3555")
		)
		("@t6g_mb_lib.t6g(sch_1):page187_i30@pure_quanta.q_res(chips)"
			("LOCATION" "R3671")
		)
		("@t6g_mb_lib.t6g(sch_1):page187_i32@pure_quanta.q_res(chips)"
			("LOCATION" "R3673")
		)
		("@t6g_mb_lib.t6g(sch_1):page187_i38@pure_quanta.q_res(chips)"
			("LOCATION" "R3721")
		)
		("@t6g_mb_lib.t6g(sch_1):page16_i634@pure_quanta.q_res(chips)"
			("LOCATION" "R1")
		)
		("@t6g_mb_lib.t6g(sch_1):page16_i639@pure_quanta.q_res(chips)"
			("LOCATION" "R2")
		)
		("@t6g_mb_lib.t6g(sch_1):page16_i640@pure_quanta.q_res(chips)"
			("LOCATION" "R3")
		)
		("@t6g_mb_lib.t6g(sch_1):page16_i641@pure_quanta.q_res(chips)"
			("LOCATION" "R4")
		)
		("@t6g_mb_lib.t6g(sch_1):page16_i642@pure_quanta.q_res(chips)"
			("LOCATION" "R5")
		)
		("@t6g_mb_lib.t6g(sch_1):page16_i643@pure_quanta.q_res(chips)"
			("LOCATION" "R6")
		)
		("@t6g_mb_lib.t6g(sch_1):page16_i650@pure_quanta.socket4677_azifs035p001c01(chips)"
			("LOCATION" "U2")
		)
		("@t6g_mb_lib.t6g(sch_1):page17_i329@pure_quanta.q_res(chips)"
			("LOCATION" "R7")
		)
		("@t6g_mb_lib.t6g(sch_1):page17_i349@pure_quanta.q_res(chips)"
			("LOCATION" "R10")
		)
		("@t6g_mb_lib.t6g(sch_1):page17_i350@pure_quanta.q_res(chips)"
			("LOCATION" "R11")
		)
		("@t6g_mb_lib.t6g(sch_1):page17_i291@pure_quanta.q_res(chips)"
			("LOCATION" "R12")
		)
		("@t6g_mb_lib.t6g(sch_1):page17_i292@pure_quanta.q_res(chips)"
			("LOCATION" "R13")
		)
		("@t6g_mb_lib.t6g(sch_1):page17_i293@pure_quanta.q_res(chips)"
			("LOCATION" "R14")
		)
		("@t6g_mb_lib.t6g(sch_1):page17_i294@pure_quanta.q_res(chips)"
			("LOCATION" "R15")
		)
		("@t6g_mb_lib.t6g(sch_1):page17_i295@pure_quanta.q_res(chips)"
			("LOCATION" "R16")
		)
		("@t6g_mb_lib.t6g(sch_1):page17_i296@pure_quanta.q_res(chips)"
			("LOCATION" "R17")
		)
		("@t6g_mb_lib.t6g(sch_1):page17_i312@pure_quanta.q_res(chips)"
			("LOCATION" "R317")
		)
		("@t6g_mb_lib.t6g(sch_1):page17_i351@pure_quanta.q_res(chips)"
			("LOCATION" "R322")
		)
		("@t6g_mb_lib.t6g(sch_1):page17_i284@pure_quanta.q_res(chips)"
			("LOCATION" "R328")
		)
		("@t6g_mb_lib.t6g(sch_1):page17_i313@pure_quanta.q_res(chips)"
			("LOCATION" "R548")
		)
		("@t6g_mb_lib.t6g(sch_1):page17_i319@pure_quanta.q_res(chips)"
			("LOCATION" "R555")
		)
		("@t6g_mb_lib.t6g(sch_1):page17_i318@pure_quanta.q_res(chips)"
			("LOCATION" "R556")
		)
		("@t6g_mb_lib.t6g(sch_1):page17_i356@pure_quanta.q_res(chips)"
			("LOCATION" "R3820")
		)
		("@t6g_mb_lib.t6g(sch_1):page17_i357@pure_quanta.q_res(chips)"
			("LOCATION" "R3821")
		)
		("@t6g_mb_lib.t6g(sch_1):page17_i355@pure_quanta.socket4677_azifs035p001c01(chips)"
			("LOCATION" "U2")
		)
		("@t6g_mb_lib.t6g(sch_1):page192_i262@pure_quanta.q_res(chips)"
			("LOCATION" "R8")
		)
		("@t6g_mb_lib.t6g(sch_1):page192_i263@pure_quanta.q_res(chips)"
			("LOCATION" "R71")
		)
		("@t6g_mb_lib.t6g(sch_1):page192_i238@pure_quanta.q_res(chips)"
			("LOCATION" "R1262")
		)
		("@t6g_mb_lib.t6g(sch_1):page192_i258@pure_quanta.q_res(chips)"
			("LOCATION" "R1758")
		)
		("@t6g_mb_lib.t6g(sch_1):page192_i259@pure_quanta.q_res(chips)"
			("LOCATION" "R1766")
		)
		("@t6g_mb_lib.t6g(sch_1):page192_i260@pure_quanta.q_res(chips)"
			("LOCATION" "R1767")
		)
		("@t6g_mb_lib.t6g(sch_1):page192_i264@pure_quanta.q_res(chips)"
			("LOCATION" "R1768")
		)
		("@t6g_mb_lib.t6g(sch_1):page192_i248@pure_quanta.q_res(chips)"
			("LOCATION" "R1769")
		)
		("@t6g_mb_lib.t6g(sch_1):page192_i250@pure_quanta.q_res(chips)"
			("LOCATION" "R1770")
		)
		("@t6g_mb_lib.t6g(sch_1):page192_i251@pure_quanta.q_res(chips)"
			("LOCATION" "R1771")
		)
		("@t6g_mb_lib.t6g(sch_1):page192_i231@pure_quanta.q_res(chips)"
			("LOCATION" "R1772")
		)
		("@t6g_mb_lib.t6g(sch_1):page192_i232@pure_quanta.q_res(chips)"
			("LOCATION" "R1773")
		)
		("@t6g_mb_lib.t6g(sch_1):page192_i233@pure_quanta.q_res(chips)"
			("LOCATION" "R1774")
		)
		("@t6g_mb_lib.t6g(sch_1):page192_i234@pure_quanta.q_res(chips)"
			("LOCATION" "R1775")
		)
		("@t6g_mb_lib.t6g(sch_1):page192_i236@pure_quanta.q_res(chips)"
			("LOCATION" "R1776")
		)
		("@t6g_mb_lib.t6g(sch_1):page192_i237@pure_quanta.q_res(chips)"
			("LOCATION" "R1777")
		)
		("@t6g_mb_lib.t6g(sch_1):page192_i242@pure_quanta.q_res(chips)"
			("LOCATION" "R1778")
		)
		("@t6g_mb_lib.t6g(sch_1):page192_i243@pure_quanta.q_res(chips)"
			("LOCATION" "R1779")
		)
		("@t6g_mb_lib.t6g(sch_1):page192_i271@pure_quanta.q_res(chips)"
			("LOCATION" "R1901")
		)
		("@t6g_mb_lib.t6g(sch_1):page192_i269@pure_quanta.q_res(chips)"
			("LOCATION" "R1902")
		)
		("@t6g_mb_lib.t6g(sch_1):page19_i142@pure_quanta.q_res(chips)"
			("LOCATION" "R18")
		)
		("@t6g_mb_lib.t6g(sch_1):page19_i140@pure_quanta.q_res(chips)"
			("LOCATION" "R19")
		)
		("@t6g_mb_lib.t6g(sch_1):page19_i139@pure_quanta.q_res(chips)"
			("LOCATION" "R20")
		)
		("@t6g_mb_lib.t6g(sch_1):page19_i138@pure_quanta.q_res(chips)"
			("LOCATION" "R21")
		)
		("@t6g_mb_lib.t6g(sch_1):page19_i135@pure_quanta.q_res(chips)"
			("LOCATION" "R22")
		)
		("@t6g_mb_lib.t6g(sch_1):page19_i134@pure_quanta.q_res(chips)"
			("LOCATION" "R23")
		)
		("@t6g_mb_lib.t6g(sch_1):page19_i136@pure_quanta.q_res(chips)"
			("LOCATION" "R24")
		)
		("@t6g_mb_lib.t6g(sch_1):page19_i137@pure_quanta.q_res(chips)"
			("LOCATION" "R25")
		)
		("@t6g_mb_lib.t6g(sch_1):page19_i156@pure_quanta.socket4677_azifs035p001c01(chips)"
			("LOCATION" "U2")
		)
		("@t6g_mb_lib.t6g(sch_1):page50_i50@pure_quanta.q_res(chips)"
			("LOCATION" "R49")
		)
		("@t6g_mb_lib.t6g(sch_1):page50_i49@pure_quanta.q_res(chips)"
			("LOCATION" "R50")
		)
		("@t6g_mb_lib.t6g(sch_1):page50_i60@pure_quanta.q_res(chips)"
			("LOCATION" "R51")
		)
		("@t6g_mb_lib.t6g(sch_1):page50_i63@pure_quanta.q_res(chips)"
			("LOCATION" "R52")
		)
		("@t6g_mb_lib.t6g(sch_1):page50_i62@pure_quanta.q_res(chips)"
			("LOCATION" "R53")
		)
		("@t6g_mb_lib.t6g(sch_1):page50_i61@pure_quanta.q_res(chips)"
			("LOCATION" "R54")
		)
		("@t6g_mb_lib.t6g(sch_1):page50_i75@pure_quanta.socket4677_azifs035p001c01(chips)"
			("LOCATION" "U1")
		)
		("@t6g_mb_lib.t6g(sch_1):page48_i249@pure_quanta.q_res(chips)"
			("LOCATION" "R55")
		)
		("@t6g_mb_lib.t6g(sch_1):page48_i250@pure_quanta.q_res(chips)"
			("LOCATION" "R56")
		)
		("@t6g_mb_lib.t6g(sch_1):page48_i253@pure_quanta.q_res(chips)"
			("LOCATION" "R57")
		)
		("@t6g_mb_lib.t6g(sch_1):page48_i251@pure_quanta.q_res(chips)"
			("LOCATION" "R58")
		)
		("@t6g_mb_lib.t6g(sch_1):page48_i252@pure_quanta.q_res(chips)"
			("LOCATION" "R59")
		)
		("@t6g_mb_lib.t6g(sch_1):page48_i254@pure_quanta.q_res(chips)"
			("LOCATION" "R60")
		)
		("@t6g_mb_lib.t6g(sch_1):page48_i256@pure_quanta.q_res(chips)"
			("LOCATION" "R516")
		)
		("@t6g_mb_lib.t6g(sch_1):page48_i258@pure_quanta.q_res(chips)"
			("LOCATION" "R557")
		)
		("@t6g_mb_lib.t6g(sch_1):page48_i259@pure_quanta.q_res(chips)"
			("LOCATION" "R558")
		)
		("@t6g_mb_lib.t6g(sch_1):page48_i260@pure_quanta.q_res(chips)"
			("LOCATION" "R559")
		)
		("@t6g_mb_lib.t6g(sch_1):page48_i261@pure_quanta.q_res(chips)"
			("LOCATION" "R560")
		)
		("@t6g_mb_lib.t6g(sch_1):page48_i288@pure_quanta.q_res(chips)"
			("LOCATION" "R3805")
		)
		("@t6g_mb_lib.t6g(sch_1):page48_i290@pure_quanta.q_res(chips)"
			("LOCATION" "R3822")
		)
		("@t6g_mb_lib.t6g(sch_1):page48_i293@pure_quanta.q_res(chips)"
			("LOCATION" "R3824")
		)
		("@t6g_mb_lib.t6g(sch_1):page48_i287@pure_quanta.socket4677_azifs035p001c01(chips)"
			("LOCATION" "U1")
		)
		("@t6g_mb_lib.t6g(sch_1):page47_i632@pure_quanta.q_res(chips)"
			("LOCATION" "R61")
		)
		("@t6g_mb_lib.t6g(sch_1):page47_i631@pure_quanta.q_res(chips)"
			("LOCATION" "R62")
		)
		("@t6g_mb_lib.t6g(sch_1):page47_i635@pure_quanta.q_res(chips)"
			("LOCATION" "R63")
		)
		("@t6g_mb_lib.t6g(sch_1):page47_i636@pure_quanta.q_res(chips)"
			("LOCATION" "R64")
		)
		("@t6g_mb_lib.t6g(sch_1):page47_i637@pure_quanta.q_res(chips)"
			("LOCATION" "R65")
		)
		("@t6g_mb_lib.t6g(sch_1):page47_i638@pure_quanta.q_res(chips)"
			("LOCATION" "R66")
		)
		("@t6g_mb_lib.t6g(sch_1):page47_i614@pure_quanta.q_res(chips)"
			("LOCATION" "R1270")
		)
		("@t6g_mb_lib.t6g(sch_1):page47_i589@pure_quanta.socket4677_azifs035p001c01(chips)"
			("LOCATION" "U1")
		)
		("@t6g_mb_lib.t6g(sch_1):page46_i14@pure_quanta.q_res(chips)"
			("LOCATION" "R67")
		)
		("@t6g_mb_lib.t6g(sch_1):page46_i13@pure_quanta.q_res(chips)"
			("LOCATION" "R68")
		)
		("@t6g_mb_lib.t6g(sch_1):page46_i4@pure_quanta.q_res(chips)"
			("LOCATION" "R69")
		)
		("@t6g_mb_lib.t6g(sch_1):page46_i3@pure_quanta.q_res(chips)"
			("LOCATION" "R70")
		)
		("@t6g_mb_lib.t6g(sch_1):page46_i12@pure_quanta.q_res(chips)"
			("LOCATION" "R1218")
		)
		("@t6g_mb_lib.t6g(sch_1):page46_i11@pure_quanta.q_res(chips)"
			("LOCATION" "R1219")
		)
		("@t6g_mb_lib.t6g(sch_1):page46_i31@pure_quanta.q_res(chips)"
			("LOCATION" "R1223")
		)
		("@t6g_mb_lib.t6g(sch_1):page46_i28@pure_quanta.q_res(chips)"
			("LOCATION" "R1224")
		)
		("@t6g_mb_lib.t6g(sch_1):page46_i27@pure_quanta.q_res(chips)"
			("LOCATION" "R1225")
		)
		("@t6g_mb_lib.t6g(sch_1):page46_i30@pure_quanta.q_res(chips)"
			("LOCATION" "R1226")
		)
		("@t6g_mb_lib.t6g(sch_1):page46_i29@pure_quanta.q_res(chips)"
			("LOCATION" "R1227")
		)
		("@t6g_mb_lib.t6g(sch_1):page46_i16@pure_quanta.q_res(chips)"
			("LOCATION" "R1398")
		)
		("@t6g_mb_lib.t6g(sch_1):page46_i15@pure_quanta.q_res(chips)"
			("LOCATION" "R1399")
		)
		("@t6g_mb_lib.t6g(sch_1):page97_i7@pure_quanta.q_res(chips)"
			("LOCATION" "R90")
		)
		("@t6g_mb_lib.t6g(sch_1):page97_i6@pure_quanta.q_res(chips)"
			("LOCATION" "R91")
		)
		("@t6g_mb_lib.t6g(sch_1):page97_i5@pure_quanta.q_res(chips)"
			("LOCATION" "R92")
		)
		("@t6g_mb_lib.t6g(sch_1):page97_i4@pure_quanta.q_res(chips)"
			("LOCATION" "R93")
		)
		("@t6g_mb_lib.t6g(sch_1):page97_i15@pure_quanta.q_res(chips)"
			("LOCATION" "R94")
		)
		("@t6g_mb_lib.t6g(sch_1):page97_i14@pure_quanta.q_res(chips)"
			("LOCATION" "R95")
		)
		("@t6g_mb_lib.t6g(sch_1):page97_i13@pure_quanta.q_res(chips)"
			("LOCATION" "R96")
		)
		("@t6g_mb_lib.t6g(sch_1):page97_i12@pure_quanta.q_res(chips)"
			("LOCATION" "R97")
		)
		("@t6g_mb_lib.t6g(sch_1):page97_i34@pure_quanta.q_res(chips)"
			("LOCATION" "R98")
		)
		("@t6g_mb_lib.t6g(sch_1):page97_i33@pure_quanta.q_res(chips)"
			("LOCATION" "R99")
		)
		("@t6g_mb_lib.t6g(sch_1):page97_i32@pure_quanta.q_res(chips)"
			("LOCATION" "R100")
		)
		("@t6g_mb_lib.t6g(sch_1):page97_i31@pure_quanta.q_res(chips)"
			("LOCATION" "R101")
		)
		("@t6g_mb_lib.t6g(sch_1):page97_i30@pure_quanta.q_res(chips)"
			("LOCATION" "R102")
		)
		("@t6g_mb_lib.t6g(sch_1):page97_i29@pure_quanta.q_res(chips)"
			("LOCATION" "R103")
		)
		("@t6g_mb_lib.t6g(sch_1):page97_i28@pure_quanta.q_res(chips)"
			("LOCATION" "R104")
		)
		("@t6g_mb_lib.t6g(sch_1):page97_i20@pure_quanta.q_res(chips)"
			("LOCATION" "R105")
		)
		("@t6g_mb_lib.t6g(sch_1):page97_i54@pure_quanta.q_res(chips)"
			("LOCATION" "R114")
		)
		("@t6g_mb_lib.t6g(sch_1):page97_i53@pure_quanta.q_res(chips)"
			("LOCATION" "R115")
		)
		("@t6g_mb_lib.t6g(sch_1):page97_i52@pure_quanta.q_res(chips)"
			("LOCATION" "R116")
		)
		("@t6g_mb_lib.t6g(sch_1):page97_i51@pure_quanta.q_res(chips)"
			("LOCATION" "R117")
		)
		("@t6g_mb_lib.t6g(sch_1):page97_i50@pure_quanta.q_res(chips)"
			("LOCATION" "R118")
		)
		("@t6g_mb_lib.t6g(sch_1):page97_i49@pure_quanta.q_res(chips)"
			("LOCATION" "R119")
		)
		("@t6g_mb_lib.t6g(sch_1):page247_i43@pure_quanta.q_res(chips)"
			("LOCATION" "R109")
		)
		("@t6g_mb_lib.t6g(sch_1):page247_i50@pure_quanta.q_res(chips)"
			("LOCATION" "R110")
		)
		("@t6g_mb_lib.t6g(sch_1):page247_i25@pure_quanta.q_res(chips)"
			("LOCATION" "R269")
		)
		("@t6g_mb_lib.t6g(sch_1):page247_i46@pure_quanta.q_res(chips)"
			("LOCATION" "R1205")
		)
		("@t6g_mb_lib.t6g(sch_1):page247_i48@pure_quanta.q_res(chips)"
			("LOCATION" "R1207")
		)
		("@t6g_mb_lib.t6g(sch_1):page247_i41@pure_quanta.q_res(chips)"
			("LOCATION" "R1744")
		)
		("@t6g_mb_lib.t6g(sch_1):page247_i44@pure_quanta.q_res(chips)"
			("LOCATION" "R1995")
		)
		("@t6g_mb_lib.t6g(sch_1):page247_i45@pure_quanta.q_res(chips)"
			("LOCATION" "R1996")
		)
		("@t6g_mb_lib.t6g(sch_1):page247_i49@pure_quanta.q_res(chips)"
			("LOCATION" "R2203")
		)
		("@t6g_mb_lib.t6g(sch_1):page247_i42@pure_quanta.q_res(chips)"
			("LOCATION" "R2221")
		)
		("@t6g_mb_lib.t6g(sch_1):page247_i47@pure_quanta.q_res(chips)"
			("LOCATION" "R2224")
		)
		("@t6g_mb_lib.t6g(sch_1):page247_i19@pure_quanta.q_res(chips)"
			("LOCATION" "R2228")
		)
		("@t6g_mb_lib.t6g(sch_1):page247_i23@pure_quanta.q_res(chips)"
			("LOCATION" "R2232")
		)
		("@t6g_mb_lib.t6g(sch_1):page247_i13@pure_quanta.q_res(chips)"
			("LOCATION" "R2234")
		)
		("@t6g_mb_lib.t6g(sch_1):page247_i15@pure_quanta.q_res(chips)"
			("LOCATION" "R2235")
		)
		("@t6g_mb_lib.t6g(sch_1):page247_i14@pure_quanta.q_res(chips)"
			("LOCATION" "R2236")
		)
		("@t6g_mb_lib.t6g(sch_1):page204_i12@pure_quanta.q_res(chips)"
			("LOCATION" "R143")
		)
		("@t6g_mb_lib.t6g(sch_1):page204_i8@pure_quanta.q_res(chips)"
			("LOCATION" "R144")
		)
		("@t6g_mb_lib.t6g(sch_1):page204_i7@pure_quanta.q_res(chips)"
			("LOCATION" "R145")
		)
		("@t6g_mb_lib.t6g(sch_1):page204_i3@pure_quanta.q_res(chips)"
			("LOCATION" "R146")
		)
		("@t6g_mb_lib.t6g(sch_1):page204_i10@pure_quanta.q_res(chips)"
			("LOCATION" "R147")
		)
		("@t6g_mb_lib.t6g(sch_1):page204_i4@pure_quanta.q_res(chips)"
			("LOCATION" "R148")
		)
		("@t6g_mb_lib.t6g(sch_1):page204_i9@pure_quanta.q_res(chips)"
			("LOCATION" "R149")
		)
		("@t6g_mb_lib.t6g(sch_1):page204_i1@pure_quanta.q_res(chips)"
			("LOCATION" "R1989")
		)
		("@t6g_mb_lib.t6g(sch_1):page92_i61@pure_quanta.q_res(chips)"
			("LOCATION" "R249")
		)
		("@t6g_mb_lib.t6g(sch_1):page92_i62@pure_quanta.q_res(chips)"
			("LOCATION" "R250")
		)
		("@t6g_mb_lib.t6g(sch_1):page92_i63@pure_quanta.q_res(chips)"
			("LOCATION" "R251")
		)
		("@t6g_mb_lib.t6g(sch_1):page92_i65@pure_quanta.q_res(chips)"
			("LOCATION" "R252")
		)
		("@t6g_mb_lib.t6g(sch_1):page92_i64@pure_quanta.q_res(chips)"
			("LOCATION" "R253")
		)
		("@t6g_mb_lib.t6g(sch_1):page92_i66@pure_quanta.q_res(chips)"
			("LOCATION" "R254")
		)
		("@t6g_mb_lib.t6g(sch_1):page92_i68@pure_quanta.q_res(chips)"
			("LOCATION" "R255")
		)
		("@t6g_mb_lib.t6g(sch_1):page92_i69@pure_quanta.q_res(chips)"
			("LOCATION" "R256")
		)
		("@t6g_mb_lib.t6g(sch_1):page92_i70@pure_quanta.q_res(chips)"
			("LOCATION" "R257")
		)
		("@t6g_mb_lib.t6g(sch_1):page92_i71@pure_quanta.q_res(chips)"
			("LOCATION" "R258")
		)
		("@t6g_mb_lib.t6g(sch_1):page92_i73@pure_quanta.q_res(chips)"
			("LOCATION" "R259")
		)
		("@t6g_mb_lib.t6g(sch_1):page92_i72@pure_quanta.q_res(chips)"
			("LOCATION" "R260")
		)
		("@t6g_mb_lib.t6g(sch_1):page92_i39@pure_quanta.q_res(chips)"
			("LOCATION" "R517")
		)
		("@t6g_mb_lib.t6g(sch_1):page92_i45@pure_quanta.q_res(chips)"
			("LOCATION" "R695")
		)
		("@t6g_mb_lib.t6g(sch_1):page92_i40@pure_quanta.q_res(chips)"
			("LOCATION" "R1391")
		)
		("@t6g_mb_lib.t6g(sch_1):page92_i42@pure_quanta.q_res(chips)"
			("LOCATION" "R1392")
		)
		("@t6g_mb_lib.t6g(sch_1):page92_i46@pure_quanta.q_res(chips)"
			("LOCATION" "R1393")
		)
		("@t6g_mb_lib.t6g(sch_1):page92_i47@pure_quanta.q_res(chips)"
			("LOCATION" "R1394")
		)
		("@t6g_mb_lib.t6g(sch_1):page91_i160@pure_quanta.q_res(chips)"
			("LOCATION" "R261")
		)
		("@t6g_mb_lib.t6g(sch_1):page91_i159@pure_quanta.q_res(chips)"
			("LOCATION" "R262")
		)
		("@t6g_mb_lib.t6g(sch_1):page91_i157@pure_quanta.q_res(chips)"
			("LOCATION" "R263")
		)
		("@t6g_mb_lib.t6g(sch_1):page91_i156@pure_quanta.q_res(chips)"
			("LOCATION" "R264")
		)
		("@t6g_mb_lib.t6g(sch_1):page91_i155@pure_quanta.q_res(chips)"
			("LOCATION" "R265")
		)
		("@t6g_mb_lib.t6g(sch_1):page91_i154@pure_quanta.q_res(chips)"
			("LOCATION" "R266")
		)
		("@t6g_mb_lib.t6g(sch_1):page91_i153@pure_quanta.q_res(chips)"
			("LOCATION" "R267")
		)
		("@t6g_mb_lib.t6g(sch_1):page91_i152@pure_quanta.q_res(chips)"
			("LOCATION" "R268")
		)
		("@t6g_mb_lib.t6g(sch_1):page91_i173@pure_quanta.q_res(chips)"
			("LOCATION" "R270")
		)
		("@t6g_mb_lib.t6g(sch_1):page91_i170@pure_quanta.q_res(chips)"
			("LOCATION" "R271")
		)
		("@t6g_mb_lib.t6g(sch_1):page91_i171@pure_quanta.q_res(chips)"
			("LOCATION" "R272")
		)
		("@t6g_mb_lib.t6g(sch_1):page91_i168@pure_quanta.q_res(chips)"
			("LOCATION" "R273")
		)
		("@t6g_mb_lib.t6g(sch_1):page91_i169@pure_quanta.q_res(chips)"
			("LOCATION" "R274")
		)
		("@t6g_mb_lib.t6g(sch_1):page91_i202@pure_quanta.q_res(chips)"
			("LOCATION" "R275")
		)
		("@t6g_mb_lib.t6g(sch_1):page91_i201@pure_quanta.q_res(chips)"
			("LOCATION" "R276")
		)
		("@t6g_mb_lib.t6g(sch_1):page91_i200@pure_quanta.q_res(chips)"
			("LOCATION" "R277")
		)
		("@t6g_mb_lib.t6g(sch_1):page91_i199@pure_quanta.q_res(chips)"
			("LOCATION" "R278")
		)
		("@t6g_mb_lib.t6g(sch_1):page91_i198@pure_quanta.q_res(chips)"
			("LOCATION" "R279")
		)
		("@t6g_mb_lib.t6g(sch_1):page91_i197@pure_quanta.q_res(chips)"
			("LOCATION" "R280")
		)
		("@t6g_mb_lib.t6g(sch_1):page91_i196@pure_quanta.q_res(chips)"
			("LOCATION" "R281")
		)
		("@t6g_mb_lib.t6g(sch_1):page91_i195@pure_quanta.q_res(chips)"
			("LOCATION" "R282")
		)
		("@t6g_mb_lib.t6g(sch_1):page91_i218@pure_quanta.q_res(chips)"
			("LOCATION" "R283")
		)
		("@t6g_mb_lib.t6g(sch_1):page91_i215@pure_quanta.q_res(chips)"
			("LOCATION" "R284")
		)
		("@t6g_mb_lib.t6g(sch_1):page91_i216@pure_quanta.q_res(chips)"
			("LOCATION" "R285")
		)
		("@t6g_mb_lib.t6g(sch_1):page91_i189@pure_quanta.q_res(chips)"
			("LOCATION" "R286")
		)
		("@t6g_mb_lib.t6g(sch_1):page91_i190@pure_quanta.q_res(chips)"
			("LOCATION" "R287")
		)
		("@t6g_mb_lib.t6g(sch_1):page91_i187@pure_quanta.q_res(chips)"
			("LOCATION" "R288")
		)
		("@t6g_mb_lib.t6g(sch_1):page91_i188@pure_quanta.q_res(chips)"
			("LOCATION" "R289")
		)
		("@t6g_mb_lib.t6g(sch_1):page91_i185@pure_quanta.q_res(chips)"
			("LOCATION" "R290")
		)
		("@t6g_mb_lib.t6g(sch_1):page91_i186@pure_quanta.q_res(chips)"
			("LOCATION" "R291")
		)
		("@t6g_mb_lib.t6g(sch_1):page91_i226@pure_quanta.q_res(chips)"
			("LOCATION" "R292")
		)
		("@t6g_mb_lib.t6g(sch_1):page91_i225@pure_quanta.q_res(chips)"
			("LOCATION" "R293")
		)
		("@t6g_mb_lib.t6g(sch_1):page91_i224@pure_quanta.q_res(chips)"
			("LOCATION" "R294")
		)
		("@t6g_mb_lib.t6g(sch_1):page91_i223@pure_quanta.q_res(chips)"
			("LOCATION" "R295")
		)
		("@t6g_mb_lib.t6g(sch_1):page91_i147@pure_quanta.q_res(chips)"
			("LOCATION" "R1008")
		)
		("@t6g_mb_lib.t6g(sch_1):page91_i161@pure_quanta.q_res(chips)"
			("LOCATION" "R1009")
		)
		("@t6g_mb_lib.t6g(sch_1):page91_i151@pure_quanta.q_res(chips)"
			("LOCATION" "R1228")
		)
		("@t6g_mb_lib.t6g(sch_1):page91_i150@pure_quanta.q_res(chips)"
			("LOCATION" "R1229")
		)
		("@t6g_mb_lib.t6g(sch_1):page91_i149@pure_quanta.q_res(chips)"
			("LOCATION" "R1230")
		)
		("@t6g_mb_lib.t6g(sch_1):page91_i194@pure_quanta.q_res(chips)"
			("LOCATION" "R1231")
		)
		("@t6g_mb_lib.t6g(sch_1):page91_i193@pure_quanta.q_res(chips)"
			("LOCATION" "R1232")
		)
		("@t6g_mb_lib.t6g(sch_1):page91_i192@pure_quanta.q_res(chips)"
			("LOCATION" "R1233")
		)
		("@t6g_mb_lib.t6g(sch_1):page91_i183@pure_quanta.q_res(chips)"
			("LOCATION" "R1234")
		)
		("@t6g_mb_lib.t6g(sch_1):page91_i184@pure_quanta.q_res(chips)"
			("LOCATION" "R1235")
		)
		("@t6g_mb_lib.t6g(sch_1):page91_i175@pure_quanta.q_res(chips)"
			("LOCATION" "R1236")
		)
		("@t6g_mb_lib.t6g(sch_1):page91_i222@pure_quanta.q_res(chips)"
			("LOCATION" "R1237")
		)
		("@t6g_mb_lib.t6g(sch_1):page91_i221@pure_quanta.q_res(chips)"
			("LOCATION" "R1238")
		)
		("@t6g_mb_lib.t6g(sch_1):page91_i220@pure_quanta.q_res(chips)"
			("LOCATION" "R1239")
		)
		("@t6g_mb_lib.t6g(sch_1):page188_i35@pure_quanta.q_res(chips)"
			("LOCATION" "R367")
		)
		("@t6g_mb_lib.t6g(sch_1):page188_i36@pure_quanta.q_res(chips)"
			("LOCATION" "R368")
		)
		("@t6g_mb_lib.t6g(sch_1):page188_i39@pure_quanta.q_res(chips)"
			("LOCATION" "R369")
		)
		("@t6g_mb_lib.t6g(sch_1):page188_i40@pure_quanta.q_res(chips)"
			("LOCATION" "R370")
		)
		("@t6g_mb_lib.t6g(sch_1):page188_i21@pure_quanta.q_res(chips)"
			("LOCATION" "R376")
		)
		("@t6g_mb_lib.t6g(sch_1):page188_i4@pure_quanta.q_res(chips)"
			("LOCATION" "R518")
		)
		("@t6g_mb_lib.t6g(sch_1):page188_i15@pure_quanta.q_res(chips)"
			("LOCATION" "R1636")
		)
		("@t6g_mb_lib.t6g(sch_1):page188_i16@pure_quanta.q_res(chips)"
			("LOCATION" "R1637")
		)
		("@t6g_mb_lib.t6g(sch_1):page188_i22@pure_quanta.q_res(chips)"
			("LOCATION" "R1638")
		)
		("@t6g_mb_lib.t6g(sch_1):page188_i25@pure_quanta.q_res(chips)"
			("LOCATION" "R1639")
		)
		("@t6g_mb_lib.t6g(sch_1):page188_i26@pure_quanta.q_res(chips)"
			("LOCATION" "R1640")
		)
		("@t6g_mb_lib.t6g(sch_1):page188_i19@pure_quanta.q_res(chips)"
			("LOCATION" "R1641")
		)
		("@t6g_mb_lib.t6g(sch_1):page188_i8@pure_quanta.q_res(chips)"
			("LOCATION" "R1642")
		)
		("@t6g_mb_lib.t6g(sch_1):page188_i10@pure_quanta.q_res(chips)"
			("LOCATION" "R1643")
		)
		("@t6g_mb_lib.t6g(sch_1):page188_i3@pure_quanta.q_res(chips)"
			("LOCATION" "R1645")
		)
		("@t6g_mb_lib.t6g(sch_1):page188_i30@pure_quanta.q_res(chips)"
			("LOCATION" "R1809")
		)
		("@t6g_mb_lib.t6g(sch_1):page188_i33@pure_quanta.q_res(chips)"
			("LOCATION" "R1810")
		)
		("@t6g_mb_lib.t6g(sch_1):page212_i121@pure_quanta.q_res(chips)"
			("LOCATION" "R434")
		)
		("@t6g_mb_lib.t6g(sch_1):page212_i138@pure_quanta.q_res(chips)"
			("LOCATION" "R435")
		)
		("@t6g_mb_lib.t6g(sch_1):page212_i137@pure_quanta.q_res(chips)"
			("LOCATION" "R436")
		)
		("@t6g_mb_lib.t6g(sch_1):page212_i136@pure_quanta.q_res(chips)"
			("LOCATION" "R437")
		)
		("@t6g_mb_lib.t6g(sch_1):page212_i135@pure_quanta.q_res(chips)"
			("LOCATION" "R441")
		)
		("@t6g_mb_lib.t6g(sch_1):page212_i133@pure_quanta.q_res(chips)"
			("LOCATION" "R442")
		)
		("@t6g_mb_lib.t6g(sch_1):page212_i134@pure_quanta.q_res(chips)"
			("LOCATION" "R443")
		)
		("@t6g_mb_lib.t6g(sch_1):page212_i132@pure_quanta.q_res(chips)"
			("LOCATION" "R444")
		)
		("@t6g_mb_lib.t6g(sch_1):page212_i130@pure_quanta.q_res(chips)"
			("LOCATION" "R447")
		)
		("@t6g_mb_lib.t6g(sch_1):page212_i131@pure_quanta.q_res(chips)"
			("LOCATION" "R459")
		)
		("@t6g_mb_lib.t6g(sch_1):page212_i129@pure_quanta.q_res(chips)"
			("LOCATION" "R461")
		)
		("@t6g_mb_lib.t6g(sch_1):page212_i128@pure_quanta.q_res(chips)"
			("LOCATION" "R462")
		)
		("@t6g_mb_lib.t6g(sch_1):page212_i127@pure_quanta.q_res(chips)"
			("LOCATION" "R468")
		)
		("@t6g_mb_lib.t6g(sch_1):page212_i125@pure_quanta.q_res(chips)"
			("LOCATION" "R469")
		)
		("@t6g_mb_lib.t6g(sch_1):page212_i126@pure_quanta.q_res(chips)"
			("LOCATION" "R472")
		)
		("@t6g_mb_lib.t6g(sch_1):page212_i123@pure_quanta.q_res(chips)"
			("LOCATION" "R473")
		)
		("@t6g_mb_lib.t6g(sch_1):page212_i124@pure_quanta.q_res(chips)"
			("LOCATION" "R474")
		)
		("@t6g_mb_lib.t6g(sch_1):page212_i122@pure_quanta.q_res(chips)"
			("LOCATION" "R476")
		)
		("@t6g_mb_lib.t6g(sch_1):page238_i152@pure_quanta.q_res(chips)"
			("LOCATION" "R446")
		)
		("@t6g_mb_lib.t6g(sch_1):page238_i147@pure_quanta.q_res(chips)"
			("LOCATION" "R1465")
		)
		("@t6g_mb_lib.t6g(sch_1):page238_i148@pure_quanta.q_res(chips)"
			("LOCATION" "R1466")
		)
		("@t6g_mb_lib.t6g(sch_1):page238_i113@pure_quanta.q_res(chips)"
			("LOCATION" "R1467")
		)
		("@t6g_mb_lib.t6g(sch_1):page238_i118@pure_quanta.q_res(chips)"
			("LOCATION" "R1547")
		)
		("@t6g_mb_lib.t6g(sch_1):page238_i110@pure_quanta.q_res(chips)"
			("LOCATION" "R1551")
		)
		("@t6g_mb_lib.t6g(sch_1):page238_i120@pure_quanta.q_res(chips)"
			("LOCATION" "R1556")
		)
		("@t6g_mb_lib.t6g(sch_1):page238_i119@pure_quanta.q_res(chips)"
			("LOCATION" "R1606")
		)
		("@t6g_mb_lib.t6g(sch_1):page238_i121@pure_quanta.q_res(chips)"
			("LOCATION" "R2317")
		)
		("@t6g_mb_lib.t6g(sch_1):page238_i108@pure_quanta.\\10m25daf484c7g\\(chips)"
			("LOCATION" "U3")
		)
		("@t6g_mb_lib.t6g(sch_1):page179_i281@pure_quanta.q_res(chips)"
			("LOCATION" "R453")
		)
		("@t6g_mb_lib.t6g(sch_1):page179_i265@pure_quanta.q_res(chips)"
			("LOCATION" "R696")
		)
		("@t6g_mb_lib.t6g(sch_1):page179_i292@pure_quanta.q_res(chips)"
			("LOCATION" "R697")
		)
		("@t6g_mb_lib.t6g(sch_1):page179_i283@pure_quanta.q_res(chips)"
			("LOCATION" "R1577")
		)
		("@t6g_mb_lib.t6g(sch_1):page179_i279@pure_quanta.q_res(chips)"
			("LOCATION" "R1578")
		)
		("@t6g_mb_lib.t6g(sch_1):page179_i286@pure_quanta.q_res(chips)"
			("LOCATION" "R1579")
		)
		("@t6g_mb_lib.t6g(sch_1):page179_i284@pure_quanta.q_res(chips)"
			("LOCATION" "R1585")
		)
		("@t6g_mb_lib.t6g(sch_1):page179_i256@pure_quanta.q_res(chips)"
			("LOCATION" "R1586")
		)
		("@t6g_mb_lib.t6g(sch_1):page179_i247@pure_quanta.q_res(chips)"
			("LOCATION" "R1588")
		)
		("@t6g_mb_lib.t6g(sch_1):page179_i248@pure_quanta.q_res(chips)"
			("LOCATION" "R1589")
		)
		("@t6g_mb_lib.t6g(sch_1):page179_i242@pure_quanta.q_res(chips)"
			("LOCATION" "R1590")
		)
		("@t6g_mb_lib.t6g(sch_1):page179_i239@pure_quanta.q_res(chips)"
			("LOCATION" "R1591")
		)
		("@t6g_mb_lib.t6g(sch_1):page179_i259@pure_quanta.q_res(chips)"
			("LOCATION" "R1675")
		)
		("@t6g_mb_lib.t6g(sch_1):page179_i260@pure_quanta.q_res(chips)"
			("LOCATION" "R1676")
		)
		("@t6g_mb_lib.t6g(sch_1):page179_i297@pure_quanta.q_res(chips)"
			("LOCATION" "R1736")
		)
		("@t6g_mb_lib.t6g(sch_1):page179_i224@pure_quanta.emmitsburg_rev0p9(chips)"
			("LOCATION" "U8")
		)
		("@t6g_mb_lib.t6g(sch_1):page254_i6@pure_quanta.q_res(chips)"
			("LOCATION" "R500")
		)
		("@t6g_mb_lib.t6g(sch_1):page254_i5@pure_quanta.q_res(chips)"
			("LOCATION" "R501")
		)
		("@t6g_mb_lib.t6g(sch_1):page254_i15@pure_quanta.q_res(chips)"
			("LOCATION" "R917")
		)
		("@t6g_mb_lib.t6g(sch_1):page254_i7@pure_quanta.q_res(chips)"
			("LOCATION" "R1295")
		)
		("@t6g_mb_lib.t6g(sch_1):page254_i8@pure_quanta.q_res(chips)"
			("LOCATION" "R1296")
		)
		("@t6g_mb_lib.t6g(sch_1):page254_i13@pure_quanta.q_res(chips)"
			("LOCATION" "R1298")
		)
		("@t6g_mb_lib.t6g(sch_1):page254_i14@pure_quanta.q_res(chips)"
			("LOCATION" "R1299")
		)
		("@t6g_mb_lib.t6g(sch_1):page254_i16@pure_quanta.q_res(chips)"
			("LOCATION" "R1395")
		)
		("@t6g_mb_lib.t6g(sch_1):page254_i27@pure_quanta.q_res(chips)"
			("LOCATION" "R3871")
		)
		("@t6g_mb_lib.t6g(sch_1):page254_i29@pure_quanta.q_res(chips)"
			("LOCATION" "R3872")
		)
		("@t6g_mb_lib.t6g(sch_1):page101_i96@pure_quanta.q_res(chips)"
			("LOCATION" "R583")
		)
		("@t6g_mb_lib.t6g(sch_1):page101_i95@pure_quanta.q_res(chips)"
			("LOCATION" "R584")
		)
		("@t6g_mb_lib.t6g(sch_1):page101_i94@pure_quanta.q_res(chips)"
			("LOCATION" "R585")
		)
		("@t6g_mb_lib.t6g(sch_1):page101_i86@pure_quanta.q_res(chips)"
			("LOCATION" "R586")
		)
		("@t6g_mb_lib.t6g(sch_1):page101_i85@pure_quanta.q_res(chips)"
			("LOCATION" "R587")
		)
		("@t6g_mb_lib.t6g(sch_1):page101_i84@pure_quanta.q_res(chips)"
			("LOCATION" "R588")
		)
		("@t6g_mb_lib.t6g(sch_1):page101_i98@pure_quanta.q_res(chips)"
			("LOCATION" "R765")
		)
		("@t6g_mb_lib.t6g(sch_1):page101_i87@pure_quanta.q_res(chips)"
			("LOCATION" "R766")
		)
		("@t6g_mb_lib.t6g(sch_1):page101_i30@pure_quanta.q_res(chips)"
			("LOCATION" "R1659")
		)
		("@t6g_mb_lib.t6g(sch_1):page101_i29@pure_quanta.q_res(chips)"
			("LOCATION" "R1667")
		)
		("@t6g_mb_lib.t6g(sch_1):page101_i28@pure_quanta.q_res(chips)"
			("LOCATION" "R2788")
		)
		("@t6g_mb_lib.t6g(sch_1):page101_i27@pure_quanta.q_res(chips)"
			("LOCATION" "R2789")
		)
		("@t6g_mb_lib.t6g(sch_1):page101_i26@pure_quanta.q_res(chips)"
			("LOCATION" "R2790")
		)
		("@t6g_mb_lib.t6g(sch_1):page101_i20@pure_quanta.q_res(chips)"
			("LOCATION" "R2791")
		)
		("@t6g_mb_lib.t6g(sch_1):page101_i19@pure_quanta.q_res(chips)"
			("LOCATION" "R2792")
		)
		("@t6g_mb_lib.t6g(sch_1):page101_i18@pure_quanta.q_res(chips)"
			("LOCATION" "R2793")
		)
		("@t6g_mb_lib.t6g(sch_1):page101_i17@pure_quanta.q_res(chips)"
			("LOCATION" "R2794")
		)
		("@t6g_mb_lib.t6g(sch_1):page101_i16@pure_quanta.q_res(chips)"
			("LOCATION" "R2795")
		)
		("@t6g_mb_lib.t6g(sch_1):page101_i15@pure_quanta.q_res(chips)"
			("LOCATION" "R2796")
		)
		("@t6g_mb_lib.t6g(sch_1):page101_i105@pure_quanta.q_res(chips)"
			("LOCATION" "R2797")
		)
		("@t6g_mb_lib.t6g(sch_1):page101_i14@pure_quanta.q_res(chips)"
			("LOCATION" "R2798")
		)
		("@t6g_mb_lib.t6g(sch_1):page101_i13@pure_quanta.q_res(chips)"
			("LOCATION" "R2799")
		)
		("@t6g_mb_lib.t6g(sch_1):page101_i12@pure_quanta.q_res(chips)"
			("LOCATION" "R2800")
		)
		("@t6g_mb_lib.t6g(sch_1):page101_i106@pure_quanta.q_res(chips)"
			("LOCATION" "R2801")
		)
		("@t6g_mb_lib.t6g(sch_1):page101_i76@pure_quanta.q_res(chips)"
			("LOCATION" "R2802")
		)
		("@t6g_mb_lib.t6g(sch_1):page101_i75@pure_quanta.q_res(chips)"
			("LOCATION" "R2803")
		)
		("@t6g_mb_lib.t6g(sch_1):page101_i74@pure_quanta.q_res(chips)"
			("LOCATION" "R2804")
		)
		("@t6g_mb_lib.t6g(sch_1):page101_i73@pure_quanta.q_res(chips)"
			("LOCATION" "R2805")
		)
		("@t6g_mb_lib.t6g(sch_1):page101_i72@pure_quanta.q_res(chips)"
			("LOCATION" "R2806")
		)
		("@t6g_mb_lib.t6g(sch_1):page101_i71@pure_quanta.q_res(chips)"
			("LOCATION" "R2807")
		)
		("@t6g_mb_lib.t6g(sch_1):page101_i66@pure_quanta.q_res(chips)"
			("LOCATION" "R2808")
		)
		("@t6g_mb_lib.t6g(sch_1):page101_i65@pure_quanta.q_res(chips)"
			("LOCATION" "R2809")
		)
		("@t6g_mb_lib.t6g(sch_1):page101_i64@pure_quanta.q_res(chips)"
			("LOCATION" "R2810")
		)
		("@t6g_mb_lib.t6g(sch_1):page101_i63@pure_quanta.q_res(chips)"
			("LOCATION" "R2811")
		)
		("@t6g_mb_lib.t6g(sch_1):page101_i62@pure_quanta.q_res(chips)"
			("LOCATION" "R2812")
		)
		("@t6g_mb_lib.t6g(sch_1):page101_i61@pure_quanta.q_res(chips)"
			("LOCATION" "R2813")
		)
		("@t6g_mb_lib.t6g(sch_1):page101_i104@pure_quanta.q_res(chips)"
			("LOCATION" "R2814")
		)
		("@t6g_mb_lib.t6g(sch_1):page101_i60@pure_quanta.q_res(chips)"
			("LOCATION" "R2815")
		)
		("@t6g_mb_lib.t6g(sch_1):page101_i59@pure_quanta.q_res(chips)"
			("LOCATION" "R2816")
		)
		("@t6g_mb_lib.t6g(sch_1):page101_i33@pure_quanta.q_res(chips)"
			("LOCATION" "R2817")
		)
		("@t6g_mb_lib.t6g(sch_1):page189_i206@pure_quanta.q_res(chips)"
			("LOCATION" "R607")
		)
		("@t6g_mb_lib.t6g(sch_1):page189_i207@pure_quanta.q_res(chips)"
			("LOCATION" "R608")
		)
		("@t6g_mb_lib.t6g(sch_1):page189_i210@pure_quanta.q_res(chips)"
			("LOCATION" "R609")
		)
		("@t6g_mb_lib.t6g(sch_1):page189_i211@pure_quanta.q_res(chips)"
			("LOCATION" "R610")
		)
		("@t6g_mb_lib.t6g(sch_1):page189_i214@pure_quanta.q_res(chips)"
			("LOCATION" "R611")
		)
		("@t6g_mb_lib.t6g(sch_1):page189_i215@pure_quanta.q_res(chips)"
			("LOCATION" "R612")
		)
		("@t6g_mb_lib.t6g(sch_1):page189_i189@pure_quanta.q_res(chips)"
			("LOCATION" "R613")
		)
		("@t6g_mb_lib.t6g(sch_1):page189_i190@pure_quanta.q_res(chips)"
			("LOCATION" "R614")
		)
		("@t6g_mb_lib.t6g(sch_1):page189_i195@pure_quanta.q_res(chips)"
			("LOCATION" "R615")
		)
		("@t6g_mb_lib.t6g(sch_1):page189_i196@pure_quanta.q_res(chips)"
			("LOCATION" "R616")
		)
		("@t6g_mb_lib.t6g(sch_1):page189_i200@pure_quanta.q_res(chips)"
			("LOCATION" "R617")
		)
		("@t6g_mb_lib.t6g(sch_1):page189_i201@pure_quanta.q_res(chips)"
			("LOCATION" "R618")
		)
		("@t6g_mb_lib.t6g(sch_1):page189_i174@pure_quanta.q_res(chips)"
			("LOCATION" "R619")
		)
		("@t6g_mb_lib.t6g(sch_1):page189_i175@pure_quanta.q_res(chips)"
			("LOCATION" "R620")
		)
		("@t6g_mb_lib.t6g(sch_1):page189_i180@pure_quanta.q_res(chips)"
			("LOCATION" "R621")
		)
		("@t6g_mb_lib.t6g(sch_1):page189_i181@pure_quanta.q_res(chips)"
			("LOCATION" "R622")
		)
		("@t6g_mb_lib.t6g(sch_1):page189_i184@pure_quanta.q_res(chips)"
			("LOCATION" "R623")
		)
		("@t6g_mb_lib.t6g(sch_1):page189_i185@pure_quanta.q_res(chips)"
			("LOCATION" "R624")
		)
		("@t6g_mb_lib.t6g(sch_1):page193_i26@pure_quanta.q_res(chips)"
			("LOCATION" "R698")
		)
		("@t6g_mb_lib.t6g(sch_1):page193_i18@pure_quanta.q_res(chips)"
			("LOCATION" "R1300")
		)
		("@t6g_mb_lib.t6g(sch_1):page193_i12@pure_quanta.q_res(chips)"
			("LOCATION" "R1306")
		)
		("@t6g_mb_lib.t6g(sch_1):page193_i11@pure_quanta.q_res(chips)"
			("LOCATION" "R1307")
		)
		("@t6g_mb_lib.t6g(sch_1):page193_i16@pure_quanta.q_res(chips)"
			("LOCATION" "R1309")
		)
		("@t6g_mb_lib.t6g(sch_1):page193_i15@pure_quanta.q_res(chips)"
			("LOCATION" "R1310")
		)
		("@t6g_mb_lib.t6g(sch_1):page193_i17@pure_quanta.q_res(chips)"
			("LOCATION" "R1313")
		)
		("@t6g_mb_lib.t6g(sch_1):page193_i19@pure_quanta.q_res(chips)"
			("LOCATION" "R1455")
		)
		("@t6g_mb_lib.t6g(sch_1):page193_i25@pure_quanta.q_res(chips)"
			("LOCATION" "R1456")
		)
		("@t6g_mb_lib.t6g(sch_1):page193_i27@pure_quanta.q_res(chips)"
			("LOCATION" "R1817")
		)
		("@t6g_mb_lib.t6g(sch_1):page246_i53@pure_quanta.q_res(chips)"
			("LOCATION" "R986")
		)
		("@t6g_mb_lib.t6g(sch_1):page246_i54@pure_quanta.q_res(chips)"
			("LOCATION" "R987")
		)
		("@t6g_mb_lib.t6g(sch_1):page246_i55@pure_quanta.q_res(chips)"
			("LOCATION" "R988")
		)
		("@t6g_mb_lib.t6g(sch_1):page246_i69@pure_quanta.q_res(chips)"
			("LOCATION" "R1101")
		)
		("@t6g_mb_lib.t6g(sch_1):page246_i9@pure_quanta.q_res(chips)"
			("LOCATION" "R1751")
		)
		("@t6g_mb_lib.t6g(sch_1):page246_i71@pure_quanta.q_res(chips)"
			("LOCATION" "R1919")
		)
		("@t6g_mb_lib.t6g(sch_1):page246_i48@pure_quanta.q_res(chips)"
			("LOCATION" "R2072")
		)
		("@t6g_mb_lib.t6g(sch_1):page246_i49@pure_quanta.q_res(chips)"
			("LOCATION" "R2073")
		)
		("@t6g_mb_lib.t6g(sch_1):page246_i50@pure_quanta.q_res(chips)"
			("LOCATION" "R2074")
		)
		("@t6g_mb_lib.t6g(sch_1):page246_i51@pure_quanta.q_res(chips)"
			("LOCATION" "R2083")
		)
		("@t6g_mb_lib.t6g(sch_1):page246_i52@pure_quanta.q_res(chips)"
			("LOCATION" "R2084")
		)
		("@t6g_mb_lib.t6g(sch_1):page246_i65@pure_quanta.q_res(chips)"
			("LOCATION" "R2087")
		)
		("@t6g_mb_lib.t6g(sch_1):page246_i66@pure_quanta.q_res(chips)"
			("LOCATION" "R2088")
		)
		("@t6g_mb_lib.t6g(sch_1):page246_i67@pure_quanta.q_res(chips)"
			("LOCATION" "R2093")
		)
		("@t6g_mb_lib.t6g(sch_1):page246_i68@pure_quanta.q_res(chips)"
			("LOCATION" "R2094")
		)
		("@t6g_mb_lib.t6g(sch_1):page246_i70@pure_quanta.q_res(chips)"
			("LOCATION" "R2095")
		)
		("@t6g_mb_lib.t6g(sch_1):page246_i72@pure_quanta.q_res(chips)"
			("LOCATION" "R2096")
		)
		("@t6g_mb_lib.t6g(sch_1):page246_i73@pure_quanta.q_res(chips)"
			("LOCATION" "R2128")
		)
		("@t6g_mb_lib.t6g(sch_1):page246_i10@pure_quanta.q_res(chips)"
			("LOCATION" "R2129")
		)
		("@t6g_mb_lib.t6g(sch_1):page246_i11@pure_quanta.q_res(chips)"
			("LOCATION" "R2132")
		)
		("@t6g_mb_lib.t6g(sch_1):page246_i12@pure_quanta.q_res(chips)"
			("LOCATION" "R2135")
		)
		("@t6g_mb_lib.t6g(sch_1):page246_i32@pure_quanta.q_res(chips)"
			("LOCATION" "R2138")
		)
		("@t6g_mb_lib.t6g(sch_1):page246_i36@pure_quanta.q_res(chips)"
			("LOCATION" "R2139")
		)
		("@t6g_mb_lib.t6g(sch_1):page246_i37@pure_quanta.q_res(chips)"
			("LOCATION" "R2142")
		)
		("@t6g_mb_lib.t6g(sch_1):page246_i13@pure_quanta.q_res(chips)"
			("LOCATION" "R2144")
		)
		("@t6g_mb_lib.t6g(sch_1):page246_i14@pure_quanta.q_res(chips)"
			("LOCATION" "R2145")
		)
		("@t6g_mb_lib.t6g(sch_1):page246_i15@pure_quanta.q_res(chips)"
			("LOCATION" "R2147")
		)
		("@t6g_mb_lib.t6g(sch_1):page246_i16@pure_quanta.q_res(chips)"
			("LOCATION" "R2157")
		)
		("@t6g_mb_lib.t6g(sch_1):page246_i30@pure_quanta.q_res(chips)"
			("LOCATION" "R2160")
		)
		("@t6g_mb_lib.t6g(sch_1):page246_i31@pure_quanta.q_res(chips)"
			("LOCATION" "R2174")
		)
		("@t6g_mb_lib.t6g(sch_1):page190_i43@pure_quanta.q_res(chips)"
			("LOCATION" "R1220")
		)
		("@t6g_mb_lib.t6g(sch_1):page190_i44@pure_quanta.q_res(chips)"
			("LOCATION" "R1221")
		)
		("@t6g_mb_lib.t6g(sch_1):page190_i39@pure_quanta.q_res(chips)"
			("LOCATION" "R1222")
		)
		("@t6g_mb_lib.t6g(sch_1):page190_i35@pure_quanta.q_res(chips)"
			("LOCATION" "R1646")
		)
		("@t6g_mb_lib.t6g(sch_1):page190_i37@pure_quanta.q_res(chips)"
			("LOCATION" "R1653")
		)
		("@t6g_mb_lib.t6g(sch_1):page190_i40@pure_quanta.q_res(chips)"
			("LOCATION" "R1654")
		)
		("@t6g_mb_lib.t6g(sch_1):page190_i19@pure_quanta.q_res(chips)"
			("LOCATION" "R1655")
		)
		("@t6g_mb_lib.t6g(sch_1):page190_i21@pure_quanta.q_res(chips)"
			("LOCATION" "R1665")
		)
		("@t6g_mb_lib.t6g(sch_1):page190_i24@pure_quanta.q_res(chips)"
			("LOCATION" "R1666")
		)
		("@t6g_mb_lib.t6g(sch_1):page190_i25@pure_quanta.q_res(chips)"
			("LOCATION" "R1672")
		)
		("@t6g_mb_lib.t6g(sch_1):page190_i29@pure_quanta.q_res(chips)"
			("LOCATION" "R1673")
		)
		("@t6g_mb_lib.t6g(sch_1):page190_i30@pure_quanta.q_res(chips)"
			("LOCATION" "R1674")
		)
		("@t6g_mb_lib.t6g(sch_1):page190_i2@pure_quanta.q_res(chips)"
			("LOCATION" "R1677")
		)
		("@t6g_mb_lib.t6g(sch_1):page190_i4@pure_quanta.q_res(chips)"
			("LOCATION" "R1678")
		)
		("@t6g_mb_lib.t6g(sch_1):page190_i9@pure_quanta.q_res(chips)"
			("LOCATION" "R1679")
		)
		("@t6g_mb_lib.t6g(sch_1):page190_i12@pure_quanta.q_res(chips)"
			("LOCATION" "R1680")
		)
		("@t6g_mb_lib.t6g(sch_1):page190_i14@pure_quanta.q_res(chips)"
			("LOCATION" "R1682")
		)
		("@t6g_mb_lib.t6g(sch_1):page190_i17@pure_quanta.q_res(chips)"
			("LOCATION" "R1683")
		)
		("@t6g_mb_lib.t6g(sch_1):page88_i43@pure_quanta.q_res(chips)"
			("LOCATION" "R1241")
		)
		("@t6g_mb_lib.t6g(sch_1):page88_i45@pure_quanta.q_res(chips)"
			("LOCATION" "R1242")
		)
		("@t6g_mb_lib.t6g(sch_1):page88_i50@pure_quanta.q_res(chips)"
			("LOCATION" "R1243")
		)
		("@t6g_mb_lib.t6g(sch_1):page88_i47@pure_quanta.q_res(chips)"
			("LOCATION" "R1244")
		)
		("@t6g_mb_lib.t6g(sch_1):page88_i44@pure_quanta.q_res(chips)"
			("LOCATION" "R2466")
		)
		("@t6g_mb_lib.t6g(sch_1):page88_i53@pure_quanta.q_res(chips)"
			("LOCATION" "R2467")
		)
		("@t6g_mb_lib.t6g(sch_1):page18_i164@pure_quanta.q_res(chips)"
			("LOCATION" "R1503")
		)
		("@t6g_mb_lib.t6g(sch_1):page18_i176@pure_quanta.socket4677_azifs035p001c01(chips)"
			("LOCATION" "U2")
		)
		("@t6g_mb_lib.t6g(sch_1):page177_i131@pure_quanta.q_res(chips)"
			("LOCATION" "R1530")
		)
		("@t6g_mb_lib.t6g(sch_1):page177_i118@pure_quanta.emmitsburg_rev0p9(chips)"
			("LOCATION" "U8")
		)
		("@t6g_mb_lib.t6g(sch_1):page240_i323@pure_quanta.q_res(chips)"
			("LOCATION" "R1681")
		)
		("@t6g_mb_lib.t6g(sch_1):page240_i350@pure_quanta.q_res(chips)"
			("LOCATION" "R3715")
		)
		("@t6g_mb_lib.t6g(sch_1):page240_i264@pure_quanta.\\10m25daf484c7g\\(chips)"
			("LOCATION" "U3")
		)
		("@t6g_mb_lib.t6g(sch_1):page100_i18@pure_quanta.q_res_4p_12(chips)"
			("LOCATION" "R1837")
		)
		("@t6g_mb_lib.t6g(sch_1):page100_i16@pure_quanta.q_res_4p_12(chips)"
			("LOCATION" "R1838")
		)
		("@t6g_mb_lib.t6g(sch_1):page210_i9@pure_quanta.q_res(chips)"
			("LOCATION" "R1948")
		)
		("@t6g_mb_lib.t6g(sch_1):page210_i10@pure_quanta.q_res(chips)"
			("LOCATION" "R1949")
		)
		("@t6g_mb_lib.t6g(sch_1):page210_i12@pure_quanta.q_res(chips)"
			("LOCATION" "R1950")
		)
		("@t6g_mb_lib.t6g(sch_1):page210_i21@pure_quanta.q_res(chips)"
			("LOCATION" "R1951")
		)
		("@t6g_mb_lib.t6g(sch_1):page210_i22@pure_quanta.q_res(chips)"
			("LOCATION" "R1952")
		)
		("@t6g_mb_lib.t6g(sch_1):page210_i24@pure_quanta.q_res(chips)"
			("LOCATION" "R1953")
		)
		("@t6g_mb_lib.t6g(sch_1):page210_i23@pure_quanta.q_res(chips)"
			("LOCATION" "R1954")
		)
		("@t6g_mb_lib.t6g(sch_1):page210_i34@pure_quanta.q_res(chips)"
			("LOCATION" "R1961")
		)
		("@t6g_mb_lib.t6g(sch_1):page210_i36@pure_quanta.q_res(chips)"
			("LOCATION" "R1962")
		)
		("@t6g_mb_lib.t6g(sch_1):page210_i35@pure_quanta.q_res(chips)"
			("LOCATION" "R1963")
		)
		("@t6g_mb_lib.t6g(sch_1):page210_i42@pure_quanta.q_res(chips)"
			("LOCATION" "R1964")
		)
		("@t6g_mb_lib.t6g(sch_1):page210_i41@pure_quanta.q_res(chips)"
			("LOCATION" "R1965")
		)
		("@t6g_mb_lib.t6g(sch_1):page210_i43@pure_quanta.q_res(chips)"
			("LOCATION" "R1966")
		)
		("@t6g_mb_lib.t6g(sch_1):page210_i44@pure_quanta.q_res(chips)"
			("LOCATION" "R1967")
		)
		("@t6g_mb_lib.t6g(sch_1):page210_i11@pure_quanta.q_res(chips)"
			("LOCATION" "R1970")
		)
		("@t6g_mb_lib.t6g(sch_1):page210_i33@pure_quanta.q_res(chips)"
			("LOCATION" "R1971")
		)
		("@t6g_mb_lib.t6g(sch_1):page183_i73@pure_quanta.q_res(chips)"
			("LOCATION" "R2468")
		)
		("@t6g_mb_lib.t6g(sch_1):page183_i74@pure_quanta.q_res(chips)"
			("LOCATION" "R2470")
		)
		("@t6g_mb_lib.t6g(sch_1):page183_i63@pure_quanta.emmitsburg_rev0p9(chips)"
			("LOCATION" "U8")
		)
		("@t6g_mb_lib.t6g(sch_1):page184_i21@pure_quanta.q_res(chips)"
			("LOCATION" "R2647")
		)
		("@t6g_mb_lib.t6g(sch_1):page184_i24@pure_quanta.emmitsburg_rev0p9(chips)"
			("LOCATION" "U8")
		)
		("@t6g_mb_lib.t6g(sch_1):page184_i25@pure_quanta.emmitsburg_rev0p9(chips)"
			("LOCATION" "U8")
		)
		("@t6g_mb_lib.t6g(sch_1):page209_i75@pure_quanta.q_res(chips)"
			("LOCATION" "R3298")
		)
		("@t6g_mb_lib.t6g(sch_1):page209_i76@pure_quanta.q_res(chips)"
			("LOCATION" "R3299")
		)
		("@t6g_mb_lib.t6g(sch_1):page209_i77@pure_quanta.q_res(chips)"
			("LOCATION" "R3300")
		)
		("@t6g_mb_lib.t6g(sch_1):page209_i78@pure_quanta.q_res(chips)"
			("LOCATION" "R3301")
		)
		("@t6g_mb_lib.t6g(sch_1):page209_i80@pure_quanta.q_res(chips)"
			("LOCATION" "R3302")
		)
		("@t6g_mb_lib.t6g(sch_1):page209_i79@pure_quanta.q_res(chips)"
			("LOCATION" "R3303")
		)
		("@t6g_mb_lib.t6g(sch_1):page209_i83@pure_quanta.q_res(chips)"
			("LOCATION" "R3304")
		)
		("@t6g_mb_lib.t6g(sch_1):page209_i84@pure_quanta.q_res(chips)"
			("LOCATION" "R3307")
		)
		("@t6g_mb_lib.t6g(sch_1):page209_i69@pure_quanta.q_res(chips)"
			("LOCATION" "R3308")
		)
		("@t6g_mb_lib.t6g(sch_1):page209_i70@pure_quanta.q_res(chips)"
			("LOCATION" "R3309")
		)
		("@t6g_mb_lib.t6g(sch_1):page209_i71@pure_quanta.q_res(chips)"
			("LOCATION" "R3310")
		)
		("@t6g_mb_lib.t6g(sch_1):page209_i72@pure_quanta.q_res(chips)"
			("LOCATION" "R3311")
		)
		("@t6g_mb_lib.t6g(sch_1):page209_i74@pure_quanta.q_res(chips)"
			("LOCATION" "R3312")
		)
		("@t6g_mb_lib.t6g(sch_1):page209_i73@pure_quanta.q_res(chips)"
			("LOCATION" "R3354")
		)
		("@t6g_mb_lib.t6g(sch_1):page209_i81@pure_quanta.q_res(chips)"
			("LOCATION" "R3355")
		)
		("@t6g_mb_lib.t6g(sch_1):page209_i82@pure_quanta.q_res(chips)"
			("LOCATION" "R3356")
		)
		("@t6g_mb_lib.t6g(sch_1):page49_i292@pure_quanta.socket4677_azifs035p001c01(chips)"
			("LOCATION" "U1")
		)
		("@t6g_mb_lib.t6g(sch_1):page51_i5@pure_quanta.socket4677_azifs035p001c01(chips)"
			("LOCATION" "U1")
		)
		("@t6g_mb_lib.t6g(sch_1):page52_i7@pure_quanta.socket4677_azifs035p001c01(chips)"
			("LOCATION" "U1")
		)
		("@t6g_mb_lib.t6g(sch_1):page53_i242@pure_quanta.socket4677_azifs035p001c01(chips)"
			("LOCATION" "U1")
		)
		("@t6g_mb_lib.t6g(sch_1):page54_i660@pure_quanta.socket4677_azifs035p001c01(chips)"
			("LOCATION" "U1")
		)
		("@t6g_mb_lib.t6g(sch_1):page55_i654@pure_quanta.socket4677_azifs035p001c01(chips)"
			("LOCATION" "U1")
		)
		("@t6g_mb_lib.t6g(sch_1):page56_i713@pure_quanta.socket4677_azifs035p001c01(chips)"
			("LOCATION" "U1")
		)
		("@t6g_mb_lib.t6g(sch_1):page57_i616@pure_quanta.socket4677_azifs035p001c01(chips)"
			("LOCATION" "U1")
		)
		("@t6g_mb_lib.t6g(sch_1):page58_i944@pure_quanta.socket4677_azifs035p001c01(chips)"
			("LOCATION" "U1")
		)
		("@t6g_mb_lib.t6g(sch_1):page59_i631@pure_quanta.socket4677_azifs035p001c01(chips)"
			("LOCATION" "U1")
		)
		("@t6g_mb_lib.t6g(sch_1):page60_i637@pure_quanta.socket4677_azifs035p001c01(chips)"
			("LOCATION" "U1")
		)
		("@t6g_mb_lib.t6g(sch_1):page61_i637@pure_quanta.socket4677_azifs035p001c01(chips)"
			("LOCATION" "U1")
		)
		("@t6g_mb_lib.t6g(sch_1):page62_i107@pure_quanta.socket4677_azifs035p001c01(chips)"
			("LOCATION" "U1")
		)
		("@t6g_mb_lib.t6g(sch_1):page62_i108@pure_quanta.socket4677_azifs035p001c01(chips)"
			("LOCATION" "U1")
		)
		("@t6g_mb_lib.t6g(sch_1):page63_i409@pure_quanta.socket4677_azifs035p001c01(chips)"
			("LOCATION" "U1")
		)
		("@t6g_mb_lib.t6g(sch_1):page63_i410@pure_quanta.socket4677_azifs035p001c01(chips)"
			("LOCATION" "U1")
		)
		("@t6g_mb_lib.t6g(sch_1):page64_i69@pure_quanta.socket4677_azifs035p001c01(chips)"
			("LOCATION" "U1")
		)
		("@t6g_mb_lib.t6g(sch_1):page65_i69@pure_quanta.socket4677_azifs035p001c01(chips)"
			("LOCATION" "U1")
		)
		("@t6g_mb_lib.t6g(sch_1):page66_i101@pure_quanta.socket4677_azifs035p001c01(chips)"
			("LOCATION" "U1")
		)
		("@t6g_mb_lib.t6g(sch_1):page67_i101@pure_quanta.socket4677_azifs035p001c01(chips)"
			("LOCATION" "U1")
		)
		("@t6g_mb_lib.t6g(sch_1):page68_i355@pure_quanta.socket4677_azifs035p001c01(chips)"
			("LOCATION" "U1")
		)
		("@t6g_mb_lib.t6g(sch_1):page69_i102@pure_quanta.socket4677_azifs035p001c01(chips)"
			("LOCATION" "U1")
		)
		("@t6g_mb_lib.t6g(sch_1):page70_i19@pure_quanta.socket4677_azifs035p001c01(chips)"
			("LOCATION" "U1")
		)
		("@t6g_mb_lib.t6g(sch_1):page70_i20@pure_quanta.socket4677_azifs035p001c01(chips)"
			("LOCATION" "U1")
		)
		("@t6g_mb_lib.t6g(sch_1):page72_i28@pure_quanta.socket4677_azifs035p001c01(chips)"
			("LOCATION" "U1")
		)
		("@t6g_mb_lib.t6g(sch_1):page72_i29@pure_quanta.socket4677_azifs035p001c01(chips)"
			("LOCATION" "U1")
		)
		("@t6g_mb_lib.t6g(sch_1):page72_i30@pure_quanta.socket4677_azifs035p001c01(chips)"
			("LOCATION" "U1")
		)
		("@t6g_mb_lib.t6g(sch_1):page73_i15@pure_quanta.socket4677_azifs035p001c01(chips)"
			("LOCATION" "U1")
		)
		("@t6g_mb_lib.t6g(sch_1):page73_i18@pure_quanta.socket4677_azifs035p001c01(chips)"
			("LOCATION" "U1")
		)
		("@t6g_mb_lib.t6g(sch_1):page73_i19@pure_quanta.socket4677_azifs035p001c01(chips)"
			("LOCATION" "U1")
		)
		("@t6g_mb_lib.t6g(sch_1):page74_i35@pure_quanta.socket4677_azifs035p001c01(chips)"
			("LOCATION" "U1")
		)
		("@t6g_mb_lib.t6g(sch_1):page74_i36@pure_quanta.socket4677_azifs035p001c01(chips)"
			("LOCATION" "U1")
		)
		("@t6g_mb_lib.t6g(sch_1):page74_i37@pure_quanta.socket4677_azifs035p001c01(chips)"
			("LOCATION" "U1")
		)
		("@t6g_mb_lib.t6g(sch_1):page75_i7@pure_quanta.socket4677_azifs035p001c01(chips)"
			("LOCATION" "U1")
		)
		("@t6g_mb_lib.t6g(sch_1):page75_i8@pure_quanta.socket4677_azifs035p001c01(chips)"
			("LOCATION" "U1")
		)
		("@t6g_mb_lib.t6g(sch_1):page76_i6@pure_quanta.socket4677_azifs035p001c01(chips)"
			("LOCATION" "U1")
		)
		("@t6g_mb_lib.t6g(sch_1):page76_i7@pure_quanta.socket4677_azifs035p001c01(chips)"
			("LOCATION" "U1")
		)
		("@t6g_mb_lib.t6g(sch_1):page20_i5@pure_quanta.socket4677_azifs035p001c01(chips)"
			("LOCATION" "U2")
		)
		("@t6g_mb_lib.t6g(sch_1):page21_i4@pure_quanta.socket4677_azifs035p001c01(chips)"
			("LOCATION" "U2")
		)
		("@t6g_mb_lib.t6g(sch_1):page22_i269@pure_quanta.socket4677_azifs035p001c01(chips)"
			("LOCATION" "U2")
		)
		("@t6g_mb_lib.t6g(sch_1):page23_i661@pure_quanta.socket4677_azifs035p001c01(chips)"
			("LOCATION" "U2")
		)
		("@t6g_mb_lib.t6g(sch_1):page24_i654@pure_quanta.socket4677_azifs035p001c01(chips)"
			("LOCATION" "U2")
		)
		("@t6g_mb_lib.t6g(sch_1):page25_i713@pure_quanta.socket4677_azifs035p001c01(chips)"
			("LOCATION" "U2")
		)
		("@t6g_mb_lib.t6g(sch_1):page26_i616@pure_quanta.socket4677_azifs035p001c01(chips)"
			("LOCATION" "U2")
		)
		("@t6g_mb_lib.t6g(sch_1):page27_i944@pure_quanta.socket4677_azifs035p001c01(chips)"
			("LOCATION" "U2")
		)
		("@t6g_mb_lib.t6g(sch_1):page28_i631@pure_quanta.socket4677_azifs035p001c01(chips)"
			("LOCATION" "U2")
		)
		("@t6g_mb_lib.t6g(sch_1):page29_i637@pure_quanta.socket4677_azifs035p001c01(chips)"
			("LOCATION" "U2")
		)
		("@t6g_mb_lib.t6g(sch_1):page30_i637@pure_quanta.socket4677_azifs035p001c01(chips)"
			("LOCATION" "U2")
		)
		("@t6g_mb_lib.t6g(sch_1):page31_i179@pure_quanta.socket4677_azifs035p001c01(chips)"
			("LOCATION" "U2")
		)
		("@t6g_mb_lib.t6g(sch_1):page31_i108@pure_quanta.socket4677_azifs035p001c01(chips)"
			("LOCATION" "U2")
		)
		("@t6g_mb_lib.t6g(sch_1):page32_i139@pure_quanta.socket4677_azifs035p001c01(chips)"
			("LOCATION" "U2")
		)
		("@t6g_mb_lib.t6g(sch_1):page32_i140@pure_quanta.socket4677_azifs035p001c01(chips)"
			("LOCATION" "U2")
		)
		("@t6g_mb_lib.t6g(sch_1):page33_i69@pure_quanta.socket4677_azifs035p001c01(chips)"
			("LOCATION" "U2")
		)
		("@t6g_mb_lib.t6g(sch_1):page34_i69@pure_quanta.socket4677_azifs035p001c01(chips)"
			("LOCATION" "U2")
		)
		("@t6g_mb_lib.t6g(sch_1):page35_i101@pure_quanta.socket4677_azifs035p001c01(chips)"
			("LOCATION" "U2")
		)
		("@t6g_mb_lib.t6g(sch_1):page36_i101@pure_quanta.socket4677_azifs035p001c01(chips)"
			("LOCATION" "U2")
		)
		("@t6g_mb_lib.t6g(sch_1):page37_i101@pure_quanta.socket4677_azifs035p001c01(chips)"
			("LOCATION" "U2")
		)
		("@t6g_mb_lib.t6g(sch_1):page38_i101@pure_quanta.socket4677_azifs035p001c01(chips)"
			("LOCATION" "U2")
		)
		("@t6g_mb_lib.t6g(sch_1):page39_i19@pure_quanta.socket4677_azifs035p001c01(chips)"
			("LOCATION" "U2")
		)
		("@t6g_mb_lib.t6g(sch_1):page39_i20@pure_quanta.socket4677_azifs035p001c01(chips)"
			("LOCATION" "U2")
		)
		("@t6g_mb_lib.t6g(sch_1):page41_i26@pure_quanta.socket4677_azifs035p001c01(chips)"
			("LOCATION" "U2")
		)
		("@t6g_mb_lib.t6g(sch_1):page41_i27@pure_quanta.socket4677_azifs035p001c01(chips)"
			("LOCATION" "U2")
		)
		("@t6g_mb_lib.t6g(sch_1):page41_i28@pure_quanta.socket4677_azifs035p001c01(chips)"
			("LOCATION" "U2")
		)
		("@t6g_mb_lib.t6g(sch_1):page42_i15@pure_quanta.socket4677_azifs035p001c01(chips)"
			("LOCATION" "U2")
		)
		("@t6g_mb_lib.t6g(sch_1):page42_i16@pure_quanta.socket4677_azifs035p001c01(chips)"
			("LOCATION" "U2")
		)
		("@t6g_mb_lib.t6g(sch_1):page42_i17@pure_quanta.socket4677_azifs035p001c01(chips)"
			("LOCATION" "U2")
		)
		("@t6g_mb_lib.t6g(sch_1):page43_i11@pure_quanta.socket4677_azifs035p001c01(chips)"
			("LOCATION" "U2")
		)
		("@t6g_mb_lib.t6g(sch_1):page43_i12@pure_quanta.socket4677_azifs035p001c01(chips)"
			("LOCATION" "U2")
		)
		("@t6g_mb_lib.t6g(sch_1):page43_i13@pure_quanta.socket4677_azifs035p001c01(chips)"
			("LOCATION" "U2")
		)
		("@t6g_mb_lib.t6g(sch_1):page44_i19@pure_quanta.socket4677_azifs035p001c01(chips)"
			("LOCATION" "U2")
		)
		("@t6g_mb_lib.t6g(sch_1):page44_i20@pure_quanta.socket4677_azifs035p001c01(chips)"
			("LOCATION" "U2")
		)
		("@t6g_mb_lib.t6g(sch_1):page45_i7@pure_quanta.socket4677_azifs035p001c01(chips)"
			("LOCATION" "U2")
		)
		("@t6g_mb_lib.t6g(sch_1):page45_i8@pure_quanta.socket4677_azifs035p001c01(chips)"
			("LOCATION" "U2")
		)
		("@t6g_mb_lib.t6g(sch_1):page185_i23@pure_quanta.emmitsburg_rev0p9(chips)"
			("LOCATION" "U8")
		)
	)
)
